G04 ================== begin FILE IDENTIFICATION RECORD ==================*
G04 Layout Name:  9054_F0T_PDB_BD_GPU_F_V04_1213_1550.brd*
G04 Film Name:    fab*
G04 File Format:  Gerber RS274X*
G04 File Origin:  Cadence Allegro 17.2-S081*
G04 Origin Date:  Wed Dec 28 10:19:02 2022*
G04 *
G04 Layer:  DRAWING FORMAT/TITLE_BLOCK_A*
G04 Layer:  MANUFACTURING/NCLEGEND-1-10*
G04 Layer:  BOARD GEOMETRY/DESIGN_OUTLINE*
G04 Layer:  BOARD GEOMETRY/CUTOUT*
G04 Layer:  PIN/SPECIAL_DRILL*
G04 Layer:  MANUFACTURING/NCDRILL_LEGEND*
G04 Layer:  MANUFACTURING/NCDRILL_FIGURE*
G04 Layer:  MANUFACTURING/PHOTOPLOT_OUTLINE*
G04 Layer:  MANUFACTURING/DIMENSION*
G04 Layer:  MANUFACTURING/DETAILS*
G04 Layer:  DRAWING FORMAT/TITLE_BLOCK*
G04 Layer:  DRAWING FORMAT/TITLE_DATA_FAB*
G04 Layer:  BOARD GEOMETRY/OUTLINE*
G04 *
G04 Offset:    (0.00 0.00)*
G04 Mirror:    No*
G04 Mode:      Positive*
G04 Rotation:  0*
G04 FullContactRelief:  No*
G04 UndefLineWidth:     6.00*
G04 ================== end FILE IDENTIFICATION RECORD ====================*
%FSLAX25Y25*MOIN*%
%IR0*IPPOS*OFA0.00000B0.00000*MIA0B0*SFA1.00000B1.00000*%
%AMMACRO18*
1,1,.006,.014497,-.035*
20,1,.006,.014497,-.035,-.014497,-.035,0.0*
1,1,.006,-.014497,-.035*
20,1,.006,-.014497,-.035,-.035,-.014497,0.0*
1,1,.006,-.035,-.014497*
20,1,.006,-.035,-.014497,-.035,.014497,0.0*
1,1,.006,-.035,.014497*
20,1,.006,-.035,.014497,-.014497,.035,0.0*
1,1,.006,-.014497,.035*
20,1,.006,-.014497,.035,.014497,.035,0.0*
1,1,.006,.014497,.035*
20,1,.006,.014497,.035,.035,.014497,0.0*
1,1,.006,.035,.014497*
20,1,.006,.035,.014497,.035,-.014497,0.0*
1,1,.006,.035,-.014497*
20,1,.006,.035,-.014497,.014497,-.035,0.0*
1,1,.006,.014497,-.035*
1,1,.006,-.0229,-.01041*
20,1,.006,-.0229,-.01041,-.0229,.00729,0.0*
1,1,.006,-.0229,.00729*
20,1,.006,-.0229,.00729,-.02221,.00902,0.0*
1,1,.006,-.02221,.00902*
20,1,.006,-.02221,.00902,-.02082,.01006,0.0*
1,1,.006,-.02082,.01006*
20,1,.006,-.02082,.01006,-.01874,.01041,0.0*
1,1,.006,-.01874,.01041*
20,1,.006,-.01874,.01041,-.01666,.00972,0.0*
1,1,.006,-.01666,.00972*
20,1,.006,-.01666,.00972,-.01562,.00798,0.0*
1,1,.006,-.01562,.00798*
1,1,.006,-.01978,.00208*
20,1,.006,-.01978,.00208,-.02672,.00208,0.0*
1,1,.006,-.02672,.00208*
1,1,.006,.00001,.00347*
20,1,.006,.00001,.00347,.00001,-.01041,0.0*
1,1,.006,.00001,-.01041*
1,1,.006,.00001,.00902*
20,1,.006,.00001,.00902,-.00068,.00937,0.0*
1,1,.006,-.00068,.00937*
20,1,.006,-.00068,.00937,-.00068,.01006,0.0*
1,1,.006,-.00068,.01006*
20,1,.006,-.00068,.01006,.00001,.01041,0.0*
1,1,.006,.00001,.01041*
20,1,.006,.00001,.01041,.0007,.01006,0.0*
1,1,.006,.0007,.01006*
20,1,.006,.0007,.01006,.0007,.00937,0.0*
1,1,.006,.0007,.00937*
20,1,.006,.0007,.00937,.00001,.00902,0.0*
1,1,.006,.00001,.00902*
1,1,.006,.02084,.01041*
20,1,.006,.02084,.01041,.02084,-.01041,0.0*
1,1,.006,.02084,-.01041*
1,1,.006,.01598,.00347*
20,1,.006,.01598,.00347,.0257,.00347,0.0*
1,1,.006,.0257,.00347*
%
%ADD18MACRO18*%
%AMMACRO21*
1,1,.006,.0415,0.0*
20,1,.006,.0415,0.0,0.0,-.0415,0.0*
1,1,.006,0.0,-.0415*
20,1,.006,0.0,-.0415,-.0415,0.0,0.0*
1,1,.006,-.0415,0.0*
20,1,.006,-.0415,0.0,0.0,.0415,0.0*
1,1,.006,0.0,.0415*
20,1,.006,0.0,.0415,.0415,0.0,0.0*
1,1,.006,.0415,0.0*
1,1,.006,-.03776,-.0242*
20,1,.006,-.03776,-.0242,-.03776,.00485,0.0*
1,1,.006,-.03776,.00485*
1,1,.006,-.03776,.00049*
20,1,.006,-.03776,.00049,-.03534,.00291,0.0*
1,1,.006,-.03534,.00291*
20,1,.006,-.03534,.00291,-.03292,.00436,0.0*
1,1,.006,-.03292,.00436*
20,1,.006,-.03292,.00436,-.02905,.00485,0.0*
1,1,.006,-.02905,.00485*
20,1,.006,-.02905,.00485,-.02566,.00436,0.0*
1,1,.006,-.02566,.00436*
20,1,.006,-.02566,.00436,-.02227,.00194,0.0*
1,1,.006,-.02227,.00194*
20,1,.006,-.02227,.00194,-.02081,-.00145,0.0*
1,1,.006,-.02081,-.00145*
20,1,.006,-.02081,-.00145,-.02033,-.00484,0.0*
1,1,.006,-.02033,-.00484*
20,1,.006,-.02033,-.00484,-.02081,-.00823,0.0*
1,1,.006,-.02081,-.00823*
20,1,.006,-.02081,-.00823,-.02227,-.01162,0.0*
1,1,.006,-.02227,-.01162*
20,1,.006,-.02227,-.01162,-.02517,-.01355,0.0*
1,1,.006,-.02517,-.01355*
20,1,.006,-.02517,-.01355,-.02905,-.01452,0.0*
1,1,.006,-.02905,-.01452*
20,1,.006,-.02905,-.01452,-.03243,-.01404,0.0*
1,1,.006,-.03243,-.01404*
20,1,.006,-.03243,-.01404,-.03582,-.01258,0.0*
1,1,.006,-.03582,-.01258*
20,1,.006,-.03582,-.01258,-.03776,-.01065,0.0*
1,1,.006,-.03776,-.01065*
1,1,.006,.00001,.00485*
20,1,.006,.00001,.00485,.00001,-.01452,0.0*
1,1,.006,.00001,-.01452*
1,1,.006,.00001,.01259*
20,1,.006,.00001,.01259,-.00095,.01308,0.0*
1,1,.006,-.00095,.01308*
20,1,.006,-.00095,.01308,-.00095,.01405,0.0*
1,1,.006,-.00095,.01405*
20,1,.006,-.00095,.01405,.00001,.01453,0.0*
1,1,.006,.00001,.01453*
20,1,.006,.00001,.01453,.00098,.01405,0.0*
1,1,.006,.00098,.01405*
20,1,.006,.00098,.01405,.00098,.01308,0.0*
1,1,.006,.00098,.01308*
20,1,.006,.00098,.01308,.00001,.01259,0.0*
1,1,.006,.00001,.01259*
1,1,.006,.02181,-.00145*
20,1,.006,.02181,-.00145,.03731,-.00145,0.0*
1,1,.006,.03731,-.00145*
20,1,.006,.03731,-.00145,.03585,.00194,0.0*
1,1,.006,.03585,.00194*
20,1,.006,.03585,.00194,.03343,.00388,0.0*
1,1,.006,.03343,.00388*
20,1,.006,.03343,.00388,.03004,.00485,0.0*
1,1,.006,.03004,.00485*
20,1,.006,.03004,.00485,.02665,.00436,0.0*
1,1,.006,.02665,.00436*
20,1,.006,.02665,.00436,.02375,.00291,0.0*
1,1,.006,.02375,.00291*
20,1,.006,.02375,.00291,.02181,-.00048,0.0*
1,1,.006,.02181,-.00048*
20,1,.006,.02181,-.00048,.02084,-.00338,0.0*
1,1,.006,.02084,-.00338*
20,1,.006,.02084,-.00338,.02084,-.00629,0.0*
1,1,.006,.02084,-.00629*
20,1,.006,.02084,-.00629,.02181,-.00919,0.0*
1,1,.006,.02181,-.00919*
20,1,.006,.02181,-.00919,.02423,-.0121,0.0*
1,1,.006,.02423,-.0121*
20,1,.006,.02423,-.0121,.02714,-.01404,0.0*
1,1,.006,.02714,-.01404*
20,1,.006,.02714,-.01404,.03053,-.01452,0.0*
1,1,.006,.03053,-.01452*
20,1,.006,.03053,-.01452,.03392,-.01355,0.0*
1,1,.006,.03392,-.01355*
20,1,.006,.03392,-.01355,.03731,-.01065,0.0*
1,1,.006,.03731,-.01065*
%
%ADD21MACRO21*%
%AMMACRO28*
1,1,.006,.042043,-.1015*
20,1,.006,.042043,-.1015,-.042043,-.1015,0.0*
1,1,.006,-.042043,-.1015*
20,1,.006,-.042043,-.1015,-.1015,-.042043,0.0*
1,1,.006,-.1015,-.042043*
20,1,.006,-.1015,-.042043,-.1015,.042043,0.0*
1,1,.006,-.1015,.042043*
20,1,.006,-.1015,.042043,-.042043,.1015,0.0*
1,1,.006,-.042043,.1015*
20,1,.006,-.042043,.1015,.042043,.1015,0.0*
1,1,.006,.042043,.1015*
20,1,.006,.042043,.1015,.1015,.042043,0.0*
1,1,.006,.1015,.042043*
20,1,.006,.1015,.042043,.1015,-.042043,0.0*
1,1,.006,.1015,-.042043*
20,1,.006,.1015,-.042043,.042043,-.1015,0.0*
1,1,.006,.042043,-.1015*
1,1,.006,-.07951,.02014*
20,1,.006,-.07951,.02014,-.07347,.02617,0.0*
1,1,.006,-.07347,.02617*
20,1,.006,-.07347,.02617,-.06642,.02919,0.0*
1,1,.006,-.06642,.02919*
20,1,.006,-.06642,.02919,-.05837,.0302,0.0*
1,1,.006,-.05837,.0302*
20,1,.006,-.05837,.0302,-.04831,.02819,0.0*
1,1,.006,-.04831,.02819*
20,1,.006,-.04831,.02819,-.04126,.02315,0.0*
1,1,.006,-.04126,.02315*
20,1,.006,-.04126,.02315,-.03925,.01712,0.0*
1,1,.006,-.03925,.01712*
20,1,.006,-.03925,.01712,-.04025,.01108,0.0*
1,1,.006,-.04025,.01108*
20,1,.006,-.04025,.01108,-.04428,.00604,0.0*
1,1,.006,-.04428,.00604*
20,1,.006,-.04428,.00604,-.06441,-.00402,0.0*
1,1,.006,-.06441,-.00402*
20,1,.006,-.06441,-.00402,-.07347,-.01107,0.0*
1,1,.006,-.07347,-.01107*
20,1,.006,-.07347,-.01107,-.07951,-.02113,0.0*
1,1,.006,-.07951,-.02113*
20,1,.006,-.07951,-.02113,-.08152,-.03019,0.0*
1,1,.006,-.08152,-.03019*
20,1,.006,-.08152,-.03019,-.03925,-.03019,0.0*
1,1,.006,-.03925,-.03019*
1,1,.006,.00001,.0302*
20,1,.006,.00001,.0302,-.00804,.02819,0.0*
1,1,.006,-.00804,.02819*
20,1,.006,-.00804,.02819,-.01408,.02315,0.0*
1,1,.006,-.01408,.02315*
20,1,.006,-.01408,.02315,-.0181,.01712,0.0*
1,1,.006,-.0181,.01712*
20,1,.006,-.0181,.01712,-.02112,.00906,0.0*
1,1,.006,-.02112,.00906*
20,1,.006,-.02112,.00906,-.02213,0.0,0.0*
1,1,.006,-.02213,0.0*
20,1,.006,-.02213,0.0,-.02112,-.00905,0.0*
1,1,.006,-.02112,-.00905*
20,1,.006,-.02112,-.00905,-.0181,-.01711,0.0*
1,1,.006,-.0181,-.01711*
20,1,.006,-.0181,-.01711,-.01408,-.02315,0.0*
1,1,.006,-.01408,-.02315*
20,1,.006,-.01408,-.02315,-.00804,-.02818,0.0*
1,1,.006,-.00804,-.02818*
20,1,.006,-.00804,-.02818,.00001,-.03019,0.0*
1,1,.006,.00001,-.03019*
20,1,.006,.00001,-.03019,.00807,-.02818,0.0*
1,1,.006,.00807,-.02818*
20,1,.006,.00807,-.02818,.01411,-.02315,0.0*
1,1,.006,.01411,-.02315*
20,1,.006,.01411,-.02315,.01813,-.01711,0.0*
1,1,.006,.01813,-.01711*
20,1,.006,.01813,-.01711,.02115,-.00905,0.0*
1,1,.006,.02115,-.00905*
20,1,.006,.02115,-.00905,.02216,0.0,0.0*
1,1,.006,.02216,0.0*
20,1,.006,.02216,0.0,.02115,.00906,0.0*
1,1,.006,.02115,.00906*
20,1,.006,.02115,.00906,.01813,.01712,0.0*
1,1,.006,.01813,.01712*
20,1,.006,.01813,.01712,.01411,.02315,0.0*
1,1,.006,.01411,.02315*
20,1,.006,.01411,.02315,.00807,.02819,0.0*
1,1,.006,.00807,.02819*
20,1,.006,.00807,.02819,.00001,.0302,0.0*
1,1,.006,.00001,.0302*
1,1,.006,.03827,-.01811*
20,1,.006,.03827,-.01811,.04431,-.02516,0.0*
1,1,.006,.04431,-.02516*
20,1,.006,.04431,-.02516,.05236,-.02918,0.0*
1,1,.006,.05236,-.02918*
20,1,.006,.05236,-.02918,.06142,-.03019,0.0*
1,1,.006,.06142,-.03019*
20,1,.006,.06142,-.03019,.06947,-.02918,0.0*
1,1,.006,.06947,-.02918*
20,1,.006,.06947,-.02918,.07753,-.02415,0.0*
1,1,.006,.07753,-.02415*
20,1,.006,.07753,-.02415,.08256,-.01811,0.0*
1,1,.006,.08256,-.01811*
20,1,.006,.08256,-.01811,.08356,-.01207,0.0*
1,1,.006,.08356,-.01207*
20,1,.006,.08356,-.01207,.08155,-.00503,0.0*
1,1,.006,.08155,-.00503*
20,1,.006,.08155,-.00503,.07451,0.0,0.0*
1,1,.006,.07451,0.0*
20,1,.006,.07451,0.0,.06746,.00202,0.0*
1,1,.006,.06746,.00202*
20,1,.006,.06746,.00202,.0584,.00202,0.0*
1,1,.006,.0584,.00202*
1,1,.006,.06746,.00202*
20,1,.006,.06746,.00202,.0735,.00504,0.0*
1,1,.006,.0735,.00504*
20,1,.006,.0735,.00504,.07853,.01007,0.0*
1,1,.006,.07853,.01007*
20,1,.006,.07853,.01007,.08055,.01611,0.0*
1,1,.006,.08055,.01611*
20,1,.006,.08055,.01611,.07853,.02215,0.0*
1,1,.006,.07853,.02215*
20,1,.006,.07853,.02215,.0735,.02718,0.0*
1,1,.006,.0735,.02718*
20,1,.006,.0735,.02718,.06444,.0302,0.0*
1,1,.006,.06444,.0302*
20,1,.006,.06444,.0302,.05538,.02919,0.0*
1,1,.006,.05538,.02919*
20,1,.006,.05538,.02919,.04632,.02517,0.0*
1,1,.006,.04632,.02517*
%
%ADD28MACRO28*%
%AMMACRO23*
1,1,.006,.0425,0.0*
20,1,.006,.0425,0.0,0.0,-.0425,0.0*
1,1,.006,0.0,-.0425*
20,1,.006,0.0,-.0425,-.0425,0.0,0.0*
1,1,.006,-.0425,0.0*
20,1,.006,-.0425,0.0,0.0,.0425,0.0*
1,1,.006,0.0,.0425*
20,1,.006,0.0,.0425,.0425,0.0,0.0*
1,1,.006,.0425,0.0*
1,1,.006,-.03867,-.02479*
20,1,.006,-.03867,-.02479,-.03867,.00496,0.0*
1,1,.006,-.03867,.00496*
1,1,.006,-.03867,.0005*
20,1,.006,-.03867,.0005,-.03619,.00298,0.0*
1,1,.006,-.03619,.00298*
20,1,.006,-.03619,.00298,-.03371,.00447,0.0*
1,1,.006,-.03371,.00447*
20,1,.006,-.03371,.00447,-.02975,.00496,0.0*
1,1,.006,-.02975,.00496*
20,1,.006,-.02975,.00496,-.02627,.00447,0.0*
1,1,.006,-.02627,.00447*
20,1,.006,-.02627,.00447,-.0228,.00199,0.0*
1,1,.006,-.0228,.00199*
20,1,.006,-.0228,.00199,-.02132,-.00148,0.0*
1,1,.006,-.02132,-.00148*
20,1,.006,-.02132,-.00148,-.02082,-.00495,0.0*
1,1,.006,-.02082,-.00495*
20,1,.006,-.02082,-.00495,-.02132,-.00842,0.0*
1,1,.006,-.02132,-.00842*
20,1,.006,-.02132,-.00842,-.0228,-.0119,0.0*
1,1,.006,-.0228,-.0119*
20,1,.006,-.0228,-.0119,-.02578,-.01388,0.0*
1,1,.006,-.02578,-.01388*
20,1,.006,-.02578,-.01388,-.02975,-.01487,0.0*
1,1,.006,-.02975,-.01487*
20,1,.006,-.02975,-.01487,-.03322,-.01437,0.0*
1,1,.006,-.03322,-.01437*
20,1,.006,-.03322,-.01437,-.03669,-.01289,0.0*
1,1,.006,-.03669,-.01289*
20,1,.006,-.03669,-.01289,-.03867,-.0109,0.0*
1,1,.006,-.03867,-.0109*
1,1,.006,.00001,.00496*
20,1,.006,.00001,.00496,.00001,-.01487,0.0*
1,1,.006,.00001,-.01487*
1,1,.006,.00001,.0129*
20,1,.006,.00001,.0129,-.00098,.01339,0.0*
1,1,.006,-.00098,.01339*
20,1,.006,-.00098,.01339,-.00098,.01438,0.0*
1,1,.006,-.00098,.01438*
20,1,.006,-.00098,.01438,.00001,.01488,0.0*
1,1,.006,.00001,.01488*
20,1,.006,.00001,.01488,.00101,.01438,0.0*
1,1,.006,.00101,.01438*
20,1,.006,.00101,.01438,.00101,.01339,0.0*
1,1,.006,.00101,.01339*
20,1,.006,.00101,.01339,.00001,.0129,0.0*
1,1,.006,.00001,.0129*
1,1,.006,.02977,.01488*
20,1,.006,.02977,.01488,.02977,-.01487,0.0*
1,1,.006,.02977,-.01487*
1,1,.006,.02283,.00496*
20,1,.006,.02283,.00496,.03672,.00496,0.0*
1,1,.006,.03672,.00496*
%
%ADD23MACRO23*%
%AMMACRO17*
1,1,.006,.035,0.0*
20,1,.006,.035,0.0,.034468,-.006078,0.0*
1,1,.006,.034468,-.006078*
20,1,.006,.034468,-.006078,.032889,-.011971,0.0*
1,1,.006,.032889,-.011971*
20,1,.006,.032889,-.011971,.030311,-.0175,0.0*
1,1,.006,.030311,-.0175*
20,1,.006,.030311,-.0175,.026812,-.022498,0.0*
1,1,.006,.026812,-.022498*
20,1,.006,.026812,-.022498,.022498,-.026812,0.0*
1,1,.006,.022498,-.026812*
20,1,.006,.022498,-.026812,.0175,-.030311,0.0*
1,1,.006,.0175,-.030311*
20,1,.006,.0175,-.030311,.011971,-.032889,0.0*
1,1,.006,.011971,-.032889*
20,1,.006,.011971,-.032889,.006078,-.034468,0.0*
1,1,.006,.006078,-.034468*
20,1,.006,.006078,-.034468,0.0,-.035,0.0*
1,1,.006,0.0,-.035*
20,1,.006,0.0,-.035,-.006078,-.034468,0.0*
1,1,.006,-.006078,-.034468*
20,1,.006,-.006078,-.034468,-.011971,-.032889,0.0*
1,1,.006,-.011971,-.032889*
20,1,.006,-.011971,-.032889,-.0175,-.030311,0.0*
1,1,.006,-.0175,-.030311*
20,1,.006,-.0175,-.030311,-.022498,-.026812,0.0*
1,1,.006,-.022498,-.026812*
20,1,.006,-.022498,-.026812,-.026812,-.022498,0.0*
1,1,.006,-.026812,-.022498*
20,1,.006,-.026812,-.022498,-.030311,-.0175,0.0*
1,1,.006,-.030311,-.0175*
20,1,.006,-.030311,-.0175,-.032889,-.011971,0.0*
1,1,.006,-.032889,-.011971*
20,1,.006,-.032889,-.011971,-.034468,-.006078,0.0*
1,1,.006,-.034468,-.006078*
20,1,.006,-.034468,-.006078,-.035,0.0,0.0*
1,1,.006,-.035,0.0*
20,1,.006,-.035,0.0,-.034468,.006078,0.0*
1,1,.006,-.034468,.006078*
20,1,.006,-.034468,.006078,-.032889,.011971,0.0*
1,1,.006,-.032889,.011971*
20,1,.006,-.032889,.011971,-.030311,.0175,0.0*
1,1,.006,-.030311,.0175*
20,1,.006,-.030311,.0175,-.026812,.022498,0.0*
1,1,.006,-.026812,.022498*
20,1,.006,-.026812,.022498,-.022498,.026812,0.0*
1,1,.006,-.022498,.026812*
20,1,.006,-.022498,.026812,-.0175,.030311,0.0*
1,1,.006,-.0175,.030311*
20,1,.006,-.0175,.030311,-.011971,.032889,0.0*
1,1,.006,-.011971,.032889*
20,1,.006,-.011971,.032889,-.006078,.034468,0.0*
1,1,.006,-.006078,.034468*
20,1,.006,-.006078,.034468,0.0,.035,0.0*
1,1,.006,0.0,.035*
20,1,.006,0.0,.035,.006078,.034468,0.0*
1,1,.006,.006078,.034468*
20,1,.006,.006078,.034468,.011971,.032889,0.0*
1,1,.006,.011971,.032889*
20,1,.006,.011971,.032889,.0175,.030311,0.0*
1,1,.006,.0175,.030311*
20,1,.006,.0175,.030311,.022498,.026812,0.0*
1,1,.006,.022498,.026812*
20,1,.006,.022498,.026812,.026812,.022498,0.0*
1,1,.006,.026812,.022498*
20,1,.006,.026812,.022498,.030311,.0175,0.0*
1,1,.006,.030311,.0175*
20,1,.006,.030311,.0175,.032889,.011971,0.0*
1,1,.006,.032889,.011971*
20,1,.006,.032889,.011971,.034468,.006078,0.0*
1,1,.006,.034468,.006078*
20,1,.006,.034468,.006078,.035,0.0,0.0*
1,1,.006,.035,0.0*
1,1,.006,-.02082,.01041*
20,1,.006,-.02082,.01041,-.02082,-.01041,0.0*
1,1,.006,-.02082,-.01041*
1,1,.006,-.0288,.01041*
20,1,.006,-.0288,.01041,-.01284,.01041,0.0*
1,1,.006,-.01284,.01041*
1,1,.006,-.00693,-.01041*
20,1,.006,-.00693,-.01041,-.00693,.01041,0.0*
1,1,.006,-.00693,.01041*
20,1,.006,-.00693,.01041,.0014,.01041,0.0*
1,1,.006,.0014,.01041*
20,1,.006,.0014,.01041,.00417,.00937,0.0*
1,1,.006,.00417,.00937*
20,1,.006,.00417,.00937,.00626,.00694,0.0*
1,1,.006,.00626,.00694*
20,1,.006,.00626,.00694,.00695,.00416,0.0*
1,1,.006,.00695,.00416*
20,1,.006,.00695,.00416,.00626,.00139,0.0*
1,1,.006,.00626,.00139*
20,1,.006,.00626,.00139,.00452,-.00069,0.0*
1,1,.006,.00452,-.00069*
20,1,.006,.00452,-.00069,.0014,-.00174,0.0*
1,1,.006,.0014,-.00174*
20,1,.006,.0014,-.00174,-.00693,-.00174,0.0*
1,1,.006,-.00693,-.00174*
1,1,.006,.01216,.01041*
20,1,.006,.01216,.01041,.02084,-.01041,0.0*
1,1,.006,.02084,-.01041*
20,1,.006,.02084,-.01041,.02952,.01041,0.0*
1,1,.006,.02952,.01041*
%
%ADD17MACRO17*%
%AMMACRO15*
1,1,.006,.035,.035*
20,1,.006,.035,.035,.035,-.035,0.0*
1,1,.006,.035,-.035*
20,1,.006,.035,-.035,-.035,-.035,0.0*
1,1,.006,-.035,-.035*
20,1,.006,-.035,-.035,-.035,.035,0.0*
1,1,.006,-.035,.035*
20,1,.006,-.035,.035,.035,.035,0.0*
1,1,.006,.035,.035*
1,1,.006,-.0245,.01225*
20,1,.006,-.0245,.01225,-.02777,.01143,0.0*
1,1,.006,-.02777,.01143*
20,1,.006,-.02777,.01143,-.03022,.00939,0.0*
1,1,.006,-.03022,.00939*
20,1,.006,-.03022,.00939,-.03185,.00694,0.0*
1,1,.006,-.03185,.00694*
20,1,.006,-.03185,.00694,-.03308,.00367,0.0*
1,1,.006,-.03308,.00367*
20,1,.006,-.03308,.00367,-.03348,0.0,0.0*
1,1,.006,-.03348,0.0*
20,1,.006,-.03348,0.0,-.03308,-.00368,0.0*
1,1,.006,-.03308,-.00368*
20,1,.006,-.03308,-.00368,-.03185,-.00694,0.0*
1,1,.006,-.03185,-.00694*
20,1,.006,-.03185,-.00694,-.03022,-.00939,0.0*
1,1,.006,-.03022,-.00939*
20,1,.006,-.03022,-.00939,-.02777,-.01143,0.0*
1,1,.006,-.02777,-.01143*
20,1,.006,-.02777,-.01143,-.0245,-.01225,0.0*
1,1,.006,-.0245,-.01225*
20,1,.006,-.0245,-.01225,-.02123,-.01143,0.0*
1,1,.006,-.02123,-.01143*
20,1,.006,-.02123,-.01143,-.01878,-.00939,0.0*
1,1,.006,-.01878,-.00939*
20,1,.006,-.01878,-.00939,-.01715,-.00694,0.0*
1,1,.006,-.01715,-.00694*
20,1,.006,-.01715,-.00694,-.01592,-.00368,0.0*
1,1,.006,-.01592,-.00368*
20,1,.006,-.01592,-.00368,-.01552,0.0,0.0*
1,1,.006,-.01552,0.0*
20,1,.006,-.01552,0.0,-.01592,.00367,0.0*
1,1,.006,-.01592,.00367*
20,1,.006,-.01592,.00367,-.01715,.00694,0.0*
1,1,.006,-.01715,.00694*
20,1,.006,-.01715,.00694,-.01878,.00939,0.0*
1,1,.006,-.01878,.00939*
20,1,.006,-.01878,.00939,-.02123,.01143,0.0*
1,1,.006,-.02123,.01143*
20,1,.006,-.02123,.01143,-.0245,.01225,0.0*
1,1,.006,-.0245,.01225*
1,1,.006,-.00775,.00817*
20,1,.006,-.00775,.00817,-.0053,.01062,0.0*
1,1,.006,-.0053,.01062*
20,1,.006,-.0053,.01062,-.00244,.01184,0.0*
1,1,.006,-.00244,.01184*
20,1,.006,-.00244,.01184,.00083,.01225,0.0*
1,1,.006,.00083,.01225*
20,1,.006,.00083,.01225,.00491,.01143,0.0*
1,1,.006,.00491,.01143*
20,1,.006,.00491,.01143,.00777,.00939,0.0*
1,1,.006,.00777,.00939*
20,1,.006,.00777,.00939,.00859,.00694,0.0*
1,1,.006,.00859,.00694*
20,1,.006,.00859,.00694,.00818,.00449,0.0*
1,1,.006,.00818,.00449*
20,1,.006,.00818,.00449,.00654,.00245,0.0*
1,1,.006,.00654,.00245*
20,1,.006,.00654,.00245,-.00162,-.00163,0.0*
1,1,.006,-.00162,-.00163*
20,1,.006,-.00162,-.00163,-.0053,-.00449,0.0*
1,1,.006,-.0053,-.00449*
20,1,.006,-.0053,-.00449,-.00775,-.00858,0.0*
1,1,.006,-.00775,-.00858*
20,1,.006,-.00775,-.00858,-.00857,-.01225,0.0*
1,1,.006,-.00857,-.01225*
20,1,.006,-.00857,-.01225,.00859,-.01225,0.0*
1,1,.006,.00859,-.01225*
1,1,.006,.01676,.00817*
20,1,.006,.01676,.00817,.01921,.01062,0.0*
1,1,.006,.01921,.01062*
20,1,.006,.01921,.01062,.02207,.01184,0.0*
1,1,.006,.02207,.01184*
20,1,.006,.02207,.01184,.02534,.01225,0.0*
1,1,.006,.02534,.01225*
20,1,.006,.02534,.01225,.02942,.01143,0.0*
1,1,.006,.02942,.01143*
20,1,.006,.02942,.01143,.03228,.00939,0.0*
1,1,.006,.03228,.00939*
20,1,.006,.03228,.00939,.0331,.00694,0.0*
1,1,.006,.0331,.00694*
20,1,.006,.0331,.00694,.03269,.00449,0.0*
1,1,.006,.03269,.00449*
20,1,.006,.03269,.00449,.03105,.00245,0.0*
1,1,.006,.03105,.00245*
20,1,.006,.03105,.00245,.02289,-.00163,0.0*
1,1,.006,.02289,-.00163*
20,1,.006,.02289,-.00163,.01921,-.00449,0.0*
1,1,.006,.01921,-.00449*
20,1,.006,.01921,-.00449,.01676,-.00858,0.0*
1,1,.006,.01676,-.00858*
20,1,.006,.01676,-.00858,.01594,-.01225,0.0*
1,1,.006,.01594,-.01225*
20,1,.006,.01594,-.01225,.0331,-.01225,0.0*
1,1,.006,.0331,-.01225*
%
%ADD15MACRO15*%
%AMMACRO12*
1,1,.006,.126,0.0*
20,1,.006,.126,0.0,.124086,-.02188,0.0*
1,1,.006,.124086,-.02188*
20,1,.006,.124086,-.02188,.118401,-.043095,0.0*
1,1,.006,.118401,-.043095*
20,1,.006,.118401,-.043095,.109119,-.063,0.0*
1,1,.006,.109119,-.063*
20,1,.006,.109119,-.063,.096522,-.080991,0.0*
1,1,.006,.096522,-.080991*
20,1,.006,.096522,-.080991,.080991,-.096522,0.0*
1,1,.006,.080991,-.096522*
20,1,.006,.080991,-.096522,.063,-.109119,0.0*
1,1,.006,.063,-.109119*
20,1,.006,.063,-.109119,.043095,-.118401,0.0*
1,1,.006,.043095,-.118401*
20,1,.006,.043095,-.118401,.02188,-.124086,0.0*
1,1,.006,.02188,-.124086*
20,1,.006,.02188,-.124086,0.0,-.126,0.0*
1,1,.006,0.0,-.126*
20,1,.006,0.0,-.126,-.02188,-.124086,0.0*
1,1,.006,-.02188,-.124086*
20,1,.006,-.02188,-.124086,-.043095,-.118401,0.0*
1,1,.006,-.043095,-.118401*
20,1,.006,-.043095,-.118401,-.063,-.109119,0.0*
1,1,.006,-.063,-.109119*
20,1,.006,-.063,-.109119,-.080991,-.096522,0.0*
1,1,.006,-.080991,-.096522*
20,1,.006,-.080991,-.096522,-.096522,-.080991,0.0*
1,1,.006,-.096522,-.080991*
20,1,.006,-.096522,-.080991,-.109119,-.063,0.0*
1,1,.006,-.109119,-.063*
20,1,.006,-.109119,-.063,-.118401,-.043095,0.0*
1,1,.006,-.118401,-.043095*
20,1,.006,-.118401,-.043095,-.124086,-.02188,0.0*
1,1,.006,-.124086,-.02188*
20,1,.006,-.124086,-.02188,-.126,0.0,0.0*
1,1,.006,-.126,0.0*
20,1,.006,-.126,0.0,-.124086,.02188,0.0*
1,1,.006,-.124086,.02188*
20,1,.006,-.124086,.02188,-.118401,.043095,0.0*
1,1,.006,-.118401,.043095*
20,1,.006,-.118401,.043095,-.109119,.063,0.0*
1,1,.006,-.109119,.063*
20,1,.006,-.109119,.063,-.096522,.080991,0.0*
1,1,.006,-.096522,.080991*
20,1,.006,-.096522,.080991,-.080991,.096522,0.0*
1,1,.006,-.080991,.096522*
20,1,.006,-.080991,.096522,-.063,.109119,0.0*
1,1,.006,-.063,.109119*
20,1,.006,-.063,.109119,-.043095,.118401,0.0*
1,1,.006,-.043095,.118401*
20,1,.006,-.043095,.118401,-.02188,.124086,0.0*
1,1,.006,-.02188,.124086*
20,1,.006,-.02188,.124086,0.0,.126,0.0*
1,1,.006,0.0,.126*
20,1,.006,0.0,.126,.02188,.124086,0.0*
1,1,.006,.02188,.124086*
20,1,.006,.02188,.124086,.043095,.118401,0.0*
1,1,.006,.043095,.118401*
20,1,.006,.043095,.118401,.063,.109119,0.0*
1,1,.006,.063,.109119*
20,1,.006,.063,.109119,.080991,.096522,0.0*
1,1,.006,.080991,.096522*
20,1,.006,.080991,.096522,.096522,.080991,0.0*
1,1,.006,.096522,.080991*
20,1,.006,.096522,.080991,.109119,.063,0.0*
1,1,.006,.109119,.063*
20,1,.006,.109119,.063,.118401,.043095,0.0*
1,1,.006,.118401,.043095*
20,1,.006,.118401,.043095,.124086,.02188,0.0*
1,1,.006,.124086,.02188*
20,1,.006,.124086,.02188,.126,0.0,0.0*
1,1,.006,.126,0.0*
1,1,.006,-.09871,.025*
20,1,.006,-.09871,.025,-.09121,.03249,0.0*
1,1,.006,-.09121,.03249*
20,1,.006,-.09121,.03249,-.08246,.03624,0.0*
1,1,.006,-.08246,.03624*
20,1,.006,-.08246,.03624,-.07247,.03749,0.0*
1,1,.006,-.07247,.03749*
20,1,.006,-.07247,.03749,-.05997,.03499,0.0*
1,1,.006,-.05997,.03499*
20,1,.006,-.05997,.03499,-.05122,.02874,0.0*
1,1,.006,-.05122,.02874*
20,1,.006,-.05122,.02874,-.04873,.02125,0.0*
1,1,.006,-.04873,.02125*
20,1,.006,-.04873,.02125,-.04997,.01375,0.0*
1,1,.006,-.04997,.01375*
20,1,.006,-.04997,.01375,-.05497,.0075,0.0*
1,1,.006,-.05497,.0075*
20,1,.006,-.05497,.0075,-.07996,-.00499,0.0*
1,1,.006,-.07996,-.00499*
20,1,.006,-.07996,-.00499,-.09121,-.01374,0.0*
1,1,.006,-.09121,-.01374*
20,1,.006,-.09121,-.01374,-.09871,-.02624,0.0*
1,1,.006,-.09871,-.02624*
20,1,.006,-.09871,-.02624,-.1012,-.03748,0.0*
1,1,.006,-.1012,-.03748*
20,1,.006,-.1012,-.03748,-.04873,-.03748,0.0*
1,1,.006,-.04873,-.03748*
1,1,.006,-.02747,-.02624*
20,1,.006,-.02747,-.02624,-.01998,-.03248,0.0*
1,1,.006,-.01998,-.03248*
20,1,.006,-.01998,-.03248,-.01123,-.03623,0.0*
1,1,.006,-.01123,-.03623*
20,1,.006,-.01123,-.03623,.00001,-.03748,0.0*
1,1,.006,.00001,-.03748*
20,1,.006,.00001,-.03748,.01126,-.03498,0.0*
1,1,.006,.01126,-.03498*
20,1,.006,.01126,-.03498,.02001,-.02998,0.0*
1,1,.006,.02001,-.02998*
20,1,.006,.02001,-.02998,.02625,-.02124,0.0*
1,1,.006,.02625,-.02124*
20,1,.006,.02625,-.02124,.0275,-.01124,0.0*
1,1,.006,.0275,-.01124*
20,1,.006,.0275,-.01124,.02501,-.00125,0.0*
1,1,.006,.02501,-.00125*
20,1,.006,.02501,-.00125,.01876,.005,0.0*
1,1,.006,.01876,.005*
20,1,.006,.01876,.005,.01001,.01,0.0*
1,1,.006,.01001,.01*
20,1,.006,.01001,.01,.00127,.01125,0.0*
1,1,.006,.00127,.01125*
20,1,.006,.00127,.01125,-.00748,.01,0.0*
1,1,.006,-.00748,.01*
20,1,.006,-.00748,.01,-.01873,.005,0.0*
1,1,.006,-.01873,.005*
20,1,.006,-.01873,.005,-.01498,.03749,0.0*
1,1,.006,-.01498,.03749*
20,1,.006,-.01498,.03749,.01876,.03749,0.0*
1,1,.006,.01876,.03749*
1,1,.006,.05125,.025*
20,1,.006,.05125,.025,.05875,.03249,0.0*
1,1,.006,.05875,.03249*
20,1,.006,.05875,.03249,.0675,.03624,0.0*
1,1,.006,.0675,.03624*
20,1,.006,.0675,.03624,.07749,.03749,0.0*
1,1,.006,.07749,.03749*
20,1,.006,.07749,.03749,.08999,.03499,0.0*
1,1,.006,.08999,.03499*
20,1,.006,.08999,.03499,.09874,.02874,0.0*
1,1,.006,.09874,.02874*
20,1,.006,.09874,.02874,.10123,.02125,0.0*
1,1,.006,.10123,.02125*
20,1,.006,.10123,.02125,.09999,.01375,0.0*
1,1,.006,.09999,.01375*
20,1,.006,.09999,.01375,.09499,.0075,0.0*
1,1,.006,.09499,.0075*
20,1,.006,.09499,.0075,.07,-.00499,0.0*
1,1,.006,.07,-.00499*
20,1,.006,.07,-.00499,.05875,-.01374,0.0*
1,1,.006,.05875,-.01374*
20,1,.006,.05875,-.01374,.05125,-.02624,0.0*
1,1,.006,.05125,-.02624*
20,1,.006,.05125,-.02624,.04876,-.03748,0.0*
1,1,.006,.04876,-.03748*
20,1,.006,.04876,-.03748,.10123,-.03748,0.0*
1,1,.006,.10123,-.03748*
%
%ADD12MACRO12*%
%AMMACRO31*
1,1,.006,.043,0.0*
20,1,.006,.043,0.0,0.0,-.043,0.0*
1,1,.006,0.0,-.043*
20,1,.006,0.0,-.043,-.043,0.0,0.0*
1,1,.006,-.043,0.0*
20,1,.006,-.043,0.0,0.0,.043,0.0*
1,1,.006,0.0,.043*
20,1,.006,0.0,.043,.043,0.0,0.0*
1,1,.006,.043,0.0*
1,1,.006,-.03913,-.02508*
20,1,.006,-.03913,-.02508,-.03913,.00502,0.0*
1,1,.006,-.03913,.00502*
1,1,.006,-.03913,.0005*
20,1,.006,-.03913,.0005,-.03662,.00301,0.0*
1,1,.006,-.03662,.00301*
20,1,.006,-.03662,.00301,-.03411,.00451,0.0*
1,1,.006,-.03411,.00451*
20,1,.006,-.03411,.00451,-.0301,.00502,0.0*
1,1,.006,-.0301,.00502*
20,1,.006,-.0301,.00502,-.02659,.00451,0.0*
1,1,.006,-.02659,.00451*
20,1,.006,-.02659,.00451,-.02308,.00201,0.0*
1,1,.006,-.02308,.00201*
20,1,.006,-.02308,.00201,-.02157,-.00151,0.0*
1,1,.006,-.02157,-.00151*
20,1,.006,-.02157,-.00151,-.02107,-.00502,0.0*
1,1,.006,-.02107,-.00502*
20,1,.006,-.02107,-.00502,-.02157,-.00853,0.0*
1,1,.006,-.02157,-.00853*
20,1,.006,-.02157,-.00853,-.02308,-.01204,0.0*
1,1,.006,-.02308,-.01204*
20,1,.006,-.02308,-.01204,-.02609,-.01405,0.0*
1,1,.006,-.02609,-.01405*
20,1,.006,-.02609,-.01405,-.0301,-.01505,0.0*
1,1,.006,-.0301,-.01505*
20,1,.006,-.0301,-.01505,-.03361,-.01455,0.0*
1,1,.006,-.03361,-.01455*
20,1,.006,-.03361,-.01455,-.03712,-.01304,0.0*
1,1,.006,-.03712,-.01304*
20,1,.006,-.03712,-.01304,-.03913,-.01104,0.0*
1,1,.006,-.03913,-.01104*
1,1,.006,.00001,.00502*
20,1,.006,.00001,.00502,.00001,-.01505,0.0*
1,1,.006,.00001,-.01505*
1,1,.006,.00001,.01304*
20,1,.006,.00001,.01304,-.00099,.01354,0.0*
1,1,.006,-.00099,.01354*
20,1,.006,-.00099,.01354,-.00099,.01455,0.0*
1,1,.006,-.00099,.01455*
20,1,.006,-.00099,.01455,.00001,.01505,0.0*
1,1,.006,.00001,.01505*
20,1,.006,.00001,.01505,.00101,.01455,0.0*
1,1,.006,.00101,.01455*
20,1,.006,.00101,.01455,.00101,.01354,0.0*
1,1,.006,.00101,.01354*
20,1,.006,.00101,.01354,.00001,.01304,0.0*
1,1,.006,.00001,.01304*
1,1,.006,.01958,-.02408*
20,1,.006,.01958,-.02408,.0226,-.02508,0.0*
1,1,.006,.0226,-.02508*
20,1,.006,.0226,-.02508,.02661,-.02408,0.0*
1,1,.006,.02661,-.02408*
20,1,.006,.02661,-.02408,.02912,-.02207,0.0*
1,1,.006,.02912,-.02207*
20,1,.006,.02912,-.02207,.03112,-.01956,0.0*
1,1,.006,.03112,-.01956*
20,1,.006,.03112,-.01956,.03413,-.01154,0.0*
1,1,.006,.03413,-.01154*
20,1,.006,.03413,-.01154,.04066,.00502,0.0*
1,1,.006,.04066,.00502*
1,1,.006,.0246,.00502*
20,1,.006,.0246,.00502,.03413,-.01154,0.0*
1,1,.006,.03413,-.01154*
%
%ADD31MACRO31*%
%AMMACRO22*
1,1,.006,.0475,0.0*
20,1,.006,.0475,0.0,0.0,-.0475,0.0*
1,1,.006,0.0,-.0475*
20,1,.006,0.0,-.0475,-.0475,0.0,0.0*
1,1,.006,-.0475,0.0*
20,1,.006,-.0475,0.0,0.0,.0475,0.0*
1,1,.006,0.0,.0475*
20,1,.006,0.0,.0475,.0475,0.0,0.0*
1,1,.006,.0475,0.0*
1,1,.006,-.04322,-.0277*
20,1,.006,-.04322,-.0277,-.04322,.00555,0.0*
1,1,.006,-.04322,.00555*
1,1,.006,-.04322,.00056*
20,1,.006,-.04322,.00056,-.04045,.00333,0.0*
1,1,.006,-.04045,.00333*
20,1,.006,-.04045,.00333,-.03768,.00499,0.0*
1,1,.006,-.03768,.00499*
20,1,.006,-.03768,.00499,-.03325,.00555,0.0*
1,1,.006,-.03325,.00555*
20,1,.006,-.03325,.00555,-.02937,.00499,0.0*
1,1,.006,-.02937,.00499*
20,1,.006,-.02937,.00499,-.02549,.00222,0.0*
1,1,.006,-.02549,.00222*
20,1,.006,-.02549,.00222,-.02382,-.00166,0.0*
1,1,.006,-.02382,-.00166*
20,1,.006,-.02382,-.00166,-.02327,-.00554,0.0*
1,1,.006,-.02327,-.00554*
20,1,.006,-.02327,-.00554,-.02382,-.00942,0.0*
1,1,.006,-.02382,-.00942*
20,1,.006,-.02382,-.00942,-.02549,-.0133,0.0*
1,1,.006,-.02549,-.0133*
20,1,.006,-.02549,-.0133,-.02881,-.01551,0.0*
1,1,.006,-.02881,-.01551*
20,1,.006,-.02881,-.01551,-.03325,-.01662,0.0*
1,1,.006,-.03325,-.01662*
20,1,.006,-.03325,-.01662,-.03712,-.01607,0.0*
1,1,.006,-.03712,-.01607*
20,1,.006,-.03712,-.01607,-.041,-.0144,0.0*
1,1,.006,-.041,-.0144*
20,1,.006,-.041,-.0144,-.04322,-.01219,0.0*
1,1,.006,-.04322,-.01219*
1,1,.006,.00001,-.01662*
20,1,.006,.00001,-.01662,-.00331,-.01607,0.0*
1,1,.006,-.00331,-.01607*
20,1,.006,-.00331,-.01607,-.00664,-.01385,0.0*
1,1,.006,-.00664,-.01385*
20,1,.006,-.00664,-.01385,-.00885,-.00997,0.0*
1,1,.006,-.00885,-.00997*
20,1,.006,-.00885,-.00997,-.00996,-.00554,0.0*
1,1,.006,-.00996,-.00554*
20,1,.006,-.00996,-.00554,-.00885,-.0011,0.0*
1,1,.006,-.00885,-.0011*
20,1,.006,-.00885,-.0011,-.00664,.00278,0.0*
1,1,.006,-.00664,.00278*
20,1,.006,-.00664,.00278,-.00331,.00499,0.0*
1,1,.006,-.00331,.00499*
20,1,.006,-.00331,.00499,.00001,.00555,0.0*
1,1,.006,.00001,.00555*
20,1,.006,.00001,.00555,.00334,.00499,0.0*
1,1,.006,.00334,.00499*
20,1,.006,.00334,.00499,.00667,.00278,0.0*
1,1,.006,.00667,.00278*
20,1,.006,.00667,.00278,.00888,-.0011,0.0*
1,1,.006,.00888,-.0011*
20,1,.006,.00888,-.0011,.00944,-.00554,0.0*
1,1,.006,.00944,-.00554*
20,1,.006,.00944,-.00554,.00888,-.00997,0.0*
1,1,.006,.00888,-.00997*
20,1,.006,.00888,-.00997,.00667,-.01385,0.0*
1,1,.006,.00667,-.01385*
20,1,.006,.00667,-.01385,.00334,-.01607,0.0*
1,1,.006,.00334,-.01607*
20,1,.006,.00334,-.01607,.00001,-.01662,0.0*
1,1,.006,.00001,-.01662*
1,1,.006,.03327,.01663*
20,1,.006,.03327,.01663,.03327,-.01662,0.0*
1,1,.006,.03327,-.01662*
1,1,.006,.02552,.00555*
20,1,.006,.02552,.00555,.04103,.00555,0.0*
1,1,.006,.04103,.00555*
%
%ADD22MACRO22*%
%AMMACRO14*
1,1,.006,.0595,0.0*
20,1,.006,.0595,0.0,0.0,-.0595,0.0*
1,1,.006,0.0,-.0595*
20,1,.006,0.0,-.0595,-.0595,0.0,0.0*
1,1,.006,-.0595,0.0*
20,1,.006,-.0595,0.0,0.0,.0595,0.0*
1,1,.006,0.0,.0595*
20,1,.006,0.0,.0595,.0595,0.0,0.0*
1,1,.006,.0595,0.0*
1,1,.006,-.04165,-.02082*
20,1,.006,-.04165,-.02082,-.04165,.02083,0.0*
1,1,.006,-.04165,.02083*
20,1,.006,-.04165,.02083,-.04998,.0125,0.0*
1,1,.006,-.04998,.0125*
1,1,.006,-.04998,-.02082*
20,1,.006,-.04998,-.02082,-.03332,-.02082,0.0*
1,1,.006,-.03332,-.02082*
1,1,.006,.00001,-.02082*
20,1,.006,.00001,-.02082,.00001,.02083,0.0*
1,1,.006,.00001,.02083*
20,1,.006,.00001,.02083,-.00832,.0125,0.0*
1,1,.006,-.00832,.0125*
1,1,.006,-.00832,-.02082*
20,1,.006,-.00832,-.02082,.00834,-.02082,0.0*
1,1,.006,.00834,-.02082*
1,1,.006,.02987,-.01596*
20,1,.006,.02987,-.01596,.03473,-.01943,0.0*
1,1,.006,.03473,-.01943*
20,1,.006,.03473,-.01943,.04029,-.02082,0.0*
1,1,.006,.04029,-.02082*
20,1,.006,.04029,-.02082,.04584,-.01943,0.0*
1,1,.006,.04584,-.01943*
20,1,.006,.04584,-.01943,.0507,-.01527,0.0*
1,1,.006,.0507,-.01527*
20,1,.006,.0507,-.01527,.05417,-.00902,0.0*
1,1,.006,.05417,-.00902*
20,1,.006,.05417,-.00902,.05556,-.00277,0.0*
1,1,.006,.05556,-.00277*
20,1,.006,.05556,-.00277,.05556,.00486,0.0*
1,1,.006,.05556,.00486*
20,1,.006,.05556,.00486,.05417,.01111,0.0*
1,1,.006,.05417,.01111*
20,1,.006,.05417,.01111,.0507,.01666,0.0*
1,1,.006,.0507,.01666*
20,1,.006,.0507,.01666,.04653,.01944,0.0*
1,1,.006,.04653,.01944*
20,1,.006,.04653,.01944,.04167,.02083,0.0*
1,1,.006,.04167,.02083*
20,1,.006,.04167,.02083,.03612,.01944,0.0*
1,1,.006,.03612,.01944*
20,1,.006,.03612,.01944,.03196,.01666,0.0*
1,1,.006,.03196,.01666*
20,1,.006,.03196,.01666,.02918,.0125,0.0*
1,1,.006,.02918,.0125*
20,1,.006,.02918,.0125,.02779,.00695,0.0*
1,1,.006,.02779,.00695*
20,1,.006,.02779,.00695,.02918,.00209,0.0*
1,1,.006,.02918,.00209*
20,1,.006,.02918,.00209,.03265,-.00277,0.0*
1,1,.006,.03265,-.00277*
20,1,.006,.03265,-.00277,.03682,-.00555,0.0*
1,1,.006,.03682,-.00555*
20,1,.006,.03682,-.00555,.04167,-.00624,0.0*
1,1,.006,.04167,-.00624*
20,1,.006,.04167,-.00624,.04723,-.00486,0.0*
1,1,.006,.04723,-.00486*
20,1,.006,.04723,-.00486,.05139,-.00138,0.0*
1,1,.006,.05139,-.00138*
20,1,.006,.05139,-.00138,.05556,.00486,0.0*
1,1,.006,.05556,.00486*
%
%ADD14MACRO14*%
%AMMACRO26*
1,1,.006,-.167,-.0835*
20,1,.006,-.167,-.0835,-.167,.0835,0.0*
1,1,.006,-.167,.0835*
20,1,.006,-.167,.0835,-.2004,.0501,0.0*
1,1,.006,-.2004,.0501*
1,1,.006,-.2004,-.0835*
20,1,.006,-.2004,-.0835,-.1336,-.0835,0.0*
1,1,.006,-.1336,-.0835*
1,1,.006,-.05287,-.01392*
20,1,.006,-.05287,-.01392,-.03339,.00557,0.0*
1,1,.006,-.03339,.00557*
20,1,.006,-.03339,.00557,-.01669,.0167,0.0*
1,1,.006,-.01669,.0167*
20,1,.006,-.01669,.0167,.00558,.02226,0.0*
1,1,.006,.00558,.02226*
20,1,.006,.00558,.02226,.02506,.0167,0.0*
1,1,.006,.02506,.0167*
20,1,.006,.02506,.0167,.03898,.00557,0.0*
1,1,.006,.03898,.00557*
20,1,.006,.03898,.00557,.05011,-.01113,0.0*
1,1,.006,.05011,-.01113*
20,1,.006,.05011,-.01113,.05289,-.03062,0.0*
1,1,.006,.05289,-.03062*
20,1,.006,.05289,-.03062,.05011,-.04732,0.0*
1,1,.006,.05011,-.04732*
20,1,.006,.05011,-.04732,.03898,-.06402,0.0*
1,1,.006,.03898,-.06402*
20,1,.006,.03898,-.06402,.02227,-.07793,0.0*
1,1,.006,.02227,-.07793*
20,1,.006,.02227,-.07793,.0028,-.0835,0.0*
1,1,.006,.0028,-.0835*
20,1,.006,.0028,-.0835,-.01947,-.07793,0.0*
1,1,.006,-.01947,-.07793*
20,1,.006,-.01947,-.07793,-.03896,-.06124,0.0*
1,1,.006,-.03896,-.06124*
20,1,.006,-.03896,-.06124,-.05009,-.03618,0.0*
1,1,.006,-.05009,-.03618*
20,1,.006,-.05009,-.03618,-.05287,-.00835,0.0*
1,1,.006,-.05287,-.00835*
20,1,.006,-.05287,-.00835,-.04731,.02783,0.0*
1,1,.006,-.04731,.02783*
20,1,.006,-.04731,.02783,-.03896,.04732,0.0*
1,1,.006,-.03896,.04732*
20,1,.006,-.03896,.04732,-.02504,.0668,0.0*
1,1,.006,-.02504,.0668*
20,1,.006,-.02504,.0668,-.00556,.08072,0.0*
1,1,.006,-.00556,.08072*
20,1,.006,-.00556,.08072,.01393,.0835,0.0*
1,1,.006,.01393,.0835*
20,1,.006,.01393,.0835,.03341,.07793,0.0*
1,1,.006,.03341,.07793*
20,1,.006,.03341,.07793,.04733,.06402,0.0*
1,1,.006,.04733,.06402*
1,1,.006,.16145,-.0835*
20,1,.006,.16145,-.0835,.16702,-.04732,0.0*
1,1,.006,.16702,-.04732*
20,1,.006,.16702,-.04732,.17537,-.0167,0.0*
1,1,.006,.17537,-.0167*
20,1,.006,.17537,-.0167,.1865,.01113,0.0*
1,1,.006,.1865,.01113*
20,1,.006,.1865,.01113,.20042,.04175,0.0*
1,1,.006,.20042,.04175*
20,1,.006,.20042,.04175,.22269,.0835,0.0*
1,1,.006,.22269,.0835*
20,1,.006,.22269,.0835,.11135,.0835,0.0*
1,1,.006,.11135,.0835*
%
%ADD26MACRO26*%
%AMMACRO11*
1,1,.006,.035,0.0*
20,1,.006,.035,0.0,.034468,-.006078,0.0*
1,1,.006,.034468,-.006078*
20,1,.006,.034468,-.006078,.032889,-.011971,0.0*
1,1,.006,.032889,-.011971*
20,1,.006,.032889,-.011971,.030311,-.0175,0.0*
1,1,.006,.030311,-.0175*
20,1,.006,.030311,-.0175,.026812,-.022498,0.0*
1,1,.006,.026812,-.022498*
20,1,.006,.026812,-.022498,.022498,-.026812,0.0*
1,1,.006,.022498,-.026812*
20,1,.006,.022498,-.026812,.0175,-.030311,0.0*
1,1,.006,.0175,-.030311*
20,1,.006,.0175,-.030311,.011971,-.032889,0.0*
1,1,.006,.011971,-.032889*
20,1,.006,.011971,-.032889,.006078,-.034468,0.0*
1,1,.006,.006078,-.034468*
20,1,.006,.006078,-.034468,0.0,-.035,0.0*
1,1,.006,0.0,-.035*
20,1,.006,0.0,-.035,-.006078,-.034468,0.0*
1,1,.006,-.006078,-.034468*
20,1,.006,-.006078,-.034468,-.011971,-.032889,0.0*
1,1,.006,-.011971,-.032889*
20,1,.006,-.011971,-.032889,-.0175,-.030311,0.0*
1,1,.006,-.0175,-.030311*
20,1,.006,-.0175,-.030311,-.022498,-.026812,0.0*
1,1,.006,-.022498,-.026812*
20,1,.006,-.022498,-.026812,-.026812,-.022498,0.0*
1,1,.006,-.026812,-.022498*
20,1,.006,-.026812,-.022498,-.030311,-.0175,0.0*
1,1,.006,-.030311,-.0175*
20,1,.006,-.030311,-.0175,-.032889,-.011971,0.0*
1,1,.006,-.032889,-.011971*
20,1,.006,-.032889,-.011971,-.034468,-.006078,0.0*
1,1,.006,-.034468,-.006078*
20,1,.006,-.034468,-.006078,-.035,0.0,0.0*
1,1,.006,-.035,0.0*
20,1,.006,-.035,0.0,-.034468,.006078,0.0*
1,1,.006,-.034468,.006078*
20,1,.006,-.034468,.006078,-.032889,.011971,0.0*
1,1,.006,-.032889,.011971*
20,1,.006,-.032889,.011971,-.030311,.0175,0.0*
1,1,.006,-.030311,.0175*
20,1,.006,-.030311,.0175,-.026812,.022498,0.0*
1,1,.006,-.026812,.022498*
20,1,.006,-.026812,.022498,-.022498,.026812,0.0*
1,1,.006,-.022498,.026812*
20,1,.006,-.022498,.026812,-.0175,.030311,0.0*
1,1,.006,-.0175,.030311*
20,1,.006,-.0175,.030311,-.011971,.032889,0.0*
1,1,.006,-.011971,.032889*
20,1,.006,-.011971,.032889,-.006078,.034468,0.0*
1,1,.006,-.006078,.034468*
20,1,.006,-.006078,.034468,0.0,.035,0.0*
1,1,.006,0.0,.035*
20,1,.006,0.0,.035,.006078,.034468,0.0*
1,1,.006,.006078,.034468*
20,1,.006,.006078,.034468,.011971,.032889,0.0*
1,1,.006,.011971,.032889*
20,1,.006,.011971,.032889,.0175,.030311,0.0*
1,1,.006,.0175,.030311*
20,1,.006,.0175,.030311,.022498,.026812,0.0*
1,1,.006,.022498,.026812*
20,1,.006,.022498,.026812,.026812,.022498,0.0*
1,1,.006,.026812,.022498*
20,1,.006,.026812,.022498,.030311,.0175,0.0*
1,1,.006,.030311,.0175*
20,1,.006,.030311,.0175,.032889,.011971,0.0*
1,1,.006,.032889,.011971*
20,1,.006,.032889,.011971,.034468,.006078,0.0*
1,1,.006,.034468,.006078*
20,1,.006,.034468,.006078,.035,0.0,0.0*
1,1,.006,.035,0.0*
1,1,.006,-.0295,.01041*
20,1,.006,-.0295,.01041,-.02082,-.01041,0.0*
1,1,.006,-.02082,-.01041*
20,1,.006,-.02082,-.01041,-.01214,.01041,0.0*
1,1,.006,-.01214,.01041*
1,1,.006,.00001,-.01041*
20,1,.006,.00001,-.01041,.00001,.01041,0.0*
1,1,.006,.00001,.01041*
20,1,.006,.00001,.01041,-.00415,.00625,0.0*
1,1,.006,-.00415,.00625*
1,1,.006,-.00415,-.01041*
20,1,.006,-.00415,-.01041,.00417,-.01041,0.0*
1,1,.006,.00417,-.01041*
1,1,.006,.02084,.01041*
20,1,.006,.02084,.01041,.01806,.00972,0.0*
1,1,.006,.01806,.00972*
20,1,.006,.01806,.00972,.01598,.00798,0.0*
1,1,.006,.01598,.00798*
20,1,.006,.01598,.00798,.01459,.0059,0.0*
1,1,.006,.01459,.0059*
20,1,.006,.01459,.0059,.01355,.00312,0.0*
1,1,.006,.01355,.00312*
20,1,.006,.01355,.00312,.01321,0.0,0.0*
1,1,.006,.01321,0.0*
20,1,.006,.01321,0.0,.01355,-.00312,0.0*
1,1,.006,.01355,-.00312*
20,1,.006,.01355,-.00312,.01459,-.0059,0.0*
1,1,.006,.01459,-.0059*
20,1,.006,.01459,-.0059,.01598,-.00798,0.0*
1,1,.006,.01598,-.00798*
20,1,.006,.01598,-.00798,.01806,-.00972,0.0*
1,1,.006,.01806,-.00972*
20,1,.006,.01806,-.00972,.02084,-.01041,0.0*
1,1,.006,.02084,-.01041*
20,1,.006,.02084,-.01041,.02362,-.00972,0.0*
1,1,.006,.02362,-.00972*
20,1,.006,.02362,-.00972,.0257,-.00798,0.0*
1,1,.006,.0257,-.00798*
20,1,.006,.0257,-.00798,.02709,-.0059,0.0*
1,1,.006,.02709,-.0059*
20,1,.006,.02709,-.0059,.02813,-.00312,0.0*
1,1,.006,.02813,-.00312*
20,1,.006,.02813,-.00312,.02847,0.0,0.0*
1,1,.006,.02847,0.0*
20,1,.006,.02847,0.0,.02813,.00312,0.0*
1,1,.006,.02813,.00312*
20,1,.006,.02813,.00312,.02709,.0059,0.0*
1,1,.006,.02709,.0059*
20,1,.006,.02709,.0059,.0257,.00798,0.0*
1,1,.006,.0257,.00798*
20,1,.006,.0257,.00798,.02362,.00972,0.0*
1,1,.006,.02362,.00972*
20,1,.006,.02362,.00972,.02084,.01041,0.0*
1,1,.006,.02084,.01041*
%
%ADD11MACRO11*%
%ADD10C,.125*%
%AMMACRO16*
1,1,.006,.079,0.0*
20,1,.006,.079,0.0,.0395,.068416,0.0*
1,1,.006,.0395,.068416*
20,1,.006,.0395,.068416,-.0395,.068416,0.0*
1,1,.006,-.0395,.068416*
20,1,.006,-.0395,.068416,-.079,0.0,0.0*
1,1,.006,-.079,0.0*
20,1,.006,-.079,0.0,-.0395,-.068416,0.0*
1,1,.006,-.0395,-.068416*
20,1,.006,-.0395,-.068416,.0395,-.068416,0.0*
1,1,.006,.0395,-.068416*
20,1,.006,.0395,-.068416,.079,0.0,0.0*
1,1,.006,.079,0.0*
1,1,.006,-.02709,-.03225*
20,1,.006,-.02709,-.03225,-.02709,.00646,0.0*
1,1,.006,-.02709,.00646*
1,1,.006,-.02709,.00065*
20,1,.006,-.02709,.00065,-.03032,.00388,0.0*
1,1,.006,-.03032,.00388*
20,1,.006,-.03032,.00388,-.03419,.00581,0.0*
1,1,.006,-.03419,.00581*
20,1,.006,-.03419,.00581,-.03871,.00646,0.0*
1,1,.006,-.03871,.00646*
20,1,.006,-.03871,.00646,-.04258,.00581,0.0*
1,1,.006,-.04258,.00581*
20,1,.006,-.04258,.00581,-.04709,.00259,0.0*
1,1,.006,-.04709,.00259*
20,1,.006,-.04709,.00259,-.04967,-.00193,0.0*
1,1,.006,-.04967,-.00193*
20,1,.006,-.04967,-.00193,-.05032,-.00645,0.0*
1,1,.006,-.05032,-.00645*
20,1,.006,-.05032,-.00645,-.04967,-.01096,0.0*
1,1,.006,-.04967,-.01096*
20,1,.006,-.04967,-.01096,-.04709,-.01548,0.0*
1,1,.006,-.04709,-.01548*
20,1,.006,-.04709,-.01548,-.04258,-.0187,0.0*
1,1,.006,-.04258,-.0187*
20,1,.006,-.04258,-.0187,-.03871,-.01935,0.0*
1,1,.006,-.03871,-.01935*
20,1,.006,-.03871,-.01935,-.03419,-.0187,0.0*
1,1,.006,-.03419,-.0187*
20,1,.006,-.03419,-.0187,-.03032,-.01677,0.0*
1,1,.006,-.03032,-.01677*
20,1,.006,-.03032,-.01677,-.02709,-.01354,0.0*
1,1,.006,-.02709,-.01354*
1,1,.006,.00001,.01936*
20,1,.006,.00001,.01936,.00001,-.01935,0.0*
1,1,.006,.00001,-.01935*
1,1,.006,-.00902,.00646*
20,1,.006,-.00902,.00646,.00905,.00646,0.0*
1,1,.006,.00905,.00646*
1,1,.006,.03873,.00646*
20,1,.006,.03873,.00646,.03873,-.01935,0.0*
1,1,.006,.03873,-.01935*
1,1,.006,.03873,.01678*
20,1,.006,.03873,.01678,.03744,.01742,0.0*
1,1,.006,.03744,.01742*
20,1,.006,.03744,.01742,.03744,.01871,0.0*
1,1,.006,.03744,.01871*
20,1,.006,.03744,.01871,.03873,.01936,0.0*
1,1,.006,.03873,.01936*
20,1,.006,.03873,.01936,.04003,.01871,0.0*
1,1,.006,.04003,.01871*
20,1,.006,.04003,.01871,.04003,.01742,0.0*
1,1,.006,.04003,.01742*
20,1,.006,.04003,.01742,.03873,.01678,0.0*
1,1,.006,.03873,.01678*
%
%ADD16MACRO16*%
%AMMACRO20*
1,1,.006,.0625,0.0*
20,1,.006,.0625,0.0,.03125,.054127,0.0*
1,1,.006,.03125,.054127*
20,1,.006,.03125,.054127,-.03125,.054127,0.0*
1,1,.006,-.03125,.054127*
20,1,.006,-.03125,.054127,-.0625,0.0,0.0*
1,1,.006,-.0625,0.0*
20,1,.006,-.0625,0.0,-.03125,-.054127,0.0*
1,1,.006,-.03125,-.054127*
20,1,.006,-.03125,-.054127,.03125,-.054127,0.0*
1,1,.006,.03125,-.054127*
20,1,.006,.03125,-.054127,.0625,0.0,0.0*
1,1,.006,.0625,0.0*
1,1,.006,-.02143,-.02552*
20,1,.006,-.02143,-.02552,-.02143,.0051,0.0*
1,1,.006,-.02143,.0051*
1,1,.006,-.02143,.00051*
20,1,.006,-.02143,.00051,-.02399,.00306,0.0*
1,1,.006,-.02399,.00306*
20,1,.006,-.02399,.00306,-.02705,.00459,0.0*
1,1,.006,-.02705,.00459*
20,1,.006,-.02705,.00459,-.03062,.0051,0.0*
1,1,.006,-.03062,.0051*
20,1,.006,-.03062,.0051,-.03368,.00459,0.0*
1,1,.006,-.03368,.00459*
20,1,.006,-.03368,.00459,-.03725,.00204,0.0*
1,1,.006,-.03725,.00204*
20,1,.006,-.03725,.00204,-.0393,-.00153,0.0*
1,1,.006,-.0393,-.00153*
20,1,.006,-.0393,-.00153,-.03981,-.0051,0.0*
1,1,.006,-.03981,-.0051*
20,1,.006,-.03981,-.0051,-.0393,-.00868,0.0*
1,1,.006,-.0393,-.00868*
20,1,.006,-.0393,-.00868,-.03725,-.01225,0.0*
1,1,.006,-.03725,-.01225*
20,1,.006,-.03725,-.01225,-.03368,-.0148,0.0*
1,1,.006,-.03368,-.0148*
20,1,.006,-.03368,-.0148,-.03062,-.01531,0.0*
1,1,.006,-.03062,-.01531*
20,1,.006,-.03062,-.01531,-.02705,-.0148,0.0*
1,1,.006,-.02705,-.0148*
20,1,.006,-.02705,-.0148,-.02399,-.01327,0.0*
1,1,.006,-.02399,-.01327*
20,1,.006,-.02399,-.01327,-.02143,-.01072,0.0*
1,1,.006,-.02143,-.01072*
1,1,.006,-.01275,.0051*
20,1,.006,-.01275,.0051,-.00662,-.01531,0.0*
1,1,.006,-.00662,-.01531*
20,1,.006,-.00662,-.01531,.00001,.0051,0.0*
1,1,.006,.00001,.0051*
20,1,.006,.00001,.0051,.00664,-.01531,0.0*
1,1,.006,.00664,-.01531*
20,1,.006,.00664,-.01531,.01277,.0051,0.0*
1,1,.006,.01277,.0051*
1,1,.006,.03064,.01531*
20,1,.006,.03064,.01531,.03064,-.01531,0.0*
1,1,.006,.03064,-.01531*
1,1,.006,.0235,.0051*
20,1,.006,.0235,.0051,.03778,.0051,0.0*
1,1,.006,.03778,.0051*
%
%ADD20MACRO20*%
%AMMACRO25*
1,1,.006,.063,0.0*
20,1,.006,.063,0.0,.0315,.05456,0.0*
1,1,.006,.0315,.05456*
20,1,.006,.0315,.05456,-.0315,.05456,0.0*
1,1,.006,-.0315,.05456*
20,1,.006,-.0315,.05456,-.063,0.0,0.0*
1,1,.006,-.063,0.0*
20,1,.006,-.063,0.0,-.0315,-.05456,0.0*
1,1,.006,-.0315,-.05456*
20,1,.006,-.0315,-.05456,.0315,-.05456,0.0*
1,1,.006,.0315,-.05456*
20,1,.006,.0315,-.05456,.063,0.0,0.0*
1,1,.006,.063,0.0*
1,1,.006,-.0216,-.02572*
20,1,.006,-.0216,-.02572,-.0216,.00515,0.0*
1,1,.006,-.0216,.00515*
1,1,.006,-.0216,.00052*
20,1,.006,-.0216,.00052,-.02418,.00309,0.0*
1,1,.006,-.02418,.00309*
20,1,.006,-.02418,.00309,-.02726,.00463,0.0*
1,1,.006,-.02726,.00463*
20,1,.006,-.02726,.00463,-.03087,.00515,0.0*
1,1,.006,-.03087,.00515*
20,1,.006,-.03087,.00515,-.03395,.00463,0.0*
1,1,.006,-.03395,.00463*
20,1,.006,-.03395,.00463,-.03755,.00206,0.0*
1,1,.006,-.03755,.00206*
20,1,.006,-.03755,.00206,-.03961,-.00154,0.0*
1,1,.006,-.03961,-.00154*
20,1,.006,-.03961,-.00154,-.04013,-.00514,0.0*
1,1,.006,-.04013,-.00514*
20,1,.006,-.04013,-.00514,-.03961,-.00874,0.0*
1,1,.006,-.03961,-.00874*
20,1,.006,-.03961,-.00874,-.03755,-.01234,0.0*
1,1,.006,-.03755,-.01234*
20,1,.006,-.03755,-.01234,-.03395,-.01492,0.0*
1,1,.006,-.03395,-.01492*
20,1,.006,-.03395,-.01492,-.03087,-.01543,0.0*
1,1,.006,-.03087,-.01543*
20,1,.006,-.03087,-.01543,-.02726,-.01492,0.0*
1,1,.006,-.02726,-.01492*
20,1,.006,-.02726,-.01492,-.02418,-.01337,0.0*
1,1,.006,-.02418,-.01337*
20,1,.006,-.02418,-.01337,-.0216,-.0108,0.0*
1,1,.006,-.0216,-.0108*
1,1,.006,-.01285,.00515*
20,1,.006,-.01285,.00515,-.00667,-.01543,0.0*
1,1,.006,-.00667,-.01543*
20,1,.006,-.00667,-.01543,.00001,.00515,0.0*
1,1,.006,.00001,.00515*
20,1,.006,.00001,.00515,.0067,-.01543,0.0*
1,1,.006,.0067,-.01543*
20,1,.006,.0067,-.01543,.01288,.00515,0.0*
1,1,.006,.01288,.00515*
1,1,.006,.02009,-.02469*
20,1,.006,.02009,-.02469,.02318,-.02572,0.0*
1,1,.006,.02318,-.02572*
20,1,.006,.02318,-.02572,.02729,-.02469,0.0*
1,1,.006,.02729,-.02469*
20,1,.006,.02729,-.02469,.02987,-.02263,0.0*
1,1,.006,.02987,-.02263*
20,1,.006,.02987,-.02263,.03192,-.02006,0.0*
1,1,.006,.03192,-.02006*
20,1,.006,.03192,-.02006,.03501,-.01183,0.0*
1,1,.006,.03501,-.01183*
20,1,.006,.03501,-.01183,.0417,.00515,0.0*
1,1,.006,.0417,.00515*
1,1,.006,.02524,.00515*
20,1,.006,.02524,.00515,.03501,-.01183,0.0*
1,1,.006,.03501,-.01183*
%
%ADD25MACRO25*%
%AMMACRO30*
1,1,.006,0.0,.035*
20,1,.006,0.0,.035,.030311,-.0175,0.0*
1,1,.006,.030311,-.0175*
20,1,.006,.030311,-.0175,-.030311,-.0175,0.0*
1,1,.006,-.030311,-.0175*
20,1,.006,-.030311,-.0175,0.0,.035,0.0*
1,1,.006,0.0,.035*
1,1,.006,-.01102,.00551*
20,1,.006,-.01102,.00551,-.01249,.00514,0.0*
1,1,.006,-.01249,.00514*
20,1,.006,-.01249,.00514,-.01359,.00422,0.0*
1,1,.006,-.01359,.00422*
20,1,.006,-.01359,.00422,-.01433,.00312,0.0*
1,1,.006,-.01433,.00312*
20,1,.006,-.01433,.00312,-.01488,.00165,0.0*
1,1,.006,-.01488,.00165*
20,1,.006,-.01488,.00165,-.01506,0.0,0.0*
1,1,.006,-.01506,0.0*
20,1,.006,-.01506,0.0,-.01488,-.00165,0.0*
1,1,.006,-.01488,-.00165*
20,1,.006,-.01488,-.00165,-.01433,-.00312,0.0*
1,1,.006,-.01433,-.00312*
20,1,.006,-.01433,-.00312,-.01359,-.00422,0.0*
1,1,.006,-.01359,-.00422*
20,1,.006,-.01359,-.00422,-.01249,-.00514,0.0*
1,1,.006,-.01249,-.00514*
20,1,.006,-.01249,-.00514,-.01102,-.00551,0.0*
1,1,.006,-.01102,-.00551*
20,1,.006,-.01102,-.00551,-.00955,-.00514,0.0*
1,1,.006,-.00955,-.00514*
20,1,.006,-.00955,-.00514,-.00845,-.00422,0.0*
1,1,.006,-.00845,-.00422*
20,1,.006,-.00845,-.00422,-.00771,-.00312,0.0*
1,1,.006,-.00771,-.00312*
20,1,.006,-.00771,-.00312,-.00716,-.00165,0.0*
1,1,.006,-.00716,-.00165*
20,1,.006,-.00716,-.00165,-.00698,0.0,0.0*
1,1,.006,-.00698,0.0*
20,1,.006,-.00698,0.0,-.00716,.00165,0.0*
1,1,.006,-.00716,.00165*
20,1,.006,-.00716,.00165,-.00771,.00312,0.0*
1,1,.006,-.00771,.00312*
20,1,.006,-.00771,.00312,-.00845,.00422,0.0*
1,1,.006,-.00845,.00422*
20,1,.006,-.00845,.00422,-.00955,.00514,0.0*
1,1,.006,-.00955,.00514*
20,1,.006,-.00955,.00514,-.01102,.00551,0.0*
1,1,.006,-.01102,.00551*
1,1,.006,.00221,-.00551*
20,1,.006,.00221,-.00551,.00221,.00551,0.0*
1,1,.006,.00221,.00551*
20,1,.006,.00221,.00551,-.00458,-.00239,0.0*
1,1,.006,-.00458,-.00239*
20,1,.006,-.00458,-.00239,.0046,-.00239,0.0*
1,1,.006,.0046,-.00239*
1,1,.006,.01104,-.00551*
20,1,.006,.01104,-.00551,.01104,.00551,0.0*
1,1,.006,.01104,.00551*
20,1,.006,.01104,.00551,.00884,.00331,0.0*
1,1,.006,.00884,.00331*
1,1,.006,.00884,-.00551*
20,1,.006,.00884,-.00551,.01324,-.00551,0.0*
1,1,.006,.01324,-.00551*
%
%ADD30MACRO30*%
%AMMACRO19*
1,1,.006,0.0,.035*
20,1,.006,0.0,.035,.030311,-.0175,0.0*
1,1,.006,.030311,-.0175*
20,1,.006,.030311,-.0175,-.030311,-.0175,0.0*
1,1,.006,-.030311,-.0175*
20,1,.006,-.030311,-.0175,0.0,.035,0.0*
1,1,.006,0.0,.035*
1,1,.006,-.01102,.00551*
20,1,.006,-.01102,.00551,-.01249,.00514,0.0*
1,1,.006,-.01249,.00514*
20,1,.006,-.01249,.00514,-.01359,.00422,0.0*
1,1,.006,-.01359,.00422*
20,1,.006,-.01359,.00422,-.01433,.00312,0.0*
1,1,.006,-.01433,.00312*
20,1,.006,-.01433,.00312,-.01488,.00165,0.0*
1,1,.006,-.01488,.00165*
20,1,.006,-.01488,.00165,-.01506,0.0,0.0*
1,1,.006,-.01506,0.0*
20,1,.006,-.01506,0.0,-.01488,-.00165,0.0*
1,1,.006,-.01488,-.00165*
20,1,.006,-.01488,-.00165,-.01433,-.00312,0.0*
1,1,.006,-.01433,-.00312*
20,1,.006,-.01433,-.00312,-.01359,-.00422,0.0*
1,1,.006,-.01359,-.00422*
20,1,.006,-.01359,-.00422,-.01249,-.00514,0.0*
1,1,.006,-.01249,-.00514*
20,1,.006,-.01249,-.00514,-.01102,-.00551,0.0*
1,1,.006,-.01102,-.00551*
20,1,.006,-.01102,-.00551,-.00955,-.00514,0.0*
1,1,.006,-.00955,-.00514*
20,1,.006,-.00955,-.00514,-.00845,-.00422,0.0*
1,1,.006,-.00845,-.00422*
20,1,.006,-.00845,-.00422,-.00771,-.00312,0.0*
1,1,.006,-.00771,-.00312*
20,1,.006,-.00771,-.00312,-.00716,-.00165,0.0*
1,1,.006,-.00716,-.00165*
20,1,.006,-.00716,-.00165,-.00698,0.0,0.0*
1,1,.006,-.00698,0.0*
20,1,.006,-.00698,0.0,-.00716,.00165,0.0*
1,1,.006,-.00716,.00165*
20,1,.006,-.00716,.00165,-.00771,.00312,0.0*
1,1,.006,-.00771,.00312*
20,1,.006,-.00771,.00312,-.00845,.00422,0.0*
1,1,.006,-.00845,.00422*
20,1,.006,-.00845,.00422,-.00955,.00514,0.0*
1,1,.006,-.00955,.00514*
20,1,.006,-.00955,.00514,-.01102,.00551,0.0*
1,1,.006,-.01102,.00551*
1,1,.006,-.00403,-.00386*
20,1,.006,-.00403,-.00386,-.00293,-.00478,0.0*
1,1,.006,-.00293,-.00478*
20,1,.006,-.00293,-.00478,-.00164,-.00533,0.0*
1,1,.006,-.00164,-.00533*
20,1,.006,-.00164,-.00533,.00001,-.00551,0.0*
1,1,.006,.00001,-.00551*
20,1,.006,.00001,-.00551,.00166,-.00514,0.0*
1,1,.006,.00166,-.00514*
20,1,.006,.00166,-.00514,.00295,-.00441,0.0*
1,1,.006,.00295,-.00441*
20,1,.006,.00295,-.00441,.00387,-.00312,0.0*
1,1,.006,.00387,-.00312*
20,1,.006,.00387,-.00312,.00405,-.00165,0.0*
1,1,.006,.00405,-.00165*
20,1,.006,.00405,-.00165,.00368,-.00018,0.0*
1,1,.006,.00368,-.00018*
20,1,.006,.00368,-.00018,.00276,.00073,0.0*
1,1,.006,.00276,.00073*
20,1,.006,.00276,.00073,.00148,.00147,0.0*
1,1,.006,.00148,.00147*
20,1,.006,.00148,.00147,.00019,.00165,0.0*
1,1,.006,.00019,.00165*
20,1,.006,.00019,.00165,-.00109,.00147,0.0*
1,1,.006,-.00109,.00147*
20,1,.006,-.00109,.00147,-.00274,.00073,0.0*
1,1,.006,-.00274,.00073*
20,1,.006,-.00274,.00073,-.00219,.00551,0.0*
1,1,.006,-.00219,.00551*
20,1,.006,-.00219,.00551,.00276,.00551,0.0*
1,1,.006,.00276,.00551*
1,1,.006,.01104,.00551*
20,1,.006,.01104,.00551,.00957,.00514,0.0*
1,1,.006,.00957,.00514*
20,1,.006,.00957,.00514,.00847,.00422,0.0*
1,1,.006,.00847,.00422*
20,1,.006,.00847,.00422,.00773,.00312,0.0*
1,1,.006,.00773,.00312*
20,1,.006,.00773,.00312,.00718,.00165,0.0*
1,1,.006,.00718,.00165*
20,1,.006,.00718,.00165,.007,0.0,0.0*
1,1,.006,.007,0.0*
20,1,.006,.007,0.0,.00718,-.00165,0.0*
1,1,.006,.00718,-.00165*
20,1,.006,.00718,-.00165,.00773,-.00312,0.0*
1,1,.006,.00773,-.00312*
20,1,.006,.00773,-.00312,.00847,-.00422,0.0*
1,1,.006,.00847,-.00422*
20,1,.006,.00847,-.00422,.00957,-.00514,0.0*
1,1,.006,.00957,-.00514*
20,1,.006,.00957,-.00514,.01104,-.00551,0.0*
1,1,.006,.01104,-.00551*
20,1,.006,.01104,-.00551,.01251,-.00514,0.0*
1,1,.006,.01251,-.00514*
20,1,.006,.01251,-.00514,.01361,-.00422,0.0*
1,1,.006,.01361,-.00422*
20,1,.006,.01361,-.00422,.01435,-.00312,0.0*
1,1,.006,.01435,-.00312*
20,1,.006,.01435,-.00312,.0149,-.00165,0.0*
1,1,.006,.0149,-.00165*
20,1,.006,.0149,-.00165,.01508,0.0,0.0*
1,1,.006,.01508,0.0*
20,1,.006,.01508,0.0,.0149,.00165,0.0*
1,1,.006,.0149,.00165*
20,1,.006,.0149,.00165,.01435,.00312,0.0*
1,1,.006,.01435,.00312*
20,1,.006,.01435,.00312,.01361,.00422,0.0*
1,1,.006,.01361,.00422*
20,1,.006,.01361,.00422,.01251,.00514,0.0*
1,1,.006,.01251,.00514*
20,1,.006,.01251,.00514,.01104,.00551,0.0*
1,1,.006,.01104,.00551*
%
%ADD19MACRO19*%
%AMMACRO27*
1,1,.006,0.0,.035*
20,1,.006,0.0,.035,.030311,-.0175,0.0*
1,1,.006,.030311,-.0175*
20,1,.006,.030311,-.0175,-.030311,-.0175,0.0*
1,1,.006,-.030311,-.0175*
20,1,.006,-.030311,-.0175,0.0,.035,0.0*
1,1,.006,0.0,.035*
1,1,.006,-.01102,.00551*
20,1,.006,-.01102,.00551,-.01249,.00514,0.0*
1,1,.006,-.01249,.00514*
20,1,.006,-.01249,.00514,-.01359,.00422,0.0*
1,1,.006,-.01359,.00422*
20,1,.006,-.01359,.00422,-.01433,.00312,0.0*
1,1,.006,-.01433,.00312*
20,1,.006,-.01433,.00312,-.01488,.00165,0.0*
1,1,.006,-.01488,.00165*
20,1,.006,-.01488,.00165,-.01506,0.0,0.0*
1,1,.006,-.01506,0.0*
20,1,.006,-.01506,0.0,-.01488,-.00165,0.0*
1,1,.006,-.01488,-.00165*
20,1,.006,-.01488,-.00165,-.01433,-.00312,0.0*
1,1,.006,-.01433,-.00312*
20,1,.006,-.01433,-.00312,-.01359,-.00422,0.0*
1,1,.006,-.01359,-.00422*
20,1,.006,-.01359,-.00422,-.01249,-.00514,0.0*
1,1,.006,-.01249,-.00514*
20,1,.006,-.01249,-.00514,-.01102,-.00551,0.0*
1,1,.006,-.01102,-.00551*
20,1,.006,-.01102,-.00551,-.00955,-.00514,0.0*
1,1,.006,-.00955,-.00514*
20,1,.006,-.00955,-.00514,-.00845,-.00422,0.0*
1,1,.006,-.00845,-.00422*
20,1,.006,-.00845,-.00422,-.00771,-.00312,0.0*
1,1,.006,-.00771,-.00312*
20,1,.006,-.00771,-.00312,-.00716,-.00165,0.0*
1,1,.006,-.00716,-.00165*
20,1,.006,-.00716,-.00165,-.00698,0.0,0.0*
1,1,.006,-.00698,0.0*
20,1,.006,-.00698,0.0,-.00716,.00165,0.0*
1,1,.006,-.00716,.00165*
20,1,.006,-.00716,.00165,-.00771,.00312,0.0*
1,1,.006,-.00771,.00312*
20,1,.006,-.00771,.00312,-.00845,.00422,0.0*
1,1,.006,-.00845,.00422*
20,1,.006,-.00845,.00422,-.00955,.00514,0.0*
1,1,.006,-.00955,.00514*
20,1,.006,-.00955,.00514,-.01102,.00551,0.0*
1,1,.006,-.01102,.00551*
1,1,.006,.00221,-.00551*
20,1,.006,.00221,-.00551,.00221,.00551,0.0*
1,1,.006,.00221,.00551*
20,1,.006,.00221,.00551,-.00458,-.00239,0.0*
1,1,.006,-.00458,-.00239*
20,1,.006,-.00458,-.00239,.0046,-.00239,0.0*
1,1,.006,.0046,-.00239*
1,1,.006,.00755,-.00092*
20,1,.006,.00755,-.00092,.00884,.00037,0.0*
1,1,.006,.00884,.00037*
20,1,.006,.00884,.00037,.00994,.0011,0.0*
1,1,.006,.00994,.0011*
20,1,.006,.00994,.0011,.01141,.00147,0.0*
1,1,.006,.01141,.00147*
20,1,.006,.01141,.00147,.01269,.0011,0.0*
1,1,.006,.01269,.0011*
20,1,.006,.01269,.0011,.01361,.00037,0.0*
1,1,.006,.01361,.00037*
20,1,.006,.01361,.00037,.01435,-.00073,0.0*
1,1,.006,.01435,-.00073*
20,1,.006,.01435,-.00073,.01453,-.00202,0.0*
1,1,.006,.01453,-.00202*
20,1,.006,.01453,-.00202,.01435,-.00312,0.0*
1,1,.006,.01435,-.00312*
20,1,.006,.01435,-.00312,.01361,-.00422,0.0*
1,1,.006,.01361,-.00422*
20,1,.006,.01361,-.00422,.01251,-.00514,0.0*
1,1,.006,.01251,-.00514*
20,1,.006,.01251,-.00514,.01122,-.00551,0.0*
1,1,.006,.01122,-.00551*
20,1,.006,.01122,-.00551,.00975,-.00514,0.0*
1,1,.006,.00975,-.00514*
20,1,.006,.00975,-.00514,.00847,-.00404,0.0*
1,1,.006,.00847,-.00404*
20,1,.006,.00847,-.00404,.00773,-.00239,0.0*
1,1,.006,.00773,-.00239*
20,1,.006,.00773,-.00239,.00755,-.00055,0.0*
1,1,.006,.00755,-.00055*
20,1,.006,.00755,-.00055,.00792,.00184,0.0*
1,1,.006,.00792,.00184*
20,1,.006,.00792,.00184,.00847,.00312,0.0*
1,1,.006,.00847,.00312*
20,1,.006,.00847,.00312,.00939,.00441,0.0*
1,1,.006,.00939,.00441*
20,1,.006,.00939,.00441,.01067,.00533,0.0*
1,1,.006,.01067,.00533*
20,1,.006,.01067,.00533,.01196,.00551,0.0*
1,1,.006,.01196,.00551*
20,1,.006,.01196,.00551,.01324,.00514,0.0*
1,1,.006,.01324,.00514*
20,1,.006,.01324,.00514,.01416,.00422,0.0*
1,1,.006,.01416,.00422*
%
%ADD27MACRO27*%
%AMMACRO24*
1,1,.006,0.0,.035*
20,1,.006,0.0,.035,.030311,-.0175,0.0*
1,1,.006,.030311,-.0175*
20,1,.006,.030311,-.0175,-.030311,-.0175,0.0*
1,1,.006,-.030311,-.0175*
20,1,.006,-.030311,-.0175,0.0,.035,0.0*
1,1,.006,0.0,.035*
1,1,.006,-.01102,.00551*
20,1,.006,-.01102,.00551,-.01249,.00514,0.0*
1,1,.006,-.01249,.00514*
20,1,.006,-.01249,.00514,-.01359,.00422,0.0*
1,1,.006,-.01359,.00422*
20,1,.006,-.01359,.00422,-.01433,.00312,0.0*
1,1,.006,-.01433,.00312*
20,1,.006,-.01433,.00312,-.01488,.00165,0.0*
1,1,.006,-.01488,.00165*
20,1,.006,-.01488,.00165,-.01506,0.0,0.0*
1,1,.006,-.01506,0.0*
20,1,.006,-.01506,0.0,-.01488,-.00165,0.0*
1,1,.006,-.01488,-.00165*
20,1,.006,-.01488,-.00165,-.01433,-.00312,0.0*
1,1,.006,-.01433,-.00312*
20,1,.006,-.01433,-.00312,-.01359,-.00422,0.0*
1,1,.006,-.01359,-.00422*
20,1,.006,-.01359,-.00422,-.01249,-.00514,0.0*
1,1,.006,-.01249,-.00514*
20,1,.006,-.01249,-.00514,-.01102,-.00551,0.0*
1,1,.006,-.01102,-.00551*
20,1,.006,-.01102,-.00551,-.00955,-.00514,0.0*
1,1,.006,-.00955,-.00514*
20,1,.006,-.00955,-.00514,-.00845,-.00422,0.0*
1,1,.006,-.00845,-.00422*
20,1,.006,-.00845,-.00422,-.00771,-.00312,0.0*
1,1,.006,-.00771,-.00312*
20,1,.006,-.00771,-.00312,-.00716,-.00165,0.0*
1,1,.006,-.00716,-.00165*
20,1,.006,-.00716,-.00165,-.00698,0.0,0.0*
1,1,.006,-.00698,0.0*
20,1,.006,-.00698,0.0,-.00716,.00165,0.0*
1,1,.006,-.00716,.00165*
20,1,.006,-.00716,.00165,-.00771,.00312,0.0*
1,1,.006,-.00771,.00312*
20,1,.006,-.00771,.00312,-.00845,.00422,0.0*
1,1,.006,-.00845,.00422*
20,1,.006,-.00845,.00422,-.00955,.00514,0.0*
1,1,.006,-.00955,.00514*
20,1,.006,-.00955,.00514,-.01102,.00551,0.0*
1,1,.006,-.01102,.00551*
1,1,.006,-.00348,-.00092*
20,1,.006,-.00348,-.00092,-.00219,.00037,0.0*
1,1,.006,-.00219,.00037*
20,1,.006,-.00219,.00037,-.00109,.0011,0.0*
1,1,.006,-.00109,.0011*
20,1,.006,-.00109,.0011,.00038,.00147,0.0*
1,1,.006,.00038,.00147*
20,1,.006,.00038,.00147,.00166,.0011,0.0*
1,1,.006,.00166,.0011*
20,1,.006,.00166,.0011,.00258,.00037,0.0*
1,1,.006,.00258,.00037*
20,1,.006,.00258,.00037,.00332,-.00073,0.0*
1,1,.006,.00332,-.00073*
20,1,.006,.00332,-.00073,.0035,-.00202,0.0*
1,1,.006,.0035,-.00202*
20,1,.006,.0035,-.00202,.00332,-.00312,0.0*
1,1,.006,.00332,-.00312*
20,1,.006,.00332,-.00312,.00258,-.00422,0.0*
1,1,.006,.00258,-.00422*
20,1,.006,.00258,-.00422,.00148,-.00514,0.0*
1,1,.006,.00148,-.00514*
20,1,.006,.00148,-.00514,.00019,-.00551,0.0*
1,1,.006,.00019,-.00551*
20,1,.006,.00019,-.00551,-.00128,-.00514,0.0*
1,1,.006,-.00128,-.00514*
20,1,.006,-.00128,-.00514,-.00256,-.00404,0.0*
1,1,.006,-.00256,-.00404*
20,1,.006,-.00256,-.00404,-.0033,-.00239,0.0*
1,1,.006,-.0033,-.00239*
20,1,.006,-.0033,-.00239,-.00348,-.00055,0.0*
1,1,.006,-.00348,-.00055*
20,1,.006,-.00348,-.00055,-.00311,.00184,0.0*
1,1,.006,-.00311,.00184*
20,1,.006,-.00311,.00184,-.00256,.00312,0.0*
1,1,.006,-.00256,.00312*
20,1,.006,-.00256,.00312,-.00164,.00441,0.0*
1,1,.006,-.00164,.00441*
20,1,.006,-.00164,.00441,-.00036,.00533,0.0*
1,1,.006,-.00036,.00533*
20,1,.006,-.00036,.00533,.00093,.00551,0.0*
1,1,.006,.00093,.00551*
20,1,.006,.00093,.00551,.00221,.00514,0.0*
1,1,.006,.00221,.00514*
20,1,.006,.00221,.00514,.00313,.00422,0.0*
1,1,.006,.00313,.00422*
1,1,.006,.01067,-.00551*
20,1,.006,.01067,-.00551,.01104,-.00312,0.0*
1,1,.006,.01104,-.00312*
20,1,.006,.01104,-.00312,.01159,-.0011,0.0*
1,1,.006,.01159,-.0011*
20,1,.006,.01159,-.0011,.01233,.00073,0.0*
1,1,.006,.01233,.00073*
20,1,.006,.01233,.00073,.01324,.00275,0.0*
1,1,.006,.01324,.00275*
20,1,.006,.01324,.00275,.01471,.00551,0.0*
1,1,.006,.01471,.00551*
20,1,.006,.01471,.00551,.00737,.00551,0.0*
1,1,.006,.00737,.00551*
%
%ADD24MACRO24*%
%AMMACRO29*
1,1,.006,-.0245,.032*
20,1,.006,-.0245,.032,.0245,.032,0.0*
1,1,.006,.0245,.032*
20,1,.006,.0245,.032,.030057,.031514,0.0*
1,1,.006,.030057,.031514*
20,1,.006,.030057,.031514,.035445,.03007,0.0*
1,1,.006,.035445,.03007*
20,1,.006,.035445,.03007,.0405,.027713,0.0*
1,1,.006,.0405,.027713*
20,1,.006,.0405,.027713,.045069,.024513,0.0*
1,1,.006,.045069,.024513*
20,1,.006,.045069,.024513,.049013,.020569,0.0*
1,1,.006,.049013,.020569*
20,1,.006,.049013,.020569,.052213,.016,0.0*
1,1,.006,.052213,.016*
20,1,.006,.052213,.016,.05457,.010945,0.0*
1,1,.006,.05457,.010945*
20,1,.006,.05457,.010945,.056014,.005557,0.0*
1,1,.006,.056014,.005557*
20,1,.006,.056014,.005557,.0565,0.0,0.0*
1,1,.006,.0565,0.0*
20,1,.006,.0565,0.0,.056014,-.005557,0.0*
1,1,.006,.056014,-.005557*
20,1,.006,.056014,-.005557,.05457,-.010945,0.0*
1,1,.006,.05457,-.010945*
20,1,.006,.05457,-.010945,.052213,-.016,0.0*
1,1,.006,.052213,-.016*
20,1,.006,.052213,-.016,.049013,-.020569,0.0*
1,1,.006,.049013,-.020569*
20,1,.006,.049013,-.020569,.045069,-.024513,0.0*
1,1,.006,.045069,-.024513*
20,1,.006,.045069,-.024513,.0405,-.027713,0.0*
1,1,.006,.0405,-.027713*
20,1,.006,.0405,-.027713,.035445,-.03007,0.0*
1,1,.006,.035445,-.03007*
20,1,.006,.035445,-.03007,.030057,-.031514,0.0*
1,1,.006,.030057,-.031514*
20,1,.006,.030057,-.031514,.0245,-.032,0.0*
1,1,.006,.0245,-.032*
20,1,.006,.0245,-.032,-.0245,-.032,0.0*
1,1,.006,-.0245,-.032*
20,1,.006,-.0245,-.032,-.030057,-.031514,0.0*
1,1,.006,-.030057,-.031514*
20,1,.006,-.030057,-.031514,-.035445,-.03007,0.0*
1,1,.006,-.035445,-.03007*
20,1,.006,-.035445,-.03007,-.0405,-.027713,0.0*
1,1,.006,-.0405,-.027713*
20,1,.006,-.0405,-.027713,-.045069,-.024513,0.0*
1,1,.006,-.045069,-.024513*
20,1,.006,-.045069,-.024513,-.049013,-.020569,0.0*
1,1,.006,-.049013,-.020569*
20,1,.006,-.049013,-.020569,-.052213,-.016,0.0*
1,1,.006,-.052213,-.016*
20,1,.006,-.052213,-.016,-.05457,-.010945,0.0*
1,1,.006,-.05457,-.010945*
20,1,.006,-.05457,-.010945,-.056014,-.005557,0.0*
1,1,.006,-.056014,-.005557*
20,1,.006,-.056014,-.005557,-.0565,0.0,0.0*
1,1,.006,-.0565,0.0*
20,1,.006,-.0565,0.0,-.056014,.005557,0.0*
1,1,.006,-.056014,.005557*
20,1,.006,-.056014,.005557,-.05457,.010945,0.0*
1,1,.006,-.05457,.010945*
20,1,.006,-.05457,.010945,-.052213,.016,0.0*
1,1,.006,-.052213,.016*
20,1,.006,-.052213,.016,-.049013,.020569,0.0*
1,1,.006,-.049013,.020569*
20,1,.006,-.049013,.020569,-.045069,.024513,0.0*
1,1,.006,-.045069,.024513*
20,1,.006,-.045069,.024513,-.0405,.027713,0.0*
1,1,.006,-.0405,.027713*
20,1,.006,-.0405,.027713,-.035445,.03007,0.0*
1,1,.006,-.035445,.03007*
20,1,.006,-.035445,.03007,-.030057,.031514,0.0*
1,1,.006,-.030057,.031514*
20,1,.006,-.030057,.031514,-.0245,.032,0.0*
1,1,.006,-.0245,.032*
1,1,.006,-.02875,-.0112*
20,1,.006,-.02875,-.0112,-.02875,.00373,0.0*
1,1,.006,-.02875,.00373*
1,1,.006,-.02875,0.0*
20,1,.006,-.02875,0.0,-.02725,.00187,0.0*
1,1,.006,-.02725,.00187*
20,1,.006,-.02725,.00187,-.02501,.00336,0.0*
1,1,.006,-.02501,.00336*
20,1,.006,-.02501,.00336,-.02203,.00373,0.0*
1,1,.006,-.02203,.00373*
20,1,.006,-.02203,.00373,-.01941,.00336,0.0*
1,1,.006,-.01941,.00336*
20,1,.006,-.01941,.00336,-.01717,.00187,0.0*
1,1,.006,-.01717,.00187*
20,1,.006,-.01717,.00187,-.01605,-.00075,0.0*
1,1,.006,-.01605,-.00075*
20,1,.006,-.01605,-.00075,-.01605,-.0112,0.0*
1,1,.006,-.01605,-.0112*
1,1,.006,-.00671,-.0112*
20,1,.006,-.00671,-.0112,-.00671,.0112,0.0*
1,1,.006,-.00671,.0112*
1,1,.006,-.00671,0.0*
20,1,.006,-.00671,0.0,-.00484,.00224,0.0*
1,1,.006,-.00484,.00224*
20,1,.006,-.00484,.00224,-.0026,.00336,0.0*
1,1,.006,-.0026,.00336*
20,1,.006,-.0026,.00336,-.00036,.00373,0.0*
1,1,.006,-.00036,.00373*
20,1,.006,-.00036,.00373,.003,.00299,0.0*
1,1,.006,.003,.00299*
20,1,.006,.003,.00299,.00524,.00149,0.0*
1,1,.006,.00524,.00149*
20,1,.006,.00524,.00149,.00673,-.00112,0.0*
1,1,.006,.00673,-.00112*
20,1,.006,.00673,-.00112,.00673,-.00411,0.0*
1,1,.006,.00673,-.00411*
20,1,.006,.00673,-.00411,.00598,-.00709,0.0*
1,1,.006,.00598,-.00709*
20,1,.006,.00598,-.00709,.00449,-.00933,0.0*
1,1,.006,.00449,-.00933*
20,1,.006,.00449,-.00933,.00188,-.01083,0.0*
1,1,.006,.00188,-.01083*
20,1,.006,.00188,-.01083,-.00036,-.0112,0.0*
1,1,.006,-.00036,-.0112*
20,1,.006,-.00036,-.0112,-.0026,-.01083,0.0*
1,1,.006,-.0026,-.01083*
20,1,.006,-.0026,-.01083,-.00484,-.00971,0.0*
1,1,.006,-.00484,-.00971*
20,1,.006,-.00484,-.00971,-.00671,-.00784,0.0*
1,1,.006,-.00671,-.00784*
1,1,.006,.01309,.00373*
20,1,.006,.01309,.00373,.01757,-.0112,0.0*
1,1,.006,.01757,-.0112*
20,1,.006,.01757,-.0112,.02242,.00373,0.0*
1,1,.006,.02242,.00373*
20,1,.006,.02242,.00373,.02727,-.0112,0.0*
1,1,.006,.02727,-.0112*
20,1,.006,.02727,-.0112,.03175,.00373,0.0*
1,1,.006,.03175,.00373*
%
%ADD29MACRO29*%
%ADD32C,.006*%
G75*
%LPD*%
G75*
G54D10*
X19685Y-774040D03*
Y766166D03*
X566575Y463701D03*
D03*
D03*
X1854331Y-774040D03*
Y766166D03*
G54D20*
X231600Y81000D03*
X1212478Y300181D03*
X1529100Y78500D03*
X2463384Y73462D03*
G54D11*
X3018Y23930D03*
X10493Y5830D03*
X3018Y43930D03*
Y83930D03*
Y63930D03*
Y103930D03*
Y143930D03*
Y123930D03*
Y163930D03*
Y203930D03*
Y183930D03*
Y223930D03*
Y263930D03*
Y243930D03*
Y283930D03*
Y323930D03*
Y303930D03*
Y343930D03*
Y383930D03*
Y363930D03*
Y403930D03*
Y443930D03*
Y423930D03*
Y463930D03*
Y503930D03*
Y483930D03*
Y523930D03*
Y563930D03*
Y543930D03*
Y583930D03*
X15642Y619715D03*
X3018Y603930D03*
X30709Y3014D03*
X35455Y620194D03*
X75455D03*
X55455D03*
X81406Y3042D03*
X101406D03*
X95455Y620194D03*
X121406Y3042D03*
X114923Y623982D03*
X124901Y640105D03*
X161406Y3042D03*
X141406D03*
X154778Y672779D03*
X181406Y3042D03*
X187600Y106500D03*
X176785Y102000D03*
X194778Y672779D03*
X174778D03*
X201406Y3042D03*
X221406D03*
X205061Y85500D03*
Y79000D03*
Y75000D03*
Y71500D03*
Y89500D03*
Y97000D03*
X225829Y103412D03*
Y99503D03*
X225953Y95780D03*
X225891Y92305D03*
X205100Y123000D03*
X214778Y672779D03*
X229829Y103412D03*
X233329D03*
X237329D03*
X229829Y99503D03*
X233329D03*
X237329D03*
X229953Y95780D03*
X233453D03*
X237453D03*
X229891Y92305D03*
X233391D03*
X237391D03*
X254778Y672779D03*
X234778D03*
X274778D03*
X314766Y39211D03*
X317766D03*
X317000Y74475D03*
Y64500D03*
X311956Y651522D03*
X294778Y672779D03*
X325500Y15000D03*
Y18000D03*
Y21000D03*
X340500D03*
Y18000D03*
Y15000D03*
X337500Y21000D03*
Y18000D03*
Y15000D03*
X334500Y21000D03*
Y18000D03*
Y15000D03*
X331500Y21000D03*
Y18000D03*
Y15000D03*
X328500Y21000D03*
Y18000D03*
Y15000D03*
X323766Y39211D03*
X320766D03*
X321500Y74475D03*
X330500Y74476D03*
X324000Y77000D03*
X321000Y63000D03*
X326000Y74476D03*
X345412Y435017D03*
Y455017D03*
Y475017D03*
Y495017D03*
Y515017D03*
Y535017D03*
Y555017D03*
Y575017D03*
Y595017D03*
X342119Y613510D03*
X331285Y620008D03*
X369192Y38417D03*
X372192D03*
X378192D03*
X375192D03*
X362127Y406608D03*
X350024Y418335D03*
X408100Y180100D03*
Y224500D03*
X399680Y402510D03*
X379680D03*
X428277Y167056D03*
X438100Y170000D03*
X430608Y211389D03*
X438100Y214500D03*
X419680Y402510D03*
X454738Y56000D03*
X451738D03*
X448738D03*
X445738D03*
X442738D03*
X454738Y68000D03*
Y65000D03*
Y62000D03*
Y59000D03*
X451738D03*
Y62000D03*
Y65000D03*
Y68000D03*
X448738Y59000D03*
Y62000D03*
Y65000D03*
Y68000D03*
X445738Y59000D03*
Y62000D03*
Y65000D03*
Y68000D03*
X442738Y59000D03*
Y62000D03*
Y65000D03*
Y68000D03*
X441938Y87700D03*
X454738Y112400D03*
Y109400D03*
Y106400D03*
Y103400D03*
X451738D03*
Y106400D03*
Y109400D03*
Y112400D03*
X448738Y103400D03*
Y106400D03*
Y109400D03*
Y112400D03*
X445738Y103400D03*
Y106400D03*
Y109400D03*
Y112400D03*
X442738Y103400D03*
Y106400D03*
Y109400D03*
Y112400D03*
X454738Y100400D03*
X451738D03*
X448738D03*
X445738D03*
X442738D03*
X454738Y147800D03*
X451738D03*
X448738D03*
X445738D03*
X442738D03*
X454738Y144800D03*
X451738D03*
X448738D03*
X445738D03*
X442738D03*
X454738Y156800D03*
Y153800D03*
Y150800D03*
X451738D03*
Y153800D03*
Y156800D03*
X448738Y150800D03*
Y153800D03*
Y156800D03*
X445738Y150800D03*
Y153800D03*
Y156800D03*
X442738Y150800D03*
Y153800D03*
Y156800D03*
X441938Y176500D03*
X454738Y201200D03*
Y198200D03*
Y195200D03*
Y192200D03*
X451738D03*
Y195200D03*
Y198200D03*
Y201200D03*
X448738Y192200D03*
Y195200D03*
Y198200D03*
Y201200D03*
X445738Y192200D03*
Y195200D03*
Y198200D03*
Y201200D03*
X442738Y192200D03*
Y195200D03*
Y198200D03*
Y201200D03*
X454738Y189200D03*
X451738D03*
X448738D03*
X445738D03*
X442738D03*
X454738Y239600D03*
Y236600D03*
X451738D03*
Y239600D03*
X448738Y236600D03*
Y239600D03*
X445738Y236600D03*
Y239600D03*
X442738Y236600D03*
Y239600D03*
X454738Y233600D03*
X451738D03*
X448738D03*
X445738D03*
X442738D03*
X441938Y220900D03*
X454738Y245600D03*
Y242600D03*
X451738D03*
Y245600D03*
X448738Y242600D03*
Y245600D03*
X445738Y242600D03*
Y245600D03*
X442738Y242600D03*
Y245600D03*
X441938Y265300D03*
X448738Y278000D03*
X451738D03*
X454738D03*
X448738Y290000D03*
Y287000D03*
Y284000D03*
Y281000D03*
X451738Y290000D03*
Y287000D03*
Y284000D03*
Y281000D03*
X454738D03*
Y284000D03*
Y287000D03*
Y290000D03*
X445738D03*
Y287000D03*
Y284000D03*
Y281000D03*
Y278000D03*
X442738Y290000D03*
Y287000D03*
Y284000D03*
Y281000D03*
Y278000D03*
X468946Y338216D03*
X465946D03*
X468946Y341216D03*
X465946D03*
X458946Y338216D03*
X455946D03*
Y341216D03*
X458946Y357216D03*
X468946Y357016D03*
X459680Y402510D03*
X439680D03*
X498923Y37456D03*
X495923D03*
X492923D03*
X489923D03*
X471946Y338216D03*
X481446D03*
X478446D03*
X481446Y341216D03*
X478446D03*
X484446Y338216D03*
X471946Y357016D03*
X479680Y402510D03*
X501923Y37456D03*
X504923D03*
X510923D03*
X507923D03*
X528084Y77900D03*
Y74900D03*
Y71900D03*
Y68900D03*
Y65900D03*
X525084Y77900D03*
Y74900D03*
Y71900D03*
Y68900D03*
Y65900D03*
X522084Y77900D03*
Y74900D03*
Y71900D03*
Y68900D03*
Y65900D03*
X525084Y116300D03*
Y113300D03*
Y110300D03*
X522084Y113300D03*
Y116300D03*
Y110300D03*
X528084Y116300D03*
Y113300D03*
Y110300D03*
X525084Y122300D03*
X522084D03*
X525084Y119300D03*
X522084D03*
X528084Y122300D03*
Y119300D03*
X525084Y166700D03*
X522084D03*
X525084Y160700D03*
Y163700D03*
Y157700D03*
Y154700D03*
X522084Y157700D03*
Y163700D03*
Y160700D03*
Y154700D03*
Y199100D03*
Y205100D03*
Y208100D03*
Y202100D03*
X525084Y199100D03*
Y202100D03*
Y208100D03*
Y205100D03*
X522084Y211100D03*
X525084D03*
X522084Y243500D03*
Y249500D03*
Y252500D03*
Y246500D03*
X525084Y243500D03*
Y246500D03*
Y252500D03*
Y249500D03*
X522084Y255500D03*
X525084D03*
X528084Y243500D03*
Y246500D03*
Y252500D03*
Y249500D03*
Y255500D03*
Y299900D03*
X525084D03*
X522084D03*
X528084Y296900D03*
X525084D03*
X522084D03*
X528084Y293900D03*
X525084D03*
X522084D03*
X528084Y290900D03*
Y287900D03*
X525084D03*
Y290900D03*
X522084D03*
Y287900D03*
X499680Y402510D03*
X519680D03*
X531084Y77900D03*
Y74900D03*
Y71900D03*
Y68900D03*
Y65900D03*
X551430Y265600D03*
X531084Y299900D03*
Y296900D03*
Y293900D03*
Y290900D03*
Y287900D03*
X539680Y402510D03*
X559680D03*
X586184Y117800D03*
X583184D03*
X586184Y114800D03*
X583184D03*
X580184D03*
X583184Y111800D03*
X580184D03*
X586184Y108800D03*
X583184D03*
X580184D03*
X586184Y105800D03*
X583184D03*
X563007Y118477D03*
Y114123D03*
X580184Y126800D03*
X583184D03*
X586184D03*
Y123800D03*
X583184D03*
X580184D03*
X586184Y120800D03*
X583184D03*
X580184D03*
X562830Y133300D03*
Y136800D03*
Y143800D03*
X583184Y239000D03*
X580184D03*
X576467Y265600D03*
X563007Y247323D03*
X583184Y242000D03*
X580184D03*
X583184Y254000D03*
Y251000D03*
Y248000D03*
Y245000D03*
X580184D03*
Y248000D03*
Y251000D03*
Y254000D03*
X583184Y260000D03*
Y257000D03*
X580184D03*
Y260000D03*
X562830Y270000D03*
Y277000D03*
Y273500D03*
X565091Y302592D03*
X570443Y302702D03*
X579680Y402510D03*
X595276Y239710D03*
X592476D03*
X620600Y239161D03*
X620466Y246839D03*
X605800Y256500D03*
X609637Y254523D03*
X605700Y259500D03*
X616184Y267000D03*
X604684D03*
X616684Y294500D03*
X602928Y293969D03*
X600875Y295937D03*
X616184Y276000D03*
X604684D03*
Y285000D03*
X616184D03*
X590684Y313800D03*
Y310800D03*
X601675Y305575D03*
X618500Y333500D03*
X619680Y402510D03*
X599680D03*
X645784Y43500D03*
X648784D03*
X645784Y40500D03*
X648784D03*
X645784Y99000D03*
X648784D03*
X645784Y96000D03*
X648784D03*
X622288Y235790D03*
X624788D03*
X640684Y264500D03*
Y269000D03*
X641000Y261500D03*
X644502Y246839D03*
X650100Y251500D03*
X623684Y281000D03*
X629018Y277500D03*
X649059Y314000D03*
X632186Y338917D03*
X623500Y379000D03*
X639680Y402510D03*
X651784Y43500D03*
Y40500D03*
X654784D03*
X657784Y43500D03*
X654784D03*
X651784Y99000D03*
Y96000D03*
X654784D03*
X657784Y99000D03*
X654784D03*
X658600Y237700D03*
X655600D03*
X664484Y212500D03*
X666984D03*
X672484D03*
X674984D03*
X679484D03*
X657259Y263000D03*
X660684Y262500D03*
X654100Y263000D03*
X651100Y266000D03*
X679184Y278980D03*
X673684Y280950D03*
X676684D03*
X670184Y288500D03*
X662184Y280500D03*
Y288500D03*
Y284500D03*
X659000Y284000D03*
X676184Y274000D03*
X657500Y330075D03*
X662075Y320000D03*
X662125Y308500D03*
X671000Y315760D03*
X668000Y311500D03*
X663500D03*
X657500Y326925D03*
X662100Y304500D03*
X658925Y320000D03*
X659680Y402510D03*
X679680D03*
X693863Y189760D03*
X688900Y184260D03*
X704200Y206569D03*
X704240Y185000D03*
X681984Y212500D03*
X685484D03*
X687984D03*
X683592Y259908D03*
X688945Y259761D03*
X695259Y248020D03*
X706984Y261100D03*
X710084D03*
X691794Y261073D03*
X692109Y248020D03*
X686784Y268100D03*
X695584D03*
X698433Y247119D03*
X702984Y283500D03*
X706684D03*
X702984Y272400D03*
X706684D03*
X686784Y278000D03*
X695584D03*
X686784Y287900D03*
X695684D03*
X710900Y324100D03*
X696613Y324032D03*
X693904D03*
X691759Y309000D03*
X699680Y402510D03*
X736554Y128056D03*
X739554Y131056D03*
Y128056D03*
X732100Y185000D03*
X729100D03*
X723100D03*
X726100Y188000D03*
X729100D03*
X732100D03*
X723100D03*
X720100D03*
X726000Y231500D03*
X729000D03*
X723000D03*
X720000D03*
X732000D03*
Y228500D03*
X720000D03*
X723000D03*
X726000D03*
X729000D03*
X712000Y215500D03*
X730600Y270000D03*
X727600D03*
X719484Y278980D03*
X722925Y299500D03*
X719433Y328087D03*
X734500Y307425D03*
X719500Y315500D03*
X734500Y310575D03*
X717401Y329996D03*
X739680Y402510D03*
X719680D03*
X742554Y131056D03*
X749600Y185000D03*
X752600D03*
X755600D03*
X746600Y188000D03*
X758600D03*
X755600D03*
X752600D03*
X749600D03*
X746600Y185000D03*
X758500Y231500D03*
X746500D03*
X755500D03*
X752500D03*
X749500D03*
X746500Y228500D03*
X755500D03*
X752500D03*
X749500D03*
X758500D03*
X759680Y402510D03*
X779680D03*
X799680D03*
X819680D03*
X862600Y29500D03*
X839680Y402510D03*
X859680D03*
X867100Y28000D03*
X872533Y29432D03*
X867100Y31500D03*
X887500Y355680D03*
X885265Y381000D03*
X878175Y374100D03*
Y364709D03*
X880500Y369500D03*
X879680Y402510D03*
X919680D03*
X899680D03*
X894500Y396500D03*
X939680Y402510D03*
X983500Y185000D03*
Y188000D03*
X977500Y185000D03*
X980500Y188000D03*
X977500D03*
X974500D03*
Y231500D03*
X977500D03*
X983500D03*
X980500D03*
X983500Y228500D03*
X980500D03*
X977500D03*
X974500D03*
X959680Y402510D03*
X979680D03*
X990954Y131056D03*
Y128056D03*
X993954Y131056D03*
Y128056D03*
X996954Y131056D03*
X986500Y185000D03*
Y188000D03*
X1004000Y185000D03*
X1001000Y188000D03*
X1004000D03*
X1007000Y185000D03*
X1010000D03*
X1013000Y188000D03*
X1010000D03*
X1007000D03*
X1001000Y185000D03*
X1004000Y231500D03*
X1007000D03*
X1010000D03*
X1001000D03*
X986500D03*
X1013000D03*
X986500Y228500D03*
X1013000D03*
X1004000D03*
X1007000D03*
X1010000D03*
X1001000D03*
X999680Y402510D03*
X1030100Y207500D03*
X1034537Y201437D03*
X1024600Y185000D03*
X1024525Y215000D03*
X1032500Y281800D03*
X1029500D03*
X1042800Y273020D03*
X1017300Y322500D03*
X1026270Y303729D03*
X1023492Y346593D03*
X1039680Y402510D03*
X1019680D03*
X1047163Y197437D03*
X1061600Y228000D03*
X1064600D03*
X1073600D03*
X1070600D03*
X1066600Y264100D03*
X1059300Y268500D03*
X1055600D03*
X1070525Y243000D03*
X1066700Y274000D03*
Y283900D03*
X1052200Y290900D03*
X1055300D03*
X1070490Y290927D03*
X1055600Y279600D03*
X1059300D03*
X1073339Y292239D03*
X1062600Y305000D03*
X1070175Y303980D03*
X1067025D03*
X1072600Y324000D03*
X1064600D03*
X1065800Y339500D03*
X1063300D03*
X1073800D03*
X1071300D03*
X1059680Y402510D03*
X1077500Y43500D03*
Y40500D03*
X1074500D03*
X1080500D03*
X1083500D03*
X1086500D03*
X1080500Y43500D03*
X1083500D03*
X1086500D03*
X1077500Y99000D03*
Y96000D03*
X1074500D03*
X1080500D03*
X1083500D03*
X1086500D03*
X1080500Y99000D03*
X1083500D03*
X1086500D03*
X1092100Y263500D03*
X1100100Y243500D03*
X1100500Y263500D03*
X1101500Y268500D03*
X1100100Y247500D03*
X1075500Y264100D03*
X1085600Y271050D03*
X1101500Y271500D03*
X1083100Y273020D03*
X1088079Y274980D03*
X1087100Y282500D03*
X1101600Y289500D03*
X1080600Y294000D03*
X1075500Y274000D03*
Y283900D03*
X1102600Y296000D03*
X1086100Y278000D03*
X1103661Y307700D03*
X1080600Y324000D03*
X1081800Y339500D03*
X1079300D03*
X1086800D03*
X1089300D03*
X1094500Y355600D03*
Y360500D03*
X1079680Y402510D03*
X1099680D03*
X1129800Y265400D03*
X1108100Y289000D03*
X1121600Y287500D03*
Y283000D03*
X1118500D03*
X1105025Y289000D03*
X1111100Y291500D03*
Y285000D03*
X1121100Y296000D03*
X1124600Y271425D03*
X1132113Y274500D03*
X1106661Y307700D03*
X1111100Y300500D03*
X1118000Y303500D03*
X1123100Y319500D03*
X1130100Y305174D03*
X1130510Y307720D03*
X1106000Y364500D03*
X1112500Y364700D03*
X1122000Y366240D03*
X1132000Y367000D03*
X1119680Y402510D03*
X1155366Y38982D03*
X1152366D03*
X1158366D03*
X1161366D03*
X1143500Y251500D03*
X1149600Y255000D03*
X1160990Y252134D03*
X1146100Y267000D03*
X1157600D03*
X1154025Y247000D03*
X1156584Y292488D03*
X1156509Y295396D03*
X1157600Y276000D03*
X1146100D03*
Y285000D03*
X1157600D03*
X1136000Y278953D03*
X1141600Y305161D03*
X1154600Y321050D03*
X1143100Y322500D03*
Y320000D03*
X1157800Y312050D03*
X1157138Y303000D03*
X1141600Y312839D03*
X1141500Y347500D03*
X1138500D03*
X1162425Y340500D03*
X1147000Y342500D03*
X1163000Y352500D03*
X1153500Y342500D03*
X1135000Y366500D03*
X1139000D03*
X1159680Y402510D03*
X1139680D03*
X1176100Y105800D03*
Y108800D03*
X1182100D03*
X1179100D03*
Y105800D03*
X1176100Y111800D03*
Y114800D03*
Y117800D03*
X1182100Y111800D03*
Y114800D03*
Y117800D03*
X1179100D03*
Y114800D03*
Y111800D03*
X1176100Y126800D03*
Y123800D03*
Y120800D03*
X1182100Y126800D03*
Y123800D03*
Y120800D03*
X1179100D03*
Y123800D03*
Y126800D03*
X1176100Y239000D03*
X1179100D03*
X1182100D03*
X1187700Y265600D03*
X1176100Y254000D03*
Y251000D03*
Y248000D03*
Y245000D03*
Y257000D03*
Y260000D03*
Y242000D03*
X1171600Y241500D03*
X1179100Y242000D03*
Y260000D03*
Y257000D03*
Y245000D03*
Y248000D03*
Y251000D03*
Y254000D03*
X1182100D03*
Y251000D03*
Y248000D03*
Y245000D03*
Y257000D03*
Y260000D03*
Y242000D03*
X1173500Y298500D03*
X1176200Y316500D03*
X1173200D03*
X1167800Y355000D03*
X1168200Y349700D03*
X1165575Y340500D03*
X1171700Y349900D03*
X1178900Y359620D03*
X1179500Y350000D03*
X1178500Y368740D03*
X1179680Y402510D03*
X1223866Y38482D03*
X1220866D03*
X1199277Y118477D03*
Y114123D03*
X1199100Y140300D03*
Y143800D03*
Y136800D03*
X1199277Y247323D03*
Y251677D03*
X1199100Y270000D03*
Y266500D03*
Y277000D03*
X1201037Y318912D03*
X1197127Y314264D03*
X1199680Y402510D03*
X1219680D03*
X1226866Y38482D03*
X1229866D03*
X1240200Y77900D03*
Y74900D03*
Y71900D03*
Y68900D03*
Y65900D03*
X1237200D03*
Y68900D03*
Y71900D03*
Y74900D03*
Y77900D03*
X1234200Y65900D03*
Y68900D03*
Y71900D03*
Y74900D03*
Y77900D03*
X1231200Y65900D03*
Y68900D03*
Y71900D03*
Y74900D03*
Y77900D03*
X1234200Y116300D03*
Y113300D03*
Y110300D03*
X1237200Y116300D03*
Y113300D03*
Y110300D03*
X1240200D03*
Y113300D03*
Y116300D03*
X1234200Y122300D03*
Y119300D03*
X1237200Y122300D03*
Y119300D03*
X1240200D03*
Y122300D03*
X1237200Y166700D03*
Y163700D03*
Y160700D03*
Y157700D03*
Y154700D03*
X1240200D03*
Y157700D03*
Y160700D03*
Y163700D03*
Y166700D03*
X1237200Y205100D03*
Y202100D03*
Y199100D03*
Y208100D03*
X1240200D03*
Y199100D03*
Y202100D03*
Y205100D03*
X1237200Y211100D03*
X1240200D03*
X1234200Y249500D03*
Y246500D03*
Y243500D03*
Y252500D03*
X1237200Y249500D03*
Y246500D03*
Y243500D03*
Y252500D03*
X1234200Y255500D03*
X1237200D03*
X1240200Y252500D03*
Y243500D03*
Y246500D03*
Y249500D03*
Y255500D03*
Y293900D03*
Y290900D03*
Y287900D03*
Y299900D03*
Y296900D03*
X1237200D03*
Y287900D03*
Y290900D03*
Y293900D03*
Y299900D03*
X1234200Y296900D03*
Y287900D03*
Y290900D03*
Y293900D03*
Y299900D03*
X1231200Y293900D03*
Y290900D03*
Y287900D03*
Y296900D03*
Y299900D03*
X1242930Y356148D03*
X1245930Y359148D03*
Y356148D03*
X1248930Y359148D03*
Y356148D03*
X1231930D03*
Y359148D03*
X1228930Y356148D03*
Y359148D03*
X1225930Y356148D03*
X1253930Y379648D03*
X1250930D03*
X1247930D03*
X1239680Y402510D03*
X1264366Y38482D03*
X1261366D03*
X1267366D03*
X1270366D03*
X1260340Y356284D03*
X1263340Y359284D03*
Y356284D03*
X1266340Y359284D03*
Y356284D03*
X1265340Y379784D03*
X1268340D03*
X1271340D03*
X1259680Y402510D03*
X1279680D03*
X1313366Y38482D03*
X1307366D03*
X1310366D03*
X1307700Y78900D03*
Y81900D03*
X1310700D03*
Y78900D03*
X1313700Y81900D03*
Y78900D03*
X1307700Y84900D03*
Y87900D03*
X1310700D03*
Y84900D03*
X1313700Y87900D03*
Y84900D03*
X1307700Y90900D03*
X1310700D03*
X1313700D03*
X1307700Y123300D03*
Y126300D03*
X1310700D03*
Y123300D03*
X1313700Y126300D03*
Y123300D03*
X1307700Y129300D03*
Y132300D03*
Y135300D03*
X1310700D03*
Y132300D03*
Y129300D03*
X1313700Y135300D03*
Y132300D03*
Y129300D03*
Y167700D03*
Y170700D03*
Y173700D03*
Y176700D03*
X1310700Y167700D03*
Y170700D03*
Y173700D03*
Y176700D03*
X1307700D03*
Y173700D03*
Y170700D03*
Y167700D03*
X1313700Y179700D03*
X1310700D03*
X1307700D03*
Y212100D03*
Y215100D03*
X1310700D03*
Y212100D03*
X1313700Y215100D03*
Y212100D03*
X1307700Y218100D03*
Y221100D03*
Y224100D03*
X1310700D03*
Y221100D03*
Y218100D03*
X1313700Y224100D03*
Y221100D03*
Y218100D03*
X1307700Y256500D03*
Y259500D03*
X1310700D03*
Y256500D03*
X1313700Y259500D03*
Y256500D03*
X1307700Y262500D03*
Y265500D03*
Y268500D03*
X1310700D03*
Y265500D03*
Y262500D03*
X1313700Y268500D03*
Y265500D03*
Y262500D03*
X1307700Y300900D03*
Y303900D03*
X1310700D03*
Y300900D03*
X1313700Y303900D03*
Y300900D03*
X1307700Y306900D03*
Y309900D03*
Y312900D03*
X1310700D03*
Y309900D03*
Y306900D03*
X1313700Y309900D03*
Y306900D03*
X1286113Y375312D03*
X1289113Y378312D03*
Y375312D03*
X1292113Y378312D03*
Y375312D03*
Y372312D03*
X1289113D03*
X1299680Y402510D03*
X1316366Y38482D03*
X1316700Y81900D03*
Y78900D03*
X1319700Y81900D03*
Y78900D03*
X1316700Y87900D03*
Y84900D03*
X1319700Y87900D03*
Y84900D03*
X1320346Y67900D03*
X1316700Y90900D03*
X1319700D03*
X1316700Y126300D03*
Y123300D03*
X1319700Y126300D03*
Y123300D03*
X1316700Y135300D03*
Y132300D03*
Y129300D03*
X1319700Y135300D03*
Y132300D03*
Y129300D03*
X1334140Y146642D03*
X1319700Y167700D03*
Y170700D03*
Y173700D03*
Y176700D03*
X1316700Y167700D03*
Y170700D03*
Y173700D03*
Y176700D03*
X1324100Y150500D03*
X1320346Y156700D03*
X1324100Y194900D03*
X1332671Y190644D03*
X1320346Y201100D03*
X1316700Y215100D03*
Y212100D03*
X1319700Y215100D03*
Y212100D03*
X1316700Y224100D03*
Y221100D03*
Y218100D03*
X1319700Y224100D03*
Y221100D03*
Y218100D03*
X1316700Y259500D03*
Y256500D03*
X1319700Y259500D03*
Y256500D03*
X1316700Y268500D03*
Y265500D03*
Y262500D03*
X1319700Y268500D03*
Y265500D03*
Y262500D03*
X1320346Y245500D03*
X1316700Y303900D03*
Y300900D03*
X1319700Y303900D03*
Y300900D03*
X1316700Y306900D03*
X1339680Y402510D03*
X1319680D03*
X1355310Y38893D03*
X1352310D03*
X1349310D03*
X1358310D03*
X1355100Y160000D03*
X1355000Y204400D03*
X1359620Y402940D03*
X1406230Y18076D03*
X1403230Y21076D03*
Y18076D03*
Y15076D03*
X1400230Y18076D03*
X1397230Y15076D03*
Y18076D03*
Y21076D03*
X1386882Y434539D03*
Y454539D03*
Y474539D03*
Y494539D03*
Y514539D03*
Y534539D03*
Y554539D03*
Y574539D03*
Y594539D03*
X1389643Y612723D03*
X1403035Y620181D03*
X1412230Y18076D03*
Y15076D03*
X1409230Y21076D03*
Y18076D03*
Y15076D03*
X1422310Y40481D03*
X1419310D03*
X1416310D03*
X1425310D03*
X1420335Y635388D03*
Y655388D03*
X1428754Y670547D03*
X1445829Y672778D03*
X1465829D03*
X1494728Y83500D03*
X1490000Y84000D03*
X1494728Y66500D03*
X1491918Y107773D03*
Y110773D03*
Y113773D03*
Y104773D03*
X1488918D03*
Y113773D03*
Y110773D03*
Y107773D03*
X1485918Y104773D03*
Y113773D03*
Y110773D03*
Y107773D03*
X1482918Y104773D03*
Y113773D03*
Y110773D03*
Y107773D03*
X1485829Y672778D03*
X1508460Y3003D03*
X1503728Y74477D03*
X1527100Y108500D03*
Y98925D03*
X1524600Y111500D03*
X1505829Y672778D03*
X1525829D03*
X1548460Y3003D03*
X1528460D03*
X1531600Y96941D03*
X1545829Y672778D03*
X1588460Y3003D03*
X1568460D03*
X1565829Y672778D03*
X1585829D03*
X1608460Y3003D03*
X1609100Y85500D03*
Y82000D03*
X1606100Y85500D03*
Y82000D03*
X1609100Y69500D03*
Y66000D03*
Y62500D03*
X1606100Y69500D03*
Y66000D03*
Y62500D03*
X1615800Y82700D03*
Y79700D03*
Y76700D03*
X1602100Y85500D03*
Y82000D03*
Y69500D03*
Y66000D03*
Y62500D03*
X1594930Y115000D03*
X1614100Y110000D03*
Y115000D03*
X1609100Y89000D03*
X1606100D03*
X1602100D03*
X1614100Y125000D03*
Y120000D03*
Y130000D03*
X1618100Y148925D03*
X1613527Y627220D03*
X1607226Y650448D03*
X1602599Y667628D03*
X1648460Y3003D03*
X1628460D03*
X1618800Y79700D03*
Y82700D03*
X1647800Y83200D03*
Y77200D03*
Y80200D03*
X1622295Y114940D03*
X1629870Y104240D03*
X1642915Y111950D03*
X1639372Y114450D03*
X1646458Y111950D03*
X1642915Y114450D03*
X1639372Y111950D03*
X1646458Y114450D03*
X1642037Y104134D03*
X1643537Y101434D03*
X1640037D03*
X1638537Y104134D03*
X1645537D03*
X1647037Y101434D03*
X1624500Y142500D03*
Y146000D03*
X1622295Y118940D03*
X1647837Y121812D03*
X1638707Y132954D03*
X1644917Y124581D03*
X1623100Y172500D03*
Y178000D03*
X1626000Y163500D03*
Y167500D03*
X1626925Y156000D03*
X1629000Y175000D03*
X1631585Y188777D03*
X1624000Y189000D03*
X1642000Y184500D03*
X1645000D03*
X1628658Y620261D03*
X1648675Y620226D03*
X1657050Y102380D03*
X1662000Y106000D03*
X1650002Y111950D03*
X1660250Y113860D03*
X1657050D03*
X1660250Y116760D03*
X1650002Y114450D03*
X1651037Y99734D03*
X1658500Y138000D03*
X1649197Y132915D03*
X1650990Y122034D03*
X1667000Y138000D03*
X1672800Y120400D03*
X1649500Y173398D03*
X1661500Y199000D03*
X1658000Y179500D03*
X1652600Y212000D03*
X1668675Y620226D03*
X1708460Y3003D03*
X1692000Y76570D03*
X1695500Y76500D03*
X1682500Y121825D03*
X1697976Y148000D03*
X1690100Y127375D03*
X1685976Y148000D03*
X1705100Y140500D03*
X1707100Y142500D03*
X1702600Y171500D03*
X1697976Y164500D03*
Y159000D03*
Y175500D03*
Y170000D03*
Y153500D03*
X1680000Y156500D03*
X1685976Y164500D03*
Y159000D03*
Y175500D03*
Y170000D03*
X1701100Y178500D03*
X1701000Y159000D03*
Y164500D03*
X1685975Y186500D03*
X1697975Y181000D03*
X1704600Y201500D03*
X1685976Y181000D03*
X1688692Y620191D03*
X1708692D03*
X1729255Y25347D03*
Y45347D03*
X1718675Y88000D03*
X1732786Y58461D03*
X1719075Y112000D03*
X1718675Y99000D03*
Y93500D03*
X1713524Y109500D03*
Y114500D03*
X1738000Y124500D03*
X1713525Y134500D03*
Y129500D03*
X1713524Y119500D03*
X1715525Y153000D03*
X1720524Y175000D03*
X1717600Y158000D03*
X1712000Y153000D03*
X1728475Y175000D03*
X1731925Y199000D03*
X1714175Y187000D03*
X1729000Y183500D03*
X1724824Y205276D03*
X1711025Y187000D03*
X1721500Y205000D03*
X1721600Y194760D03*
Y198500D03*
X1728600Y387500D03*
X1731100D03*
X1733600D03*
Y397500D03*
X1731100D03*
X1728600D03*
X1729275Y562751D03*
Y542751D03*
Y582751D03*
Y602751D03*
X1753635Y69037D03*
X1767525Y114016D03*
X1764000Y107000D03*
X1763500Y113000D03*
X1767425Y137000D03*
X1768500Y142525D03*
X1764100Y119500D03*
X1764000Y158025D03*
X1759925Y178900D03*
X1768500Y158025D03*
X1763925Y170984D03*
Y155484D03*
X1766925Y181500D03*
X1769425Y203000D03*
X1754925D03*
X1754260Y187260D03*
X1768000D03*
X1746000Y191240D03*
X1750563Y198000D03*
X1751600Y238000D03*
Y235500D03*
X1740600D03*
Y238000D03*
X1751600Y233000D03*
X1740600D03*
X1751600Y258000D03*
Y255500D03*
X1740600Y258000D03*
Y255500D03*
Y248000D03*
Y250500D03*
Y253000D03*
X1751600D03*
Y250500D03*
Y248000D03*
X1766432Y250301D03*
Y247301D03*
X1766447Y239798D03*
Y242798D03*
X1751600Y240500D03*
X1740600D03*
X1742109Y345235D03*
Y342435D03*
X1747416Y348293D03*
X1751289Y345227D03*
X1747909Y345335D03*
Y342535D03*
X1744909Y345335D03*
Y342535D03*
X1747416Y351817D03*
X1747235Y359564D03*
X1742109Y339635D03*
Y336835D03*
Y334035D03*
X1747909Y339735D03*
Y336935D03*
Y334135D03*
X1744909Y339735D03*
Y336935D03*
Y334135D03*
X1767151Y333311D03*
X1767600Y350000D03*
X1747235Y367264D03*
Y374964D03*
X1755454Y515746D03*
X1793635Y69037D03*
X1773635D03*
X1772975Y109500D03*
Y104500D03*
X1773076Y117500D03*
X1773500Y121000D03*
X1772975Y124500D03*
X1772500Y174000D03*
X1800100Y187500D03*
X1770075Y181500D03*
X1778000Y189500D03*
X1789600Y247000D03*
X1783932Y250357D03*
Y247357D03*
X1775432Y250357D03*
Y247357D03*
X1783947Y239798D03*
Y242798D03*
X1775447Y239798D03*
Y242798D03*
X1789600Y243500D03*
X1777532Y328322D03*
X1777375Y356300D03*
X1777459Y332322D03*
X1777383Y348288D03*
Y352305D03*
X1776100Y361500D03*
Y371500D03*
Y368500D03*
X1776140Y364405D03*
X1784035Y389535D03*
X1781535D03*
X1784035Y386935D03*
X1781535D03*
X1778838Y389508D03*
Y386908D03*
X1781535Y402935D03*
X1784035D03*
X1778838Y402908D03*
X1781535Y405535D03*
X1784035D03*
X1778838Y405508D03*
X1775454Y515746D03*
X1813635Y69037D03*
X1815454Y515746D03*
X1853635Y69037D03*
X1833635D03*
X1842164Y419238D03*
X1837164D03*
X1852164D03*
X1844500Y416500D03*
X1847500Y437000D03*
X1835454Y515746D03*
X1855509Y515697D03*
X1871008Y117112D03*
X1871009Y93913D03*
X1871008Y137112D03*
Y177112D03*
Y157112D03*
Y197112D03*
Y237112D03*
Y217112D03*
Y257112D03*
Y297112D03*
Y277112D03*
Y317112D03*
Y357112D03*
Y337112D03*
Y377112D03*
Y417112D03*
Y397112D03*
Y437112D03*
Y477112D03*
Y457112D03*
Y497112D03*
X2463384Y678262D03*
G54D30*
X1846142Y230433D03*
Y240433D03*
X1856772D03*
Y230433D03*
X1846142Y250433D03*
Y260433D03*
Y270433D03*
X1856772D03*
Y260433D03*
Y250433D03*
X1846142Y280433D03*
Y290433D03*
Y300433D03*
X1856772D03*
Y290433D03*
Y280433D03*
X1848957Y324213D03*
X1843957Y329213D03*
X1848957Y314213D03*
X1843957Y319213D03*
X1853957Y329213D03*
Y319213D03*
X1858957Y324213D03*
Y314213D03*
X1848957Y334213D03*
Y344213D03*
X1843957Y339213D03*
Y349213D03*
X1853957D03*
Y339213D03*
X1858957Y344213D03*
Y334213D03*
X2463384Y527062D03*
G54D12*
X32284Y541339D03*
X59055Y498032D03*
X1673228D03*
X1700000Y541339D03*
X2463384Y262462D03*
G54D21*
X207874Y639095D03*
X1524409D03*
X2463384Y224662D03*
G54D22*
X240866Y15512D03*
X300866Y10197D03*
X1431417Y15512D03*
X1491417Y10197D03*
X2463384Y111262D03*
G54D31*
X1851457Y220433D03*
X1856772Y360433D03*
X2463384Y149062D03*
G36*
G01X41338Y17716D02*
G03X53150I5906J0D01*
G01Y23763D01*
G02X55572Y32155I15747J1D01*
G03X38916I-8328J5246D01*
G02X41338Y23763I-13327J-8392D01*
G01Y17716D01*
G37*
G36*
G01Y330708D02*
G03X53150I5906J0D01*
G01Y336755D01*
G02X55572Y345147I15747J1D01*
G03X38916I-8328J5246D01*
G02X41338Y336755I-13327J-8392D01*
G01Y330708D01*
G37*
G36*
G01X273622Y53148D02*
G03X285434I5906J0D01*
G01Y59195D01*
G02X287856Y67587I15747J1D01*
G03X271200I-8328J5246D01*
G02X273622Y59195I-13327J-8392D01*
G01Y53148D01*
G37*
G36*
G01X309055Y561023D02*
G03X320867I5906J0D01*
G01Y567070D01*
G02X323289Y575462I15747J1D01*
G03X306633I-8328J5246D01*
G02X309055Y567070I-13327J-8392D01*
G01Y561023D01*
G37*
G36*
G01X387796Y344488D02*
G03X399608I5906J0D01*
G01Y350535D01*
G02X402030Y358927I15747J1D01*
G03X385374I-8328J5246D01*
G02X387796Y350535I-13327J-8392D01*
G01Y344488D01*
G37*
G36*
G01X742126Y64961D02*
G03X753938I5906J0D01*
G01Y71008D01*
G02X756360Y79400I15747J1D01*
G03X739704I-8328J5246D01*
G02X742126Y71008I-13327J-8392D01*
G01Y64961D01*
G37*
G36*
G01Y344488D02*
G03X753938I5906J0D01*
G01Y350535D01*
G02X756360Y358927I15747J1D01*
G03X739704I-8328J5246D01*
G02X742126Y350535I-13327J-8392D01*
G01Y344488D01*
G37*
G36*
G01X978346Y64961D02*
G03X990158I5906J0D01*
G01Y71008D01*
G02X992580Y79400I15747J1D01*
G03X975924I-8328J5246D01*
G02X978346Y71008I-13327J-8392D01*
G01Y64961D01*
G37*
G36*
G01Y344488D02*
G03X990158I5906J0D01*
G01Y350535D01*
G02X992580Y358927I15747J1D01*
G03X975924I-8328J5246D01*
G02X978346Y350535I-13327J-8392D01*
G01Y344488D01*
G37*
G36*
G01X1332678D02*
G03X1344490I5906J0D01*
G01Y350535D01*
G02X1346912Y358927I15747J1D01*
G03X1330256I-8328J5246D01*
G02X1332678Y350535I-13327J-8392D01*
G01Y344488D01*
G37*
G36*
G01X1411418Y561023D02*
G03X1423230I5906J0D01*
G01Y567070D01*
G02X1425652Y575462I15747J1D01*
G03X1408996I-8328J5246D01*
G02X1411418Y567070I-13327J-8392D01*
G01Y561023D01*
G37*
G36*
G01X1446850Y53149D02*
G03X1458662I5906J0D01*
G01Y59196D01*
G02X1461084Y67588I15747J1D01*
G03X1444428I-8328J5246D01*
G02X1446850Y59196I-13327J-8392D01*
G01Y53149D01*
G37*
G36*
G01X1679134Y17716D02*
G03X1690946I5906J0D01*
G01Y23763D01*
G02X1693368Y32155I15747J1D01*
G03X1676712I-8328J5246D01*
G02X1679134Y23763I-13327J-8392D01*
G01Y17716D01*
G37*
G36*
G01Y330708D02*
G03X1690946I5906J0D01*
G01Y336755D01*
G02X1693368Y345147I15747J1D01*
G03X1676712I-8328J5246D01*
G02X1679134Y336755I-13327J-8392D01*
G01Y330708D01*
G37*
G36*
G01X1793306Y96457D02*
G03X1805118I5906J0D01*
G01Y102504D01*
G02X1807540Y110896I15747J1D01*
G03X1790884I-8328J5246D01*
G02X1793306Y102504I-13327J-8392D01*
G01Y96457D01*
G37*
G36*
G01Y478346D02*
G03X1805118I5906J0D01*
G01Y484393D01*
G02X1807540Y492785I15747J1D01*
G03X1790884I-8328J5246D01*
G02X1793306Y484393I-13327J-8392D01*
G01Y478346D01*
G37*
G54D32*
G01X-457143Y-1211429D02*
Y2242857D01*
X4308572D01*
Y-1211429D01*
X-457143D01*
G01X-266250Y344750D02*
X-270900D01*
Y357250D01*
X-266250D01*
G01X-210450Y344750D02*
X-205800D01*
Y357250D01*
X-210450D01*
G01X-163464Y217864D02*
X-168114D01*
Y230364D01*
X-163464D01*
G01X392702Y344488D02*
X-43500D01*
X-73500Y363500D01*
X-186975D01*
G01X-174943Y392844D02*
X-179593D01*
Y405344D01*
X-174943D01*
G01X-172200Y645935D02*
X-176850D01*
Y658435D01*
X-172200D01*
G01X-161800Y-49750D02*
X-166450D01*
Y-37250D01*
X-161800D01*
G01X-156728Y-1034D02*
X-161378D01*
Y11466D01*
X-156728D01*
G01X-161750Y53750D02*
X-166400D01*
Y66250D01*
X-161750D01*
G01Y137750D02*
X-166400D01*
Y150250D01*
X-161750D01*
G01X-150350Y311958D02*
X-155000D01*
Y324458D01*
X-150350D01*
G01X-113328Y-1034D02*
X-108678D01*
Y11466D01*
X-113328D01*
G01X-107664Y217864D02*
X-103014D01*
Y230364D01*
X-107664D01*
G01X-119350Y311958D02*
X-114700D01*
Y324458D01*
X-119350D01*
G01X-106000Y-49750D02*
X-101350D01*
Y-37250D01*
X-106000D01*
G01X273646Y8012D02*
X-80900D01*
Y-31000D01*
X-91975D01*
G01X46244Y17716D02*
X-89853D01*
G01X-105950Y53750D02*
X-101300D01*
Y66250D01*
X-105950D01*
G01X278528Y53148D02*
X16500D01*
X-41500Y72500D01*
X-88675D01*
G01X-105950Y137750D02*
X-101300D01*
Y150250D01*
X-105950D01*
G01X747032Y64961D02*
X77500D01*
X-58500Y156500D01*
X-88675D01*
G01X58055Y236614D02*
X-84189D01*
G01X46244Y330708D02*
X-83475D01*
G01X58055Y411594D02*
X-80318D01*
G01X-94343Y392844D02*
X-89693D01*
Y405344D01*
X-94343D01*
G01X-91600Y645935D02*
X-86950D01*
Y658435D01*
X-91600D01*
G01X136303Y664685D02*
X-77575D01*
G01X-37066Y-18750D02*
X-41716D01*
Y-6250D01*
X-37066D01*
G01X-18466Y-18750D02*
X-13816D01*
Y-6250D01*
X-18466D01*
G01X-23697Y1215896D02*
X-36197D01*
X-33697Y1214036D01*
G01X-23697D02*
Y1217756D01*
G01X-36197Y1228296D02*
X-35780Y1227056D01*
X-34739Y1226126D01*
X-33489Y1225506D01*
X-31822Y1225041D01*
X-29947Y1224886D01*
X-28072Y1225041D01*
X-26405Y1225506D01*
X-25155Y1226126D01*
X-24114Y1227056D01*
X-23697Y1228296D01*
X-24114Y1229536D01*
X-25155Y1230466D01*
X-26405Y1231086D01*
X-28072Y1231551D01*
X-29947Y1231706D01*
X-31822Y1231551D01*
X-33489Y1231086D01*
X-34739Y1230466D01*
X-35780Y1229536D01*
X-36197Y1228296D01*
G01X-23697Y1236666D02*
X-36197D01*
X-25780Y1240696D01*
X-36197Y1244726D01*
X-23697D01*
G01Y1249066D02*
X-36197D01*
X-25780Y1253096D01*
X-36197Y1257126D01*
X-23697D01*
G01X51392Y1220716D02*
X-22712D01*
G01X50538Y1260086D02*
X-22712D01*
G01X-25468Y1471264D02*
Y1479264D01*
X-26668Y1477664D01*
G01Y1471264D02*
X-24268D01*
G01X-17468Y1479264D02*
X-18268Y1478997D01*
X-18868Y1478331D01*
X-19268Y1477531D01*
X-19568Y1476464D01*
X-19668Y1475264D01*
X-19568Y1474064D01*
X-19268Y1472997D01*
X-18868Y1472197D01*
X-18268Y1471531D01*
X-17468Y1471264D01*
X-16668Y1471531D01*
X-16068Y1472197D01*
X-15668Y1472997D01*
X-15368Y1474064D01*
X-15268Y1475264D01*
X-15368Y1476464D01*
X-15668Y1477531D01*
X-16068Y1478331D01*
X-16668Y1478997D01*
X-17468Y1479264D01*
G01X-9468Y1470997D02*
X-9668Y1471131D01*
Y1471397D01*
X-9468Y1471531D01*
X-9268Y1471397D01*
Y1471131D01*
X-9468Y1470997D01*
G01X-3368Y1471264D02*
Y1479264D01*
X432D01*
G01X-968Y1475397D02*
X-3368D01*
G01X6532Y1471264D02*
X5732Y1471397D01*
X5032Y1471931D01*
X4432Y1472731D01*
X4032Y1473664D01*
X3832Y1474731D01*
Y1475797D01*
X4032Y1476864D01*
X4432Y1477797D01*
X5032Y1478597D01*
X5732Y1479131D01*
X6532Y1479264D01*
X7332Y1479131D01*
X8032Y1478597D01*
X8632Y1477797D01*
X9032Y1476864D01*
X9232Y1475797D01*
Y1474731D01*
X9032Y1473664D01*
X8632Y1472731D01*
X8032Y1471931D01*
X7332Y1471397D01*
X6532Y1471264D01*
G01X12532D02*
Y1479264D01*
X15032D01*
X15832Y1478864D01*
X16332Y1478331D01*
X16532Y1477264D01*
X16332Y1476197D01*
X15732Y1475531D01*
X15032Y1475131D01*
X12532D01*
G01X15032D02*
X16532Y1471264D01*
G01X30532Y1479264D02*
Y1471264D01*
G01X28232Y1479264D02*
X32832D01*
G01X36432Y1471264D02*
Y1479264D01*
G01X40632D02*
Y1471264D01*
G01Y1475264D02*
X36432D01*
G01X48532Y1471264D02*
X44532D01*
Y1479264D01*
X48532D01*
G01X46932Y1475397D02*
X44532D01*
G01X60532Y1471264D02*
Y1479264D01*
X62932D01*
X63732Y1478864D01*
X64332Y1477931D01*
X64532Y1476864D01*
X64332Y1475797D01*
X63832Y1474997D01*
X62932Y1474597D01*
X60532D01*
G01X70532Y1479264D02*
Y1471264D01*
G01X68232Y1479264D02*
X72832D01*
G01X76432Y1471264D02*
Y1479264D01*
G01X80632D02*
Y1471264D01*
G01Y1475264D02*
X76432D01*
G01X94532Y1479264D02*
Y1471264D01*
G01X92232Y1479264D02*
X96832D01*
G01X102532Y1471264D02*
X101732Y1471397D01*
X101032Y1471931D01*
X100432Y1472731D01*
X100032Y1473664D01*
X99832Y1474731D01*
Y1475797D01*
X100032Y1476864D01*
X100432Y1477797D01*
X101032Y1478597D01*
X101732Y1479131D01*
X102532Y1479264D01*
X103332Y1479131D01*
X104032Y1478597D01*
X104632Y1477797D01*
X105032Y1476864D01*
X105232Y1475797D01*
Y1474731D01*
X105032Y1473664D01*
X104632Y1472731D01*
X104032Y1471931D01*
X103332Y1471397D01*
X102532Y1471264D01*
G01X110532D02*
X109732Y1471397D01*
X109032Y1471931D01*
X108432Y1472731D01*
X108032Y1473664D01*
X107832Y1474731D01*
Y1475797D01*
X108032Y1476864D01*
X108432Y1477797D01*
X109032Y1478597D01*
X109732Y1479131D01*
X110532Y1479264D01*
X111332Y1479131D01*
X112032Y1478597D01*
X112632Y1477797D01*
X113032Y1476864D01*
X113232Y1475797D01*
Y1474731D01*
X113032Y1473664D01*
X112632Y1472731D01*
X112032Y1471931D01*
X111332Y1471397D01*
X110532Y1471264D01*
G01X116532Y1479264D02*
Y1471264D01*
X120532D01*
G01X125332Y1479264D02*
X127732D01*
G01X126532D02*
Y1471264D01*
G01X125332D02*
X127732D01*
G01X132232D02*
Y1479264D01*
X136832Y1471264D01*
Y1479264D01*
G01X143132Y1475264D02*
X145132D01*
Y1472864D01*
X144532Y1472064D01*
X143832Y1471531D01*
X142832Y1471264D01*
X141832Y1471531D01*
X141132Y1472064D01*
X140532Y1472864D01*
X140132Y1473797D01*
X139932Y1474864D01*
Y1475797D01*
X140132Y1476597D01*
X140532Y1477531D01*
X141132Y1478331D01*
X141732Y1478864D01*
X142532Y1479264D01*
X143232D01*
X144032Y1478997D01*
X144632Y1478464D01*
G01X156432Y1471264D02*
Y1479264D01*
G01X160632D02*
Y1471264D01*
G01Y1475264D02*
X156432D01*
G01X166532Y1471264D02*
X165732Y1471397D01*
X165032Y1471931D01*
X164432Y1472731D01*
X164032Y1473664D01*
X163832Y1474731D01*
Y1475797D01*
X164032Y1476864D01*
X164432Y1477797D01*
X165032Y1478597D01*
X165732Y1479131D01*
X166532Y1479264D01*
X167332Y1479131D01*
X168032Y1478597D01*
X168632Y1477797D01*
X169032Y1476864D01*
X169232Y1475797D01*
Y1474731D01*
X169032Y1473664D01*
X168632Y1472731D01*
X168032Y1471931D01*
X167332Y1471397D01*
X166532Y1471264D01*
G01X172532Y1479264D02*
Y1471264D01*
X176532D01*
G01X184532D02*
X180532D01*
Y1479264D01*
X184532D01*
G01X182932Y1475397D02*
X180532D01*
G01X188432Y1472330D02*
X189232Y1471664D01*
X190132Y1471264D01*
X190932D01*
X191732Y1471664D01*
X192332Y1472330D01*
X192632Y1473264D01*
X192432Y1474197D01*
X191932Y1474997D01*
X191032Y1475531D01*
X189832Y1475797D01*
X189132Y1476331D01*
X188832Y1477264D01*
X189032Y1478197D01*
X189532Y1478864D01*
X190232Y1479264D01*
X190932D01*
X191632Y1478997D01*
X192232Y1478331D01*
G01X203532Y1479264D02*
X204932Y1471264D01*
X206532Y1479264D01*
X208132Y1471264D01*
X209532Y1479264D01*
G01X212432Y1471264D02*
Y1479264D01*
G01X216632D02*
Y1471264D01*
G01Y1475264D02*
X212432D01*
G01X221332Y1479264D02*
X223732D01*
G01X222532D02*
Y1471264D01*
G01X221332D02*
X223732D01*
G01X232732Y1478597D02*
X232132Y1478997D01*
X231432Y1479264D01*
X230632D01*
X229732Y1478864D01*
X229032Y1478197D01*
X228532Y1477397D01*
X228132Y1476064D01*
X228032Y1474864D01*
X228232Y1473664D01*
X228532Y1472864D01*
X229132Y1472064D01*
X229832Y1471531D01*
X230532Y1471264D01*
X231232D01*
X231932Y1471531D01*
X232532Y1471931D01*
X233032Y1472464D01*
G01X236432Y1471264D02*
Y1479264D01*
G01X240632D02*
Y1471264D01*
G01Y1475264D02*
X236432D01*
G01X252432Y1472330D02*
X253232Y1471664D01*
X254132Y1471264D01*
X254932D01*
X255732Y1471664D01*
X256332Y1472330D01*
X256632Y1473264D01*
X256432Y1474197D01*
X255932Y1474997D01*
X255032Y1475531D01*
X253832Y1475797D01*
X253132Y1476331D01*
X252832Y1477264D01*
X253032Y1478197D01*
X253532Y1478864D01*
X254232Y1479264D01*
X254932D01*
X255632Y1478997D01*
X256232Y1478331D01*
G01X261332Y1479264D02*
X263732D01*
G01X262532D02*
Y1471264D01*
G01X261332D02*
X263732D01*
G01X268632Y1479264D02*
X272432D01*
X268632Y1471264D01*
X272432D01*
G01X280532D02*
X276532D01*
Y1479264D01*
X280532D01*
G01X278932Y1475397D02*
X276532D01*
G01X293332Y1479264D02*
X295732D01*
G01X294532D02*
Y1471264D01*
G01X293332D02*
X295732D01*
G01X300432Y1472330D02*
X301232Y1471664D01*
X302132Y1471264D01*
X302932D01*
X303732Y1471664D01*
X304332Y1472330D01*
X304632Y1473264D01*
X304432Y1474197D01*
X303932Y1474997D01*
X303032Y1475531D01*
X301832Y1475797D01*
X301132Y1476331D01*
X300832Y1477264D01*
X301032Y1478197D01*
X301532Y1478864D01*
X302232Y1479264D01*
X302932D01*
X303632Y1478997D01*
X304232Y1478331D01*
G01X320532Y1471264D02*
X316532D01*
Y1479264D01*
X320532D01*
G01X318932Y1475397D02*
X316532D01*
G01X326532Y1471264D02*
X325732Y1471397D01*
X325032Y1471931D01*
X324432Y1472731D01*
X324032Y1473664D01*
X323832Y1474731D01*
Y1475797D01*
X324032Y1476864D01*
X324432Y1477797D01*
X325032Y1478597D01*
X325732Y1479131D01*
X326532Y1479264D01*
X327332Y1479131D01*
X328032Y1478597D01*
X328632Y1477797D01*
X329032Y1476864D01*
X329232Y1475797D01*
Y1474731D01*
X329032Y1473664D01*
X328632Y1472731D01*
X328032Y1471931D01*
X327332Y1471397D01*
X326532Y1471264D01*
G01X327332Y1473397D02*
X328532Y1471264D01*
G01X332332Y1479264D02*
Y1473531D01*
X332732Y1472330D01*
X333532Y1471531D01*
X334532Y1471264D01*
X335532Y1471531D01*
X336332Y1472330D01*
X336732Y1473531D01*
Y1479264D01*
G01X340032Y1471264D02*
X342532Y1479264D01*
X345032Y1471264D01*
G01X344132Y1474064D02*
X340932D01*
G01X348532Y1479264D02*
Y1471264D01*
X352532D01*
G01X366532Y1479264D02*
Y1471264D01*
G01X364232Y1479264D02*
X368832D01*
G01X374532Y1471264D02*
X373732Y1471397D01*
X373032Y1471931D01*
X372432Y1472731D01*
X372032Y1473664D01*
X371832Y1474731D01*
Y1475797D01*
X372032Y1476864D01*
X372432Y1477797D01*
X373032Y1478597D01*
X373732Y1479131D01*
X374532Y1479264D01*
X375332Y1479131D01*
X376032Y1478597D01*
X376632Y1477797D01*
X377032Y1476864D01*
X377232Y1475797D01*
Y1474731D01*
X377032Y1473664D01*
X376632Y1472731D01*
X376032Y1471931D01*
X375332Y1471397D01*
X374532Y1471264D01*
G01X390532D02*
X389732Y1471397D01*
X389032Y1471931D01*
X388432Y1472731D01*
X388032Y1473664D01*
X387832Y1474731D01*
Y1475797D01*
X388032Y1476864D01*
X388432Y1477797D01*
X389032Y1478597D01*
X389732Y1479131D01*
X390532Y1479264D01*
X391332Y1479131D01*
X392032Y1478597D01*
X392632Y1477797D01*
X393032Y1476864D01*
X393232Y1475797D01*
Y1474731D01*
X393032Y1473664D01*
X392632Y1472731D01*
X392032Y1471931D01*
X391332Y1471397D01*
X390532Y1471264D01*
G01X396532D02*
Y1479264D01*
X399032D01*
X399832Y1478864D01*
X400332Y1478331D01*
X400532Y1477264D01*
X400332Y1476197D01*
X399732Y1475531D01*
X399032Y1475131D01*
X396532D01*
G01X399032D02*
X400532Y1471264D01*
G01X411932D02*
Y1479264D01*
X414532Y1472597D01*
X417132Y1479264D01*
Y1471264D01*
G01X422532D02*
X421732Y1471397D01*
X421032Y1471931D01*
X420432Y1472731D01*
X420032Y1473664D01*
X419832Y1474731D01*
Y1475797D01*
X420032Y1476864D01*
X420432Y1477797D01*
X421032Y1478597D01*
X421732Y1479131D01*
X422532Y1479264D01*
X423332Y1479131D01*
X424032Y1478597D01*
X424632Y1477797D01*
X425032Y1476864D01*
X425232Y1475797D01*
Y1474731D01*
X425032Y1473664D01*
X424632Y1472731D01*
X424032Y1471931D01*
X423332Y1471397D01*
X422532Y1471264D01*
G01X428532D02*
Y1479264D01*
X431032D01*
X431832Y1478864D01*
X432332Y1478331D01*
X432532Y1477264D01*
X432332Y1476197D01*
X431732Y1475531D01*
X431032Y1475131D01*
X428532D01*
G01X431032D02*
X432532Y1471264D01*
G01X440532D02*
X436532D01*
Y1479264D01*
X440532D01*
G01X438932Y1475397D02*
X436532D01*
G01X454532Y1479264D02*
Y1471264D01*
G01X452232Y1479264D02*
X456832D01*
G01X460432Y1471264D02*
Y1479264D01*
G01X464632D02*
Y1471264D01*
G01Y1475264D02*
X460432D01*
G01X468032Y1471264D02*
X470532Y1479264D01*
X473032Y1471264D01*
G01X472132Y1474064D02*
X468932D01*
G01X476232Y1471264D02*
Y1479264D01*
X480832Y1471264D01*
Y1479264D01*
G01X494332Y1471264D02*
X494532Y1472997D01*
X494832Y1474464D01*
X495232Y1475797D01*
X495732Y1477264D01*
X496532Y1479264D01*
X492532D01*
G01X502532D02*
X501732Y1478997D01*
X501132Y1478331D01*
X500732Y1477531D01*
X500432Y1476464D01*
X500332Y1475264D01*
X500432Y1474064D01*
X500732Y1472997D01*
X501132Y1472197D01*
X501732Y1471531D01*
X502532Y1471264D01*
X503332Y1471531D01*
X503932Y1472197D01*
X504332Y1472997D01*
X504632Y1474064D01*
X504732Y1475264D01*
X504632Y1476464D01*
X504332Y1477531D01*
X503932Y1478331D01*
X503332Y1478997D01*
X502532Y1479264D01*
G01X515932Y1471264D02*
Y1479264D01*
X518532Y1472597D01*
X521132Y1479264D01*
Y1471264D01*
G01X525332Y1479264D02*
X527732D01*
G01X526532D02*
Y1471264D01*
G01X525332D02*
X527732D01*
G01X532532Y1479264D02*
Y1471264D01*
X536532D01*
G01X542532Y1470997D02*
X542332Y1471131D01*
Y1471397D01*
X542532Y1471531D01*
X542732Y1471397D01*
Y1471131D01*
X542532Y1470997D01*
G01X564232Y1471264D02*
Y1479264D01*
X568832Y1471264D01*
Y1479264D01*
G01X574532Y1471264D02*
X573732Y1471397D01*
X573032Y1471931D01*
X572432Y1472731D01*
X572032Y1473664D01*
X571832Y1474731D01*
Y1475797D01*
X572032Y1476864D01*
X572432Y1477797D01*
X573032Y1478597D01*
X573732Y1479131D01*
X574532Y1479264D01*
X575332Y1479131D01*
X576032Y1478597D01*
X576632Y1477797D01*
X577032Y1476864D01*
X577232Y1475797D01*
Y1474731D01*
X577032Y1473664D01*
X576632Y1472731D01*
X576032Y1471931D01*
X575332Y1471397D01*
X574532Y1471264D01*
G01X580232D02*
Y1479264D01*
X584832Y1471264D01*
Y1479264D01*
G01X589232Y1473931D02*
X591832D01*
G01X596632Y1471264D02*
Y1479264D01*
X600432D01*
G01X599032Y1475397D02*
X596632D01*
G01X604332Y1479264D02*
Y1473531D01*
X604732Y1472330D01*
X605532Y1471531D01*
X606532Y1471264D01*
X607532Y1471531D01*
X608332Y1472330D01*
X608732Y1473531D01*
Y1479264D01*
G01X612232Y1471264D02*
Y1479264D01*
X616832Y1471264D01*
Y1479264D01*
G01X624732Y1478597D02*
X624132Y1478997D01*
X623432Y1479264D01*
X622632D01*
X621732Y1478864D01*
X621032Y1478197D01*
X620532Y1477397D01*
X620132Y1476064D01*
X620032Y1474864D01*
X620232Y1473664D01*
X620532Y1472864D01*
X621132Y1472064D01*
X621832Y1471531D01*
X622532Y1471264D01*
X623232D01*
X623932Y1471531D01*
X624532Y1471931D01*
X625032Y1472464D01*
G01X630532Y1479264D02*
Y1471264D01*
G01X628232Y1479264D02*
X632832D01*
G01X637332D02*
X639732D01*
G01X638532D02*
Y1471264D01*
G01X637332D02*
X639732D01*
G01X646532D02*
X645732Y1471397D01*
X645032Y1471931D01*
X644432Y1472731D01*
X644032Y1473664D01*
X643832Y1474731D01*
Y1475797D01*
X644032Y1476864D01*
X644432Y1477797D01*
X645032Y1478597D01*
X645732Y1479131D01*
X646532Y1479264D01*
X647332Y1479131D01*
X648032Y1478597D01*
X648632Y1477797D01*
X649032Y1476864D01*
X649232Y1475797D01*
Y1474731D01*
X649032Y1473664D01*
X648632Y1472731D01*
X648032Y1471931D01*
X647332Y1471397D01*
X646532Y1471264D01*
G01X652232D02*
Y1479264D01*
X656832Y1471264D01*
Y1479264D01*
G01X660032Y1471264D02*
X662532Y1479264D01*
X665032Y1471264D01*
G01X664132Y1474064D02*
X660932D01*
G01X668532Y1479264D02*
Y1471264D01*
X672532D01*
G01X684532D02*
Y1479264D01*
X686932D01*
X687732Y1478864D01*
X688332Y1477931D01*
X688532Y1476864D01*
X688332Y1475797D01*
X687832Y1474997D01*
X686932Y1474597D01*
X684532D01*
G01X692032Y1471264D02*
X694532Y1479264D01*
X697032Y1471264D01*
G01X696132Y1474064D02*
X692932D01*
G01X700332Y1471264D02*
Y1479264D01*
X702332D01*
X703132Y1478864D01*
X703732Y1478331D01*
X704232Y1477531D01*
X704632Y1476597D01*
X704732Y1475264D01*
X704632Y1473931D01*
X704232Y1472997D01*
X703732Y1472197D01*
X703132Y1471664D01*
X702332Y1471264D01*
X700332D01*
G01X717332Y1479264D02*
X719732D01*
G01X718532D02*
Y1471264D01*
G01X717332D02*
X719732D01*
G01X724432Y1472330D02*
X725232Y1471664D01*
X726132Y1471264D01*
X726932D01*
X727732Y1471664D01*
X728332Y1472330D01*
X728632Y1473264D01*
X728432Y1474197D01*
X727932Y1474997D01*
X727032Y1475531D01*
X725832Y1475797D01*
X725132Y1476331D01*
X724832Y1477264D01*
X725032Y1478197D01*
X725532Y1478864D01*
X726232Y1479264D01*
X726932D01*
X727632Y1478997D01*
X728232Y1478331D01*
G01X740532Y1471264D02*
Y1479264D01*
X743032D01*
X743832Y1478864D01*
X744332Y1478331D01*
X744532Y1477264D01*
X744332Y1476197D01*
X743732Y1475531D01*
X743032Y1475131D01*
X740532D01*
G01X743032D02*
X744532Y1471264D01*
G01X752532D02*
X748532D01*
Y1479264D01*
X752532D01*
G01X750932Y1475397D02*
X748532D01*
G01X758532Y1471264D02*
X757732Y1471397D01*
X757032Y1471931D01*
X756432Y1472731D01*
X756032Y1473664D01*
X755832Y1474731D01*
Y1475797D01*
X756032Y1476864D01*
X756432Y1477797D01*
X757032Y1478597D01*
X757732Y1479131D01*
X758532Y1479264D01*
X759332Y1479131D01*
X760032Y1478597D01*
X760632Y1477797D01*
X761032Y1476864D01*
X761232Y1475797D01*
Y1474731D01*
X761032Y1473664D01*
X760632Y1472731D01*
X760032Y1471931D01*
X759332Y1471397D01*
X758532Y1471264D01*
G01X759332Y1473397D02*
X760532Y1471264D01*
G01X764332Y1479264D02*
Y1473531D01*
X764732Y1472330D01*
X765532Y1471531D01*
X766532Y1471264D01*
X767532Y1471531D01*
X768332Y1472330D01*
X768732Y1473531D01*
Y1479264D01*
G01X773332D02*
X775732D01*
G01X774532D02*
Y1471264D01*
G01X773332D02*
X775732D01*
G01X780532D02*
Y1479264D01*
X783032D01*
X783832Y1478864D01*
X784332Y1478331D01*
X784532Y1477264D01*
X784332Y1476197D01*
X783732Y1475531D01*
X783032Y1475131D01*
X780532D01*
G01X783032D02*
X784532Y1471264D01*
G01X792532D02*
X788532D01*
Y1479264D01*
X792532D01*
G01X790932Y1475397D02*
X788532D01*
G01X796332Y1471264D02*
Y1479264D01*
X798332D01*
X799132Y1478864D01*
X799732Y1478331D01*
X800232Y1477531D01*
X800632Y1476597D01*
X800732Y1475264D01*
X800632Y1473931D01*
X800232Y1472997D01*
X799732Y1472197D01*
X799132Y1471664D01*
X798332Y1471264D01*
X796332D01*
G01X814532Y1479264D02*
Y1471264D01*
G01X812232Y1479264D02*
X816832D01*
G01X822532Y1471264D02*
X821732Y1471397D01*
X821032Y1471931D01*
X820432Y1472731D01*
X820032Y1473664D01*
X819832Y1474731D01*
Y1475797D01*
X820032Y1476864D01*
X820432Y1477797D01*
X821032Y1478597D01*
X821732Y1479131D01*
X822532Y1479264D01*
X823332Y1479131D01*
X824032Y1478597D01*
X824632Y1477797D01*
X825032Y1476864D01*
X825232Y1475797D01*
Y1474731D01*
X825032Y1473664D01*
X824632Y1472731D01*
X824032Y1471931D01*
X823332Y1471397D01*
X822532Y1471264D01*
G01X839332Y1475531D02*
X839732Y1475931D01*
X840032Y1476597D01*
X840232Y1477531D01*
X840032Y1478331D01*
X839632Y1478864D01*
X838932Y1479264D01*
X836232D01*
Y1471264D01*
X839532D01*
X840232Y1471797D01*
X840632Y1472597D01*
X840832Y1473531D01*
X840632Y1474464D01*
X840032Y1475264D01*
X839332Y1475531D01*
X836232D01*
G01X848532Y1471264D02*
X844532D01*
Y1479264D01*
X848532D01*
G01X846932Y1475397D02*
X844532D01*
G01X860032Y1471264D02*
X862532Y1479264D01*
X865032Y1471264D01*
G01X864132Y1474064D02*
X860932D01*
G01X868332Y1471264D02*
Y1479264D01*
X870332D01*
X871132Y1478864D01*
X871732Y1478331D01*
X872232Y1477531D01*
X872632Y1476597D01*
X872732Y1475264D01*
X872632Y1473931D01*
X872232Y1472997D01*
X871732Y1472197D01*
X871132Y1471664D01*
X870332Y1471264D01*
X868332D01*
G01X876332D02*
Y1479264D01*
X878332D01*
X879132Y1478864D01*
X879732Y1478331D01*
X880232Y1477531D01*
X880632Y1476597D01*
X880732Y1475264D01*
X880632Y1473931D01*
X880232Y1472997D01*
X879732Y1472197D01*
X879132Y1471664D01*
X878332Y1471264D01*
X876332D01*
G01X888532D02*
X884532D01*
Y1479264D01*
X888532D01*
G01X886932Y1475397D02*
X884532D01*
G01X892332Y1471264D02*
Y1479264D01*
X894332D01*
X895132Y1478864D01*
X895732Y1478331D01*
X896232Y1477531D01*
X896632Y1476597D01*
X896732Y1475264D01*
X896632Y1473931D01*
X896232Y1472997D01*
X895732Y1472197D01*
X895132Y1471664D01*
X894332Y1471264D01*
X892332D01*
G01X910532Y1479264D02*
Y1471264D01*
G01X908232Y1479264D02*
X912832D01*
G01X918532Y1471264D02*
X917732Y1471397D01*
X917032Y1471931D01*
X916432Y1472731D01*
X916032Y1473664D01*
X915832Y1474731D01*
Y1475797D01*
X916032Y1476864D01*
X916432Y1477797D01*
X917032Y1478597D01*
X917732Y1479131D01*
X918532Y1479264D01*
X919332Y1479131D01*
X920032Y1478597D01*
X920632Y1477797D01*
X921032Y1476864D01*
X921232Y1475797D01*
Y1474731D01*
X921032Y1473664D01*
X920632Y1472731D01*
X920032Y1471931D01*
X919332Y1471397D01*
X918532Y1471264D01*
G01X932532D02*
Y1479264D01*
X934932D01*
X935732Y1478864D01*
X936332Y1477931D01*
X936532Y1476864D01*
X936332Y1475797D01*
X935832Y1474997D01*
X934932Y1474597D01*
X932532D01*
G01X940532Y1471264D02*
Y1479264D01*
X943032D01*
X943832Y1478864D01*
X944332Y1478331D01*
X944532Y1477264D01*
X944332Y1476197D01*
X943732Y1475531D01*
X943032Y1475131D01*
X940532D01*
G01X943032D02*
X944532Y1471264D01*
G01X952532D02*
X948532D01*
Y1479264D01*
X952532D01*
G01X950932Y1475397D02*
X948532D01*
G01X956032Y1479264D02*
X958532Y1471264D01*
X961032Y1479264D01*
G01X968532Y1471264D02*
X964532D01*
Y1479264D01*
X968532D01*
G01X966932Y1475397D02*
X964532D01*
G01X972232Y1471264D02*
Y1479264D01*
X976832Y1471264D01*
Y1479264D01*
G01X982532D02*
Y1471264D01*
G01X980232Y1479264D02*
X984832D01*
G01X998532D02*
Y1471264D01*
G01X996232Y1479264D02*
X1000832D01*
G01X1004432Y1471264D02*
Y1479264D01*
G01X1008632D02*
Y1471264D01*
G01Y1475264D02*
X1004432D01*
G01X1016532Y1471264D02*
X1012532D01*
Y1479264D01*
X1016532D01*
G01X1014932Y1475397D02*
X1012532D01*
G01X1028532Y1471264D02*
Y1479264D01*
X1030932D01*
X1031732Y1478864D01*
X1032332Y1477931D01*
X1032532Y1476864D01*
X1032332Y1475797D01*
X1031832Y1474997D01*
X1030932Y1474597D01*
X1028532D01*
G01X1038532Y1471264D02*
X1037732Y1471397D01*
X1037032Y1471931D01*
X1036432Y1472731D01*
X1036032Y1473664D01*
X1035832Y1474731D01*
Y1475797D01*
X1036032Y1476864D01*
X1036432Y1477797D01*
X1037032Y1478597D01*
X1037732Y1479131D01*
X1038532Y1479264D01*
X1039332Y1479131D01*
X1040032Y1478597D01*
X1040632Y1477797D01*
X1041032Y1476864D01*
X1041232Y1475797D01*
Y1474731D01*
X1041032Y1473664D01*
X1040632Y1472731D01*
X1040032Y1471931D01*
X1039332Y1471397D01*
X1038532Y1471264D01*
G01X1046532Y1479264D02*
Y1471264D01*
G01X1044232Y1479264D02*
X1048832D01*
G01X1056532Y1471264D02*
X1052532D01*
Y1479264D01*
X1056532D01*
G01X1054932Y1475397D02*
X1052532D01*
G01X1060232Y1471264D02*
Y1479264D01*
X1064832Y1471264D01*
Y1479264D01*
G01X1070532D02*
Y1471264D01*
G01X1068232Y1479264D02*
X1072832D01*
G01X1077332D02*
X1079732D01*
G01X1078532D02*
Y1471264D01*
G01X1077332D02*
X1079732D01*
G01X1084032D02*
X1086532Y1479264D01*
X1089032Y1471264D01*
G01X1088132Y1474064D02*
X1084932D01*
G01X1092532Y1479264D02*
Y1471264D01*
X1096532D01*
G01X1108532D02*
Y1479264D01*
X1110932D01*
X1111732Y1478864D01*
X1112332Y1477931D01*
X1112532Y1476864D01*
X1112332Y1475797D01*
X1111832Y1474997D01*
X1110932Y1474597D01*
X1108532D01*
G01X1116332Y1479264D02*
Y1473531D01*
X1116732Y1472330D01*
X1117532Y1471531D01*
X1118532Y1471264D01*
X1119532Y1471531D01*
X1120332Y1472330D01*
X1120732Y1473531D01*
Y1479264D01*
G01X1124532D02*
Y1471264D01*
X1128532D01*
G01X1132532Y1479264D02*
Y1471264D01*
X1136532D01*
G01X1148032D02*
X1150532Y1479264D01*
X1153032Y1471264D01*
G01X1152132Y1474064D02*
X1148932D01*
G01X1155532Y1479264D02*
X1156932Y1471264D01*
X1158532Y1479264D01*
X1160132Y1471264D01*
X1161532Y1479264D01*
G01X1164032Y1471264D02*
X1166532Y1479264D01*
X1169032Y1471264D01*
G01X1168132Y1474064D02*
X1164932D01*
G01X1174532Y1471264D02*
Y1474864D01*
X1172532Y1479264D01*
G01X1176532D02*
X1174532Y1474864D01*
G01X1182532Y1470997D02*
X1182332Y1471131D01*
Y1471397D01*
X1182532Y1471531D01*
X1182732Y1471397D01*
Y1471131D01*
X1182532Y1470997D01*
G01X-27168Y1487197D02*
X-26468Y1486531D01*
X-25668Y1486264D01*
X-24868Y1486531D01*
X-24168Y1487330D01*
X-23668Y1488531D01*
X-23468Y1489731D01*
Y1491197D01*
X-23668Y1492397D01*
X-24168Y1493464D01*
X-24768Y1493997D01*
X-25468Y1494264D01*
X-26268Y1493997D01*
X-26868Y1493464D01*
X-27268Y1492664D01*
X-27468Y1491597D01*
X-27268Y1490664D01*
X-26768Y1489731D01*
X-26168Y1489197D01*
X-25468Y1489064D01*
X-24668Y1489330D01*
X-24068Y1489997D01*
X-23468Y1491197D01*
G01X-17468Y1485997D02*
X-17668Y1486131D01*
Y1486397D01*
X-17468Y1486531D01*
X-17268Y1486397D01*
Y1486131D01*
X-17468Y1485997D01*
G01X-11968Y1486264D02*
X-9468Y1494264D01*
X-6968Y1486264D01*
G01X-7868Y1489064D02*
X-11068D01*
G01X-3768Y1486264D02*
Y1494264D01*
X832Y1486264D01*
Y1494264D01*
G01X6532Y1486264D02*
Y1489864D01*
X4532Y1494264D01*
G01X8532D02*
X6532Y1489864D01*
G01X20432Y1487330D02*
X21232Y1486664D01*
X22132Y1486264D01*
X22932D01*
X23732Y1486664D01*
X24332Y1487330D01*
X24632Y1488264D01*
X24432Y1489197D01*
X23932Y1489997D01*
X23032Y1490531D01*
X21832Y1490797D01*
X21132Y1491331D01*
X20832Y1492264D01*
X21032Y1493197D01*
X21532Y1493864D01*
X22232Y1494264D01*
X22932D01*
X23632Y1493997D01*
X24232Y1493331D01*
G01X28532Y1486264D02*
Y1494264D01*
X30932D01*
X31732Y1493864D01*
X32332Y1492931D01*
X32532Y1491864D01*
X32332Y1490797D01*
X31832Y1489997D01*
X30932Y1489597D01*
X28532D01*
G01X40532Y1486264D02*
X36532D01*
Y1494264D01*
X40532D01*
G01X38932Y1490397D02*
X36532D01*
G01X48732Y1493597D02*
X48132Y1493997D01*
X47432Y1494264D01*
X46632D01*
X45732Y1493864D01*
X45032Y1493197D01*
X44532Y1492397D01*
X44132Y1491064D01*
X44032Y1489864D01*
X44232Y1488664D01*
X44532Y1487864D01*
X45132Y1487064D01*
X45832Y1486531D01*
X46532Y1486264D01*
X47232D01*
X47932Y1486531D01*
X48532Y1486931D01*
X49032Y1487464D01*
G01X53332Y1494264D02*
X55732D01*
G01X54532D02*
Y1486264D01*
G01X53332D02*
X55732D01*
G01X60032D02*
X62532Y1494264D01*
X65032Y1486264D01*
G01X64132Y1489064D02*
X60932D01*
G01X68532Y1494264D02*
Y1486264D01*
X72532D01*
G01X84332D02*
Y1494264D01*
X86332D01*
X87132Y1493864D01*
X87732Y1493331D01*
X88232Y1492531D01*
X88632Y1491597D01*
X88732Y1490264D01*
X88632Y1488931D01*
X88232Y1487997D01*
X87732Y1487197D01*
X87132Y1486664D01*
X86332Y1486264D01*
X84332D01*
G01X92532D02*
Y1494264D01*
X95032D01*
X95832Y1493864D01*
X96332Y1493331D01*
X96532Y1492264D01*
X96332Y1491197D01*
X95732Y1490531D01*
X95032Y1490131D01*
X92532D01*
G01X95032D02*
X96532Y1486264D01*
G01X101332Y1494264D02*
X103732D01*
G01X102532D02*
Y1486264D01*
G01X101332D02*
X103732D01*
G01X108532Y1494264D02*
Y1486264D01*
X112532D01*
G01X116532Y1494264D02*
Y1486264D01*
X120532D01*
G01X132032D02*
X134532Y1494264D01*
X137032Y1486264D01*
G01X136132Y1489064D02*
X132932D01*
G01X140232Y1486264D02*
Y1494264D01*
X144832Y1486264D01*
Y1494264D01*
G01X148332Y1486264D02*
Y1494264D01*
X150332D01*
X151132Y1493864D01*
X151732Y1493331D01*
X152232Y1492531D01*
X152632Y1491597D01*
X152732Y1490264D01*
X152632Y1488931D01*
X152232Y1487997D01*
X151732Y1487197D01*
X151132Y1486664D01*
X150332Y1486264D01*
X148332D01*
G01X164432Y1487330D02*
X165232Y1486664D01*
X166132Y1486264D01*
X166932D01*
X167732Y1486664D01*
X168332Y1487330D01*
X168632Y1488264D01*
X168432Y1489197D01*
X167932Y1489997D01*
X167032Y1490531D01*
X165832Y1490797D01*
X165132Y1491331D01*
X164832Y1492264D01*
X165032Y1493197D01*
X165532Y1493864D01*
X166232Y1494264D01*
X166932D01*
X167632Y1493997D01*
X168232Y1493331D01*
G01X174532Y1494264D02*
Y1486264D01*
G01X172232Y1494264D02*
X176832D01*
G01X180032Y1486264D02*
X182532Y1494264D01*
X185032Y1486264D01*
G01X184132Y1489064D02*
X180932D01*
G01X192732Y1493597D02*
X192132Y1493997D01*
X191432Y1494264D01*
X190632D01*
X189732Y1493864D01*
X189032Y1493197D01*
X188532Y1492397D01*
X188132Y1491064D01*
X188032Y1489864D01*
X188232Y1488664D01*
X188532Y1487864D01*
X189132Y1487064D01*
X189832Y1486531D01*
X190532Y1486264D01*
X191232D01*
X191932Y1486531D01*
X192532Y1486931D01*
X193032Y1487464D01*
G01X196332Y1486264D02*
Y1494264D01*
G01X200132D02*
X196332Y1489330D01*
G01X200732Y1486264D02*
X198032Y1491597D01*
G01X208532Y1486264D02*
X204532D01*
Y1494264D01*
X208532D01*
G01X206932Y1490397D02*
X204532D01*
G01X212332Y1486264D02*
Y1494264D01*
X214332D01*
X215132Y1493864D01*
X215732Y1493331D01*
X216232Y1492531D01*
X216632Y1491597D01*
X216732Y1490264D01*
X216632Y1488931D01*
X216232Y1487997D01*
X215732Y1487197D01*
X215132Y1486664D01*
X214332Y1486264D01*
X212332D01*
G01X228432D02*
Y1494264D01*
G01X232632D02*
Y1486264D01*
G01Y1490264D02*
X228432D01*
G01X238532Y1486264D02*
X237732Y1486397D01*
X237032Y1486931D01*
X236432Y1487731D01*
X236032Y1488664D01*
X235832Y1489731D01*
Y1490797D01*
X236032Y1491864D01*
X236432Y1492797D01*
X237032Y1493597D01*
X237732Y1494131D01*
X238532Y1494264D01*
X239332Y1494131D01*
X240032Y1493597D01*
X240632Y1492797D01*
X241032Y1491864D01*
X241232Y1490797D01*
Y1489731D01*
X241032Y1488664D01*
X240632Y1487731D01*
X240032Y1486931D01*
X239332Y1486397D01*
X238532Y1486264D01*
G01X244532Y1494264D02*
Y1486264D01*
X248532D01*
G01X256532D02*
X252532D01*
Y1494264D01*
X256532D01*
G01X254932Y1490397D02*
X252532D01*
G01X268532Y1486264D02*
Y1494264D01*
X270932D01*
X271732Y1493864D01*
X272332Y1492931D01*
X272532Y1491864D01*
X272332Y1490797D01*
X271832Y1489997D01*
X270932Y1489597D01*
X268532D01*
G01X276532Y1494264D02*
Y1486264D01*
X280532D01*
G01X288532D02*
X284532D01*
Y1494264D01*
X288532D01*
G01X286932Y1490397D02*
X284532D01*
G01X292032Y1486264D02*
X294532Y1494264D01*
X297032Y1486264D01*
G01X296132Y1489064D02*
X292932D01*
G01X300432Y1487330D02*
X301232Y1486664D01*
X302132Y1486264D01*
X302932D01*
X303732Y1486664D01*
X304332Y1487330D01*
X304632Y1488264D01*
X304432Y1489197D01*
X303932Y1489997D01*
X303032Y1490531D01*
X301832Y1490797D01*
X301132Y1491331D01*
X300832Y1492264D01*
X301032Y1493197D01*
X301532Y1493864D01*
X302232Y1494264D01*
X302932D01*
X303632Y1493997D01*
X304232Y1493331D01*
G01X312532Y1486264D02*
X308532D01*
Y1494264D01*
X312532D01*
G01X310932Y1490397D02*
X308532D01*
G01X324632Y1486264D02*
Y1494264D01*
X328432D01*
G01X327032Y1490397D02*
X324632D01*
G01X334532Y1486264D02*
X333732Y1486397D01*
X333032Y1486931D01*
X332432Y1487731D01*
X332032Y1488664D01*
X331832Y1489731D01*
Y1490797D01*
X332032Y1491864D01*
X332432Y1492797D01*
X333032Y1493597D01*
X333732Y1494131D01*
X334532Y1494264D01*
X335332Y1494131D01*
X336032Y1493597D01*
X336632Y1492797D01*
X337032Y1491864D01*
X337232Y1490797D01*
Y1489731D01*
X337032Y1488664D01*
X336632Y1487731D01*
X336032Y1486931D01*
X335332Y1486397D01*
X334532Y1486264D01*
G01X340532Y1494264D02*
Y1486264D01*
X344532D01*
G01X348532Y1494264D02*
Y1486264D01*
X352532D01*
G01X358532D02*
X357732Y1486397D01*
X357032Y1486931D01*
X356432Y1487731D01*
X356032Y1488664D01*
X355832Y1489731D01*
Y1490797D01*
X356032Y1491864D01*
X356432Y1492797D01*
X357032Y1493597D01*
X357732Y1494131D01*
X358532Y1494264D01*
X359332Y1494131D01*
X360032Y1493597D01*
X360632Y1492797D01*
X361032Y1491864D01*
X361232Y1490797D01*
Y1489731D01*
X361032Y1488664D01*
X360632Y1487731D01*
X360032Y1486931D01*
X359332Y1486397D01*
X358532Y1486264D01*
G01X363532Y1494264D02*
X364932Y1486264D01*
X366532Y1494264D01*
X368132Y1486264D01*
X369532Y1494264D01*
G01X382532Y1486264D02*
X381732Y1486397D01*
X381032Y1486931D01*
X380432Y1487731D01*
X380032Y1488664D01*
X379832Y1489731D01*
Y1490797D01*
X380032Y1491864D01*
X380432Y1492797D01*
X381032Y1493597D01*
X381732Y1494131D01*
X382532Y1494264D01*
X383332Y1494131D01*
X384032Y1493597D01*
X384632Y1492797D01*
X385032Y1491864D01*
X385232Y1490797D01*
Y1489731D01*
X385032Y1488664D01*
X384632Y1487731D01*
X384032Y1486931D01*
X383332Y1486397D01*
X382532Y1486264D01*
G01X388332Y1494264D02*
Y1488531D01*
X388732Y1487330D01*
X389532Y1486531D01*
X390532Y1486264D01*
X391532Y1486531D01*
X392332Y1487330D01*
X392732Y1488531D01*
Y1494264D01*
G01X398532D02*
Y1486264D01*
G01X396232Y1494264D02*
X400832D01*
G01X404532D02*
Y1486264D01*
X408532D01*
G01X413332Y1494264D02*
X415732D01*
G01X414532D02*
Y1486264D01*
G01X413332D02*
X415732D01*
G01X420232D02*
Y1494264D01*
X424832Y1486264D01*
Y1494264D01*
G01X432532Y1486264D02*
X428532D01*
Y1494264D01*
X432532D01*
G01X430932Y1490397D02*
X428532D01*
G01X438532Y1485997D02*
X438332Y1486131D01*
Y1486397D01*
X438532Y1486531D01*
X438732Y1486397D01*
Y1486131D01*
X438532Y1485997D01*
G01X452532Y1486264D02*
Y1494264D01*
X454932D01*
X455732Y1493864D01*
X456332Y1492931D01*
X456532Y1491864D01*
X456332Y1490797D01*
X455832Y1489997D01*
X454932Y1489597D01*
X452532D01*
G01X462532Y1494264D02*
Y1486264D01*
G01X460232Y1494264D02*
X464832D01*
G01X468432Y1486264D02*
Y1494264D01*
G01X472632D02*
Y1486264D01*
G01Y1490264D02*
X468432D01*
G01X486532Y1494264D02*
Y1486264D01*
G01X484232Y1494264D02*
X488832D01*
G01X494532Y1486264D02*
X493732Y1486397D01*
X493032Y1486931D01*
X492432Y1487731D01*
X492032Y1488664D01*
X491832Y1489731D01*
Y1490797D01*
X492032Y1491864D01*
X492432Y1492797D01*
X493032Y1493597D01*
X493732Y1494131D01*
X494532Y1494264D01*
X495332Y1494131D01*
X496032Y1493597D01*
X496632Y1492797D01*
X497032Y1491864D01*
X497232Y1490797D01*
Y1489731D01*
X497032Y1488664D01*
X496632Y1487731D01*
X496032Y1486931D01*
X495332Y1486397D01*
X494532Y1486264D01*
G01X500532Y1494264D02*
Y1486264D01*
X504532D01*
G01X512532D02*
X508532D01*
Y1494264D01*
X512532D01*
G01X510932Y1490397D02*
X508532D01*
G01X516532Y1486264D02*
Y1494264D01*
X519032D01*
X519832Y1493864D01*
X520332Y1493331D01*
X520532Y1492264D01*
X520332Y1491197D01*
X519732Y1490531D01*
X519032Y1490131D01*
X516532D01*
G01X519032D02*
X520532Y1486264D01*
G01X524032D02*
X526532Y1494264D01*
X529032Y1486264D01*
G01X528132Y1489064D02*
X524932D01*
G01X532232Y1486264D02*
Y1494264D01*
X536832Y1486264D01*
Y1494264D01*
G01X544732Y1493597D02*
X544132Y1493997D01*
X543432Y1494264D01*
X542632D01*
X541732Y1493864D01*
X541032Y1493197D01*
X540532Y1492397D01*
X540132Y1491064D01*
X540032Y1489864D01*
X540232Y1488664D01*
X540532Y1487864D01*
X541132Y1487064D01*
X541832Y1486531D01*
X542532Y1486264D01*
X543232D01*
X543932Y1486531D01*
X544532Y1486931D01*
X545032Y1487464D01*
G01X552532Y1486264D02*
X548532D01*
Y1494264D01*
X552532D01*
G01X550932Y1490397D02*
X548532D01*
G01X566532Y1485997D02*
X566332Y1486131D01*
Y1486397D01*
X566532Y1486531D01*
X566732Y1486397D01*
Y1486131D01*
X566532Y1485997D01*
G01Y1489597D02*
X566332Y1489731D01*
Y1489997D01*
X566532Y1490131D01*
X566732Y1489997D01*
Y1489731D01*
X566532Y1489597D01*
G01X581432Y1488931D02*
X583832D01*
G01X582532Y1490664D02*
Y1487197D01*
G01X588732Y1485997D02*
X592332Y1494264D01*
G01X597232Y1488931D02*
X599832D01*
G01X604332Y1487464D02*
X604932Y1486797D01*
X605632Y1486397D01*
X606532Y1486264D01*
X607432Y1486531D01*
X608132Y1487064D01*
X608632Y1487997D01*
X608732Y1489064D01*
X608532Y1490131D01*
X608032Y1490797D01*
X607332Y1491331D01*
X606632Y1491464D01*
X605932Y1491331D01*
X605032Y1490797D01*
X605332Y1494264D01*
X608032D01*
G01X614032Y1483597D02*
X613032Y1484931D01*
X612532Y1486264D01*
Y1491597D01*
X613032Y1492931D01*
X614032Y1494264D01*
G01X619932Y1486264D02*
Y1494264D01*
X622532Y1487597D01*
X625132Y1494264D01*
Y1486264D01*
G01X629332Y1494264D02*
X631732D01*
G01X630532D02*
Y1486264D01*
G01X629332D02*
X631732D01*
G01X636532Y1494264D02*
Y1486264D01*
X640532D01*
G01X647032Y1483597D02*
X648032Y1484931D01*
X648532Y1486264D01*
Y1491597D01*
X648032Y1492931D01*
X647032Y1494264D01*
G01X654332Y1484797D02*
X654732Y1486531D01*
G01X668232Y1486264D02*
Y1494264D01*
X672832Y1486264D01*
Y1494264D01*
G01X676532Y1486264D02*
Y1494264D01*
X678932D01*
X679732Y1493864D01*
X680332Y1492931D01*
X680532Y1491864D01*
X680332Y1490797D01*
X679832Y1489997D01*
X678932Y1489597D01*
X676532D01*
G01X686532Y1494264D02*
Y1486264D01*
G01X684232Y1494264D02*
X688832D01*
G01X692432Y1486264D02*
Y1494264D01*
G01X696632D02*
Y1486264D01*
G01Y1490264D02*
X692432D01*
G01X710532Y1494264D02*
Y1486264D01*
G01X708232Y1494264D02*
X712832D01*
G01X718532Y1486264D02*
X717732Y1486397D01*
X717032Y1486931D01*
X716432Y1487731D01*
X716032Y1488664D01*
X715832Y1489731D01*
Y1490797D01*
X716032Y1491864D01*
X716432Y1492797D01*
X717032Y1493597D01*
X717732Y1494131D01*
X718532Y1494264D01*
X719332Y1494131D01*
X720032Y1493597D01*
X720632Y1492797D01*
X721032Y1491864D01*
X721232Y1490797D01*
Y1489731D01*
X721032Y1488664D01*
X720632Y1487731D01*
X720032Y1486931D01*
X719332Y1486397D01*
X718532Y1486264D01*
G01X724532Y1494264D02*
Y1486264D01*
X728532D01*
G01X736532D02*
X732532D01*
Y1494264D01*
X736532D01*
G01X734932Y1490397D02*
X732532D01*
G01X740532Y1486264D02*
Y1494264D01*
X743032D01*
X743832Y1493864D01*
X744332Y1493331D01*
X744532Y1492264D01*
X744332Y1491197D01*
X743732Y1490531D01*
X743032Y1490131D01*
X740532D01*
G01X743032D02*
X744532Y1486264D01*
G01X748032D02*
X750532Y1494264D01*
X753032Y1486264D01*
G01X752132Y1489064D02*
X748932D01*
G01X756232Y1486264D02*
Y1494264D01*
X760832Y1486264D01*
Y1494264D01*
G01X768732Y1493597D02*
X768132Y1493997D01*
X767432Y1494264D01*
X766632D01*
X765732Y1493864D01*
X765032Y1493197D01*
X764532Y1492397D01*
X764132Y1491064D01*
X764032Y1489864D01*
X764232Y1488664D01*
X764532Y1487864D01*
X765132Y1487064D01*
X765832Y1486531D01*
X766532Y1486264D01*
X767232D01*
X767932Y1486531D01*
X768532Y1486931D01*
X769032Y1487464D01*
G01X776532Y1486264D02*
X772532D01*
Y1494264D01*
X776532D01*
G01X774932Y1490397D02*
X772532D01*
G01X782532Y1485997D02*
X782332Y1486131D01*
Y1486397D01*
X782532Y1486531D01*
X782732Y1486397D01*
Y1486131D01*
X782532Y1485997D01*
G01Y1489597D02*
X782332Y1489731D01*
Y1489997D01*
X782532Y1490131D01*
X782732Y1489997D01*
Y1489731D01*
X782532Y1489597D01*
G01X797432Y1488931D02*
X799832D01*
G01X798532Y1490664D02*
Y1487197D01*
G01X804732Y1485997D02*
X808332Y1494264D01*
G01X813232Y1488931D02*
X815832D01*
G01X823732Y1486264D02*
Y1494264D01*
X820032Y1488531D01*
X825032D01*
G01X830032Y1483597D02*
X829032Y1484931D01*
X828532Y1486264D01*
Y1491597D01*
X829032Y1492931D01*
X830032Y1494264D01*
G01X835932Y1486264D02*
Y1494264D01*
X838532Y1487597D01*
X841132Y1494264D01*
Y1486264D01*
G01X845332Y1494264D02*
X847732D01*
G01X846532D02*
Y1486264D01*
G01X845332D02*
X847732D01*
G01X852532Y1494264D02*
Y1486264D01*
X856532D01*
G01X863032Y1483597D02*
X864032Y1484931D01*
X864532Y1486264D01*
Y1491597D01*
X864032Y1492931D01*
X863032Y1494264D01*
G01X870532Y1485997D02*
X870332Y1486131D01*
Y1486397D01*
X870532Y1486531D01*
X870732Y1486397D01*
Y1486131D01*
X870532Y1485997D01*
G01X-25468Y1501264D02*
X-24768Y1501397D01*
X-23968Y1501797D01*
X-23468Y1502464D01*
X-23268Y1503397D01*
X-23468Y1504330D01*
X-24068Y1505131D01*
X-24968Y1505531D01*
X-25968D01*
X-26568Y1505797D01*
X-27068Y1506464D01*
X-27268Y1507397D01*
X-26968Y1508331D01*
X-26268Y1508997D01*
X-25468Y1509264D01*
X-24668Y1508997D01*
X-23968Y1508331D01*
X-23668Y1507397D01*
X-23868Y1506464D01*
X-24368Y1505797D01*
X-24968Y1505531D01*
X-25968D01*
X-26868Y1505131D01*
X-27468Y1504330D01*
X-27668Y1503397D01*
X-27468Y1502464D01*
X-26968Y1501797D01*
X-26168Y1501397D01*
X-25468Y1501264D01*
G01X-17468Y1500997D02*
X-17668Y1501131D01*
Y1501397D01*
X-17468Y1501531D01*
X-17268Y1501397D01*
Y1501131D01*
X-17468Y1500997D01*
G01X-11768Y1501264D02*
Y1509264D01*
X-7168Y1501264D01*
Y1509264D01*
G01X-1468Y1501264D02*
X-2268Y1501397D01*
X-2968Y1501931D01*
X-3568Y1502731D01*
X-3968Y1503664D01*
X-4168Y1504731D01*
Y1505797D01*
X-3968Y1506864D01*
X-3568Y1507797D01*
X-2968Y1508597D01*
X-2268Y1509131D01*
X-1468Y1509264D01*
X-668Y1509131D01*
X32Y1508597D01*
X632Y1507797D01*
X1032Y1506864D01*
X1232Y1505797D01*
Y1504731D01*
X1032Y1503664D01*
X632Y1502731D01*
X32Y1501931D01*
X-668Y1501397D01*
X-1468Y1501264D01*
G01X6532Y1509264D02*
Y1501264D01*
G01X4232Y1509264D02*
X8832D01*
G01X20032Y1501264D02*
X22532Y1509264D01*
X25032Y1501264D01*
G01X24132Y1504064D02*
X20932D01*
G01X28532Y1509264D02*
Y1501264D01*
X32532D01*
G01X36532Y1509264D02*
Y1501264D01*
X40532D01*
G01X46532D02*
X45732Y1501397D01*
X45032Y1501931D01*
X44432Y1502731D01*
X44032Y1503664D01*
X43832Y1504731D01*
Y1505797D01*
X44032Y1506864D01*
X44432Y1507797D01*
X45032Y1508597D01*
X45732Y1509131D01*
X46532Y1509264D01*
X47332Y1509131D01*
X48032Y1508597D01*
X48632Y1507797D01*
X49032Y1506864D01*
X49232Y1505797D01*
Y1504731D01*
X49032Y1503664D01*
X48632Y1502731D01*
X48032Y1501931D01*
X47332Y1501397D01*
X46532Y1501264D01*
G01X51532Y1509264D02*
X52932Y1501264D01*
X54532Y1509264D01*
X56132Y1501264D01*
X57532Y1509264D01*
G01X71332Y1505531D02*
X71732Y1505931D01*
X72032Y1506597D01*
X72232Y1507531D01*
X72032Y1508331D01*
X71632Y1508864D01*
X70932Y1509264D01*
X68232D01*
Y1501264D01*
X71532D01*
X72232Y1501797D01*
X72632Y1502597D01*
X72832Y1503531D01*
X72632Y1504464D01*
X72032Y1505264D01*
X71332Y1505531D01*
X68232D01*
G01X76532Y1501264D02*
Y1509264D01*
X79032D01*
X79832Y1508864D01*
X80332Y1508331D01*
X80532Y1507264D01*
X80332Y1506197D01*
X79732Y1505531D01*
X79032Y1505131D01*
X76532D01*
G01X79032D02*
X80532Y1501264D01*
G01X88532D02*
X84532D01*
Y1509264D01*
X88532D01*
G01X86932Y1505397D02*
X84532D01*
G01X92032Y1501264D02*
X94532Y1509264D01*
X97032Y1501264D01*
G01X96132Y1504064D02*
X92932D01*
G01X100332Y1501264D02*
Y1509264D01*
G01X104132D02*
X100332Y1504330D01*
G01X104732Y1501264D02*
X102032Y1506597D01*
G01X110532Y1501264D02*
X109732Y1501397D01*
X109032Y1501931D01*
X108432Y1502731D01*
X108032Y1503664D01*
X107832Y1504731D01*
Y1505797D01*
X108032Y1506864D01*
X108432Y1507797D01*
X109032Y1508597D01*
X109732Y1509131D01*
X110532Y1509264D01*
X111332Y1509131D01*
X112032Y1508597D01*
X112632Y1507797D01*
X113032Y1506864D01*
X113232Y1505797D01*
Y1504731D01*
X113032Y1503664D01*
X112632Y1502731D01*
X112032Y1501931D01*
X111332Y1501397D01*
X110532Y1501264D01*
G01X116332Y1509264D02*
Y1503531D01*
X116732Y1502330D01*
X117532Y1501531D01*
X118532Y1501264D01*
X119532Y1501531D01*
X120332Y1502330D01*
X120732Y1503531D01*
Y1509264D01*
G01X126532D02*
Y1501264D01*
G01X124232Y1509264D02*
X128832D01*
G01X140632Y1501264D02*
Y1509264D01*
X144432D01*
G01X143032Y1505397D02*
X140632D01*
G01X150532Y1501264D02*
X149732Y1501397D01*
X149032Y1501931D01*
X148432Y1502731D01*
X148032Y1503664D01*
X147832Y1504731D01*
Y1505797D01*
X148032Y1506864D01*
X148432Y1507797D01*
X149032Y1508597D01*
X149732Y1509131D01*
X150532Y1509264D01*
X151332Y1509131D01*
X152032Y1508597D01*
X152632Y1507797D01*
X153032Y1506864D01*
X153232Y1505797D01*
Y1504731D01*
X153032Y1503664D01*
X152632Y1502731D01*
X152032Y1501931D01*
X151332Y1501397D01*
X150532Y1501264D01*
G01X156532D02*
Y1509264D01*
X159032D01*
X159832Y1508864D01*
X160332Y1508331D01*
X160532Y1507264D01*
X160332Y1506197D01*
X159732Y1505531D01*
X159032Y1505131D01*
X156532D01*
G01X159032D02*
X160532Y1501264D01*
G01X172532Y1509264D02*
Y1501264D01*
X176532D01*
G01X180032D02*
X182532Y1509264D01*
X185032Y1501264D01*
G01X184132Y1504064D02*
X180932D01*
G01X188432Y1502330D02*
X189232Y1501664D01*
X190132Y1501264D01*
X190932D01*
X191732Y1501664D01*
X192332Y1502330D01*
X192632Y1503264D01*
X192432Y1504197D01*
X191932Y1504997D01*
X191032Y1505531D01*
X189832Y1505797D01*
X189132Y1506331D01*
X188832Y1507264D01*
X189032Y1508197D01*
X189532Y1508864D01*
X190232Y1509264D01*
X190932D01*
X191632Y1508997D01*
X192232Y1508331D01*
G01X200532Y1501264D02*
X196532D01*
Y1509264D01*
X200532D01*
G01X198932Y1505397D02*
X196532D01*
G01X204532Y1501264D02*
Y1509264D01*
X207032D01*
X207832Y1508864D01*
X208332Y1508331D01*
X208532Y1507264D01*
X208332Y1506197D01*
X207732Y1505531D01*
X207032Y1505131D01*
X204532D01*
G01X207032D02*
X208532Y1501264D01*
G01X220032Y1509264D02*
X222532Y1501264D01*
X225032Y1509264D01*
G01X229332D02*
X231732D01*
G01X230532D02*
Y1501264D01*
G01X229332D02*
X231732D01*
G01X236032D02*
X238532Y1509264D01*
X241032Y1501264D01*
G01X240132Y1504064D02*
X236932D01*
G01X252432Y1501264D02*
Y1509264D01*
G01X256632D02*
Y1501264D01*
G01Y1505264D02*
X252432D01*
G01X262532Y1501264D02*
X261732Y1501397D01*
X261032Y1501931D01*
X260432Y1502731D01*
X260032Y1503664D01*
X259832Y1504731D01*
Y1505797D01*
X260032Y1506864D01*
X260432Y1507797D01*
X261032Y1508597D01*
X261732Y1509131D01*
X262532Y1509264D01*
X263332Y1509131D01*
X264032Y1508597D01*
X264632Y1507797D01*
X265032Y1506864D01*
X265232Y1505797D01*
Y1504731D01*
X265032Y1503664D01*
X264632Y1502731D01*
X264032Y1501931D01*
X263332Y1501397D01*
X262532Y1501264D01*
G01X268532Y1509264D02*
Y1501264D01*
X272532D01*
G01X280532D02*
X276532D01*
Y1509264D01*
X280532D01*
G01X278932Y1505397D02*
X276532D01*
G01X286532Y1500997D02*
X286332Y1501131D01*
Y1501397D01*
X286532Y1501531D01*
X286732Y1501397D01*
Y1501131D01*
X286532Y1500997D01*
G01X-25668Y1516264D02*
X-25468Y1517997D01*
X-25168Y1519464D01*
X-24768Y1520797D01*
X-24268Y1522264D01*
X-23468Y1524264D01*
X-27468D01*
G01X-17468Y1515997D02*
X-17668Y1516131D01*
Y1516397D01*
X-17468Y1516531D01*
X-17268Y1516397D01*
Y1516131D01*
X-17468Y1515997D01*
G01X-11368Y1516264D02*
Y1524264D01*
X-7568D01*
G01X-8968Y1520397D02*
X-11368D01*
G01X-1468Y1516264D02*
X-2268Y1516397D01*
X-2968Y1516931D01*
X-3568Y1517731D01*
X-3968Y1518664D01*
X-4168Y1519731D01*
Y1520797D01*
X-3968Y1521864D01*
X-3568Y1522797D01*
X-2968Y1523597D01*
X-2268Y1524131D01*
X-1468Y1524264D01*
X-668Y1524131D01*
X32Y1523597D01*
X632Y1522797D01*
X1032Y1521864D01*
X1232Y1520797D01*
Y1519731D01*
X1032Y1518664D01*
X632Y1517731D01*
X32Y1516931D01*
X-668Y1516397D01*
X-1468Y1516264D01*
G01X4532D02*
Y1524264D01*
X7032D01*
X7832Y1523864D01*
X8332Y1523331D01*
X8532Y1522264D01*
X8332Y1521197D01*
X7732Y1520531D01*
X7032Y1520131D01*
X4532D01*
G01X7032D02*
X8532Y1516264D01*
G01X22532D02*
Y1524264D01*
X21332Y1522664D01*
G01Y1516264D02*
X23732D01*
G01X30532Y1524264D02*
X29732Y1523997D01*
X29132Y1523331D01*
X28732Y1522531D01*
X28432Y1521464D01*
X28332Y1520264D01*
X28432Y1519064D01*
X28732Y1517997D01*
X29132Y1517197D01*
X29732Y1516531D01*
X30532Y1516264D01*
X31332Y1516531D01*
X31932Y1517197D01*
X32332Y1517997D01*
X32632Y1519064D01*
X32732Y1520264D01*
X32632Y1521464D01*
X32332Y1522531D01*
X31932Y1523331D01*
X31332Y1523997D01*
X30532Y1524264D01*
G01X35932Y1516264D02*
Y1524264D01*
X38532Y1517597D01*
X41132Y1524264D01*
Y1516264D01*
G01X45332Y1524264D02*
X47732D01*
G01X46532D02*
Y1516264D01*
G01X45332D02*
X47732D01*
G01X52532Y1524264D02*
Y1516264D01*
X56532D01*
G01X60432Y1517330D02*
X61232Y1516664D01*
X62132Y1516264D01*
X62932D01*
X63732Y1516664D01*
X64332Y1517330D01*
X64632Y1518264D01*
X64432Y1519197D01*
X63932Y1519997D01*
X63032Y1520531D01*
X61832Y1520797D01*
X61132Y1521331D01*
X60832Y1522264D01*
X61032Y1523197D01*
X61532Y1523864D01*
X62232Y1524264D01*
X62932D01*
X63632Y1523997D01*
X64232Y1523331D01*
G01X76032Y1524264D02*
X78532Y1516264D01*
X81032Y1524264D01*
G01X85332D02*
X87732D01*
G01X86532D02*
Y1516264D01*
G01X85332D02*
X87732D01*
G01X92032D02*
X94532Y1524264D01*
X97032Y1516264D01*
G01X96132Y1519064D02*
X92932D01*
G01X100432Y1517330D02*
X101232Y1516664D01*
X102132Y1516264D01*
X102932D01*
X103732Y1516664D01*
X104332Y1517330D01*
X104632Y1518264D01*
X104432Y1519197D01*
X103932Y1519997D01*
X103032Y1520531D01*
X101832Y1520797D01*
X101132Y1521331D01*
X100832Y1522264D01*
X101032Y1523197D01*
X101532Y1523864D01*
X102232Y1524264D01*
X102932D01*
X103632Y1523997D01*
X104232Y1523331D01*
G01X116332Y1524264D02*
Y1518531D01*
X116732Y1517330D01*
X117532Y1516531D01*
X118532Y1516264D01*
X119532Y1516531D01*
X120332Y1517330D01*
X120732Y1518531D01*
Y1524264D01*
G01X124432Y1517330D02*
X125232Y1516664D01*
X126132Y1516264D01*
X126932D01*
X127732Y1516664D01*
X128332Y1517330D01*
X128632Y1518264D01*
X128432Y1519197D01*
X127932Y1519997D01*
X127032Y1520531D01*
X125832Y1520797D01*
X125132Y1521331D01*
X124832Y1522264D01*
X125032Y1523197D01*
X125532Y1523864D01*
X126232Y1524264D01*
X126932D01*
X127632Y1523997D01*
X128232Y1523331D01*
G01X136532Y1516264D02*
X132532D01*
Y1524264D01*
X136532D01*
G01X134932Y1520397D02*
X132532D01*
G01X148832Y1517197D02*
X149532Y1516531D01*
X150332Y1516264D01*
X151132Y1516531D01*
X151832Y1517330D01*
X152332Y1518531D01*
X152532Y1519731D01*
Y1521197D01*
X152332Y1522397D01*
X151832Y1523464D01*
X151232Y1523997D01*
X150532Y1524264D01*
X149732Y1523997D01*
X149132Y1523464D01*
X148732Y1522664D01*
X148532Y1521597D01*
X148732Y1520664D01*
X149232Y1519731D01*
X149832Y1519197D01*
X150532Y1519064D01*
X151332Y1519330D01*
X151932Y1519997D01*
X152532Y1521197D01*
G01X158532Y1515997D02*
X158332Y1516131D01*
Y1516397D01*
X158532Y1516531D01*
X158732Y1516397D01*
Y1516131D01*
X158532Y1515997D01*
G01X166532Y1516264D02*
X167232Y1516397D01*
X168032Y1516797D01*
X168532Y1517464D01*
X168732Y1518397D01*
X168532Y1519330D01*
X167932Y1520131D01*
X167032Y1520531D01*
X166032D01*
X165432Y1520797D01*
X164932Y1521464D01*
X164732Y1522397D01*
X165032Y1523331D01*
X165732Y1523997D01*
X166532Y1524264D01*
X167332Y1523997D01*
X168032Y1523331D01*
X168332Y1522397D01*
X168132Y1521464D01*
X167632Y1520797D01*
X167032Y1520531D01*
X166032D01*
X165132Y1520131D01*
X164532Y1519330D01*
X164332Y1518397D01*
X164532Y1517464D01*
X165032Y1516797D01*
X165832Y1516397D01*
X166532Y1516264D01*
G01X171932D02*
Y1524264D01*
X174532Y1517597D01*
X177132Y1524264D01*
Y1516264D01*
G01X181332Y1524264D02*
X183732D01*
G01X182532D02*
Y1516264D01*
G01X181332D02*
X183732D01*
G01X188532Y1524264D02*
Y1516264D01*
X192532D01*
G01X196432Y1517330D02*
X197232Y1516664D01*
X198132Y1516264D01*
X198932D01*
X199732Y1516664D01*
X200332Y1517330D01*
X200632Y1518264D01*
X200432Y1519197D01*
X199932Y1519997D01*
X199032Y1520531D01*
X197832Y1520797D01*
X197132Y1521331D01*
X196832Y1522264D01*
X197032Y1523197D01*
X197532Y1523864D01*
X198232Y1524264D01*
X198932D01*
X199632Y1523997D01*
X200232Y1523331D01*
G01X212332Y1516264D02*
Y1524264D01*
X214332D01*
X215132Y1523864D01*
X215732Y1523331D01*
X216232Y1522531D01*
X216632Y1521597D01*
X216732Y1520264D01*
X216632Y1518931D01*
X216232Y1517997D01*
X215732Y1517197D01*
X215132Y1516664D01*
X214332Y1516264D01*
X212332D01*
G01X220532D02*
Y1524264D01*
X223032D01*
X223832Y1523864D01*
X224332Y1523331D01*
X224532Y1522264D01*
X224332Y1521197D01*
X223732Y1520531D01*
X223032Y1520131D01*
X220532D01*
G01X223032D02*
X224532Y1516264D01*
G01X229332Y1524264D02*
X231732D01*
G01X230532D02*
Y1516264D01*
G01X229332D02*
X231732D01*
G01X236532Y1524264D02*
Y1516264D01*
X240532D01*
G01X244532Y1524264D02*
Y1516264D01*
X248532D01*
G01X263332Y1520531D02*
X263732Y1520931D01*
X264032Y1521597D01*
X264232Y1522531D01*
X264032Y1523331D01*
X263632Y1523864D01*
X262932Y1524264D01*
X260232D01*
Y1516264D01*
X263532D01*
X264232Y1516797D01*
X264632Y1517597D01*
X264832Y1518531D01*
X264632Y1519464D01*
X264032Y1520264D01*
X263332Y1520531D01*
X260232D01*
G01X269332Y1524264D02*
X271732D01*
G01X270532D02*
Y1516264D01*
G01X269332D02*
X271732D01*
G01X278532Y1524264D02*
Y1516264D01*
G01X276232Y1524264D02*
X280832D01*
G01X286532Y1515997D02*
X286332Y1516131D01*
Y1516397D01*
X286532Y1516531D01*
X286732Y1516397D01*
Y1516131D01*
X286532Y1515997D01*
G01X300632Y1516264D02*
Y1524264D01*
X304432D01*
G01X303032Y1520397D02*
X300632D01*
G01X310532Y1516264D02*
X309732Y1516397D01*
X309032Y1516931D01*
X308432Y1517731D01*
X308032Y1518664D01*
X307832Y1519731D01*
Y1520797D01*
X308032Y1521864D01*
X308432Y1522797D01*
X309032Y1523597D01*
X309732Y1524131D01*
X310532Y1524264D01*
X311332Y1524131D01*
X312032Y1523597D01*
X312632Y1522797D01*
X313032Y1521864D01*
X313232Y1520797D01*
Y1519731D01*
X313032Y1518664D01*
X312632Y1517731D01*
X312032Y1516931D01*
X311332Y1516397D01*
X310532Y1516264D01*
G01X316532D02*
Y1524264D01*
X319032D01*
X319832Y1523864D01*
X320332Y1523331D01*
X320532Y1522264D01*
X320332Y1521197D01*
X319732Y1520531D01*
X319032Y1520131D01*
X316532D01*
G01X319032D02*
X320532Y1516264D01*
G01X334532D02*
X335232Y1516397D01*
X336032Y1516797D01*
X336532Y1517464D01*
X336732Y1518397D01*
X336532Y1519330D01*
X335932Y1520131D01*
X335032Y1520531D01*
X334032D01*
X333432Y1520797D01*
X332932Y1521464D01*
X332732Y1522397D01*
X333032Y1523331D01*
X333732Y1523997D01*
X334532Y1524264D01*
X335332Y1523997D01*
X336032Y1523331D01*
X336332Y1522397D01*
X336132Y1521464D01*
X335632Y1520797D01*
X335032Y1520531D01*
X334032D01*
X333132Y1520131D01*
X332532Y1519330D01*
X332332Y1518397D01*
X332532Y1517464D01*
X333032Y1516797D01*
X333832Y1516397D01*
X334532Y1516264D01*
G01X339932D02*
Y1524264D01*
X342532Y1517597D01*
X345132Y1524264D01*
Y1516264D01*
G01X349332Y1524264D02*
X351732D01*
G01X350532D02*
Y1516264D01*
G01X349332D02*
X351732D01*
G01X356532Y1524264D02*
Y1516264D01*
X360532D01*
G01X364432Y1517330D02*
X365232Y1516664D01*
X366132Y1516264D01*
X366932D01*
X367732Y1516664D01*
X368332Y1517330D01*
X368632Y1518264D01*
X368432Y1519197D01*
X367932Y1519997D01*
X367032Y1520531D01*
X365832Y1520797D01*
X365132Y1521331D01*
X364832Y1522264D01*
X365032Y1523197D01*
X365532Y1523864D01*
X366232Y1524264D01*
X366932D01*
X367632Y1523997D01*
X368232Y1523331D01*
G01X380032Y1524264D02*
X382532Y1516264D01*
X385032Y1524264D01*
G01X389332D02*
X391732D01*
G01X390532D02*
Y1516264D01*
G01X389332D02*
X391732D01*
G01X396032D02*
X398532Y1524264D01*
X401032Y1516264D01*
G01X400132Y1519064D02*
X396932D01*
G01X404432Y1517330D02*
X405232Y1516664D01*
X406132Y1516264D01*
X406932D01*
X407732Y1516664D01*
X408332Y1517330D01*
X408632Y1518264D01*
X408432Y1519197D01*
X407932Y1519997D01*
X407032Y1520531D01*
X405832Y1520797D01*
X405132Y1521331D01*
X404832Y1522264D01*
X405032Y1523197D01*
X405532Y1523864D01*
X406232Y1524264D01*
X406932D01*
X407632Y1523997D01*
X408232Y1523331D01*
G01X420332Y1524264D02*
Y1518531D01*
X420732Y1517330D01*
X421532Y1516531D01*
X422532Y1516264D01*
X423532Y1516531D01*
X424332Y1517330D01*
X424732Y1518531D01*
Y1524264D01*
G01X428432Y1517330D02*
X429232Y1516664D01*
X430132Y1516264D01*
X430932D01*
X431732Y1516664D01*
X432332Y1517330D01*
X432632Y1518264D01*
X432432Y1519197D01*
X431932Y1519997D01*
X431032Y1520531D01*
X429832Y1520797D01*
X429132Y1521331D01*
X428832Y1522264D01*
X429032Y1523197D01*
X429532Y1523864D01*
X430232Y1524264D01*
X430932D01*
X431632Y1523997D01*
X432232Y1523331D01*
G01X440532Y1516264D02*
X436532D01*
Y1524264D01*
X440532D01*
G01X438932Y1520397D02*
X436532D01*
G01X454332Y1516264D02*
X454532Y1517997D01*
X454832Y1519464D01*
X455232Y1520797D01*
X455732Y1522264D01*
X456532Y1524264D01*
X452532D01*
G01X462532Y1515997D02*
X462332Y1516131D01*
Y1516397D01*
X462532Y1516531D01*
X462732Y1516397D01*
Y1516131D01*
X462532Y1515997D01*
G01X468832Y1517197D02*
X469532Y1516531D01*
X470332Y1516264D01*
X471132Y1516531D01*
X471832Y1517330D01*
X472332Y1518531D01*
X472532Y1519731D01*
Y1521197D01*
X472332Y1522397D01*
X471832Y1523464D01*
X471232Y1523997D01*
X470532Y1524264D01*
X469732Y1523997D01*
X469132Y1523464D01*
X468732Y1522664D01*
X468532Y1521597D01*
X468732Y1520664D01*
X469232Y1519731D01*
X469832Y1519197D01*
X470532Y1519064D01*
X471332Y1519330D01*
X471932Y1519997D01*
X472532Y1521197D01*
G01X475932Y1516264D02*
Y1524264D01*
X478532Y1517597D01*
X481132Y1524264D01*
Y1516264D01*
G01X485332Y1524264D02*
X487732D01*
G01X486532D02*
Y1516264D01*
G01X485332D02*
X487732D01*
G01X492532Y1524264D02*
Y1516264D01*
X496532D01*
G01X500432Y1517330D02*
X501232Y1516664D01*
X502132Y1516264D01*
X502932D01*
X503732Y1516664D01*
X504332Y1517330D01*
X504632Y1518264D01*
X504432Y1519197D01*
X503932Y1519997D01*
X503032Y1520531D01*
X501832Y1520797D01*
X501132Y1521331D01*
X500832Y1522264D01*
X501032Y1523197D01*
X501532Y1523864D01*
X502232Y1524264D01*
X502932D01*
X503632Y1523997D01*
X504232Y1523331D01*
G01X516332Y1516264D02*
Y1524264D01*
X518332D01*
X519132Y1523864D01*
X519732Y1523331D01*
X520232Y1522531D01*
X520632Y1521597D01*
X520732Y1520264D01*
X520632Y1518931D01*
X520232Y1517997D01*
X519732Y1517197D01*
X519132Y1516664D01*
X518332Y1516264D01*
X516332D01*
G01X524532D02*
Y1524264D01*
X527032D01*
X527832Y1523864D01*
X528332Y1523331D01*
X528532Y1522264D01*
X528332Y1521197D01*
X527732Y1520531D01*
X527032Y1520131D01*
X524532D01*
G01X527032D02*
X528532Y1516264D01*
G01X533332Y1524264D02*
X535732D01*
G01X534532D02*
Y1516264D01*
G01X533332D02*
X535732D01*
G01X540532Y1524264D02*
Y1516264D01*
X544532D01*
G01X548532Y1524264D02*
Y1516264D01*
X552532D01*
G01X567332Y1520531D02*
X567732Y1520931D01*
X568032Y1521597D01*
X568232Y1522531D01*
X568032Y1523331D01*
X567632Y1523864D01*
X566932Y1524264D01*
X564232D01*
Y1516264D01*
X567532D01*
X568232Y1516797D01*
X568632Y1517597D01*
X568832Y1518531D01*
X568632Y1519464D01*
X568032Y1520264D01*
X567332Y1520531D01*
X564232D01*
G01X573332Y1524264D02*
X575732D01*
G01X574532D02*
Y1516264D01*
G01X573332D02*
X575732D01*
G01X582532Y1524264D02*
Y1516264D01*
G01X580232Y1524264D02*
X584832D01*
G01X590532Y1515997D02*
X590332Y1516131D01*
Y1516397D01*
X590532Y1516531D01*
X590732Y1516397D01*
Y1516131D01*
X590532Y1515997D01*
G01X596632Y1516264D02*
Y1524264D01*
X600432D01*
G01X599032Y1520397D02*
X596632D01*
G01X606532Y1516264D02*
X605732Y1516397D01*
X605032Y1516931D01*
X604432Y1517731D01*
X604032Y1518664D01*
X603832Y1519731D01*
Y1520797D01*
X604032Y1521864D01*
X604432Y1522797D01*
X605032Y1523597D01*
X605732Y1524131D01*
X606532Y1524264D01*
X607332Y1524131D01*
X608032Y1523597D01*
X608632Y1522797D01*
X609032Y1521864D01*
X609232Y1520797D01*
Y1519731D01*
X609032Y1518664D01*
X608632Y1517731D01*
X608032Y1516931D01*
X607332Y1516397D01*
X606532Y1516264D01*
G01X612532D02*
Y1524264D01*
X615032D01*
X615832Y1523864D01*
X616332Y1523331D01*
X616532Y1522264D01*
X616332Y1521197D01*
X615732Y1520531D01*
X615032Y1520131D01*
X612532D01*
G01X615032D02*
X616532Y1516264D01*
G01X628632Y1522931D02*
X629232Y1523731D01*
X629932Y1524131D01*
X630732Y1524264D01*
X631732Y1523997D01*
X632432Y1523331D01*
X632632Y1522531D01*
X632532Y1521730D01*
X632132Y1521064D01*
X630132Y1519731D01*
X629232Y1518797D01*
X628632Y1517464D01*
X628432Y1516264D01*
X632632D01*
G01X638532Y1524264D02*
X637732Y1523997D01*
X637132Y1523331D01*
X636732Y1522531D01*
X636432Y1521464D01*
X636332Y1520264D01*
X636432Y1519064D01*
X636732Y1517997D01*
X637132Y1517197D01*
X637732Y1516531D01*
X638532Y1516264D01*
X639332Y1516531D01*
X639932Y1517197D01*
X640332Y1517997D01*
X640632Y1519064D01*
X640732Y1520264D01*
X640632Y1521464D01*
X640332Y1522531D01*
X639932Y1523331D01*
X639332Y1523997D01*
X638532Y1524264D01*
G01X643932Y1516264D02*
Y1524264D01*
X646532Y1517597D01*
X649132Y1524264D01*
Y1516264D01*
G01X653332Y1524264D02*
X655732D01*
G01X654532D02*
Y1516264D01*
G01X653332D02*
X655732D01*
G01X660532Y1524264D02*
Y1516264D01*
X664532D01*
G01X668432Y1517330D02*
X669232Y1516664D01*
X670132Y1516264D01*
X670932D01*
X671732Y1516664D01*
X672332Y1517330D01*
X672632Y1518264D01*
X672432Y1519197D01*
X671932Y1519997D01*
X671032Y1520531D01*
X669832Y1520797D01*
X669132Y1521331D01*
X668832Y1522264D01*
X669032Y1523197D01*
X669532Y1523864D01*
X670232Y1524264D01*
X670932D01*
X671632Y1523997D01*
X672232Y1523331D01*
G01X684032Y1524264D02*
X686532Y1516264D01*
X689032Y1524264D01*
G01X693332D02*
X695732D01*
G01X694532D02*
Y1516264D01*
G01X693332D02*
X695732D01*
G01X700032D02*
X702532Y1524264D01*
X705032Y1516264D01*
G01X704132Y1519064D02*
X700932D01*
G01X708432Y1517330D02*
X709232Y1516664D01*
X710132Y1516264D01*
X710932D01*
X711732Y1516664D01*
X712332Y1517330D01*
X712632Y1518264D01*
X712432Y1519197D01*
X711932Y1519997D01*
X711032Y1520531D01*
X709832Y1520797D01*
X709132Y1521331D01*
X708832Y1522264D01*
X709032Y1523197D01*
X709532Y1523864D01*
X710232Y1524264D01*
X710932D01*
X711632Y1523997D01*
X712232Y1523331D01*
G01X724332Y1524264D02*
Y1518531D01*
X724732Y1517330D01*
X725532Y1516531D01*
X726532Y1516264D01*
X727532Y1516531D01*
X728332Y1517330D01*
X728732Y1518531D01*
Y1524264D01*
G01X732432Y1517330D02*
X733232Y1516664D01*
X734132Y1516264D01*
X734932D01*
X735732Y1516664D01*
X736332Y1517330D01*
X736632Y1518264D01*
X736432Y1519197D01*
X735932Y1519997D01*
X735032Y1520531D01*
X733832Y1520797D01*
X733132Y1521331D01*
X732832Y1522264D01*
X733032Y1523197D01*
X733532Y1523864D01*
X734232Y1524264D01*
X734932D01*
X735632Y1523997D01*
X736232Y1523331D01*
G01X744532Y1516264D02*
X740532D01*
Y1524264D01*
X744532D01*
G01X742932Y1520397D02*
X740532D01*
G01X758532Y1516264D02*
Y1524264D01*
X757332Y1522664D01*
G01Y1516264D02*
X759732D01*
G01X764832Y1517197D02*
X765532Y1516531D01*
X766332Y1516264D01*
X767132Y1516531D01*
X767832Y1517330D01*
X768332Y1518531D01*
X768532Y1519731D01*
Y1521197D01*
X768332Y1522397D01*
X767832Y1523464D01*
X767232Y1523997D01*
X766532Y1524264D01*
X765732Y1523997D01*
X765132Y1523464D01*
X764732Y1522664D01*
X764532Y1521597D01*
X764732Y1520664D01*
X765232Y1519731D01*
X765832Y1519197D01*
X766532Y1519064D01*
X767332Y1519330D01*
X767932Y1519997D01*
X768532Y1521197D01*
G01X774532Y1515997D02*
X774332Y1516131D01*
Y1516397D01*
X774532Y1516531D01*
X774732Y1516397D01*
Y1516131D01*
X774532Y1515997D01*
G01X782332Y1516264D02*
X782532Y1517997D01*
X782832Y1519464D01*
X783232Y1520797D01*
X783732Y1522264D01*
X784532Y1524264D01*
X780532D01*
G01X787932Y1516264D02*
Y1524264D01*
X790532Y1517597D01*
X793132Y1524264D01*
Y1516264D01*
G01X797332Y1524264D02*
X799732D01*
G01X798532D02*
Y1516264D01*
G01X797332D02*
X799732D01*
G01X804532Y1524264D02*
Y1516264D01*
X808532D01*
G01X812432Y1517330D02*
X813232Y1516664D01*
X814132Y1516264D01*
X814932D01*
X815732Y1516664D01*
X816332Y1517330D01*
X816632Y1518264D01*
X816432Y1519197D01*
X815932Y1519997D01*
X815032Y1520531D01*
X813832Y1520797D01*
X813132Y1521331D01*
X812832Y1522264D01*
X813032Y1523197D01*
X813532Y1523864D01*
X814232Y1524264D01*
X814932D01*
X815632Y1523997D01*
X816232Y1523331D01*
G01X828332Y1516264D02*
Y1524264D01*
X830332D01*
X831132Y1523864D01*
X831732Y1523331D01*
X832232Y1522531D01*
X832632Y1521597D01*
X832732Y1520264D01*
X832632Y1518931D01*
X832232Y1517997D01*
X831732Y1517197D01*
X831132Y1516664D01*
X830332Y1516264D01*
X828332D01*
G01X836532D02*
Y1524264D01*
X839032D01*
X839832Y1523864D01*
X840332Y1523331D01*
X840532Y1522264D01*
X840332Y1521197D01*
X839732Y1520531D01*
X839032Y1520131D01*
X836532D01*
G01X839032D02*
X840532Y1516264D01*
G01X845332Y1524264D02*
X847732D01*
G01X846532D02*
Y1516264D01*
G01X845332D02*
X847732D01*
G01X852532Y1524264D02*
Y1516264D01*
X856532D01*
G01X860532Y1524264D02*
Y1516264D01*
X864532D01*
G01X879332Y1520531D02*
X879732Y1520931D01*
X880032Y1521597D01*
X880232Y1522531D01*
X880032Y1523331D01*
X879632Y1523864D01*
X878932Y1524264D01*
X876232D01*
Y1516264D01*
X879532D01*
X880232Y1516797D01*
X880632Y1517597D01*
X880832Y1518531D01*
X880632Y1519464D01*
X880032Y1520264D01*
X879332Y1520531D01*
X876232D01*
G01X885332Y1524264D02*
X887732D01*
G01X886532D02*
Y1516264D01*
G01X885332D02*
X887732D01*
G01X894532Y1524264D02*
Y1516264D01*
G01X892232Y1524264D02*
X896832D01*
G01X902532Y1515997D02*
X902332Y1516131D01*
Y1516397D01*
X902532Y1516531D01*
X902732Y1516397D01*
Y1516131D01*
X902532Y1515997D01*
G01X-27368Y1534597D02*
X-26668Y1535531D01*
X-26068Y1536064D01*
X-25268Y1536331D01*
X-24568Y1536064D01*
X-24068Y1535531D01*
X-23668Y1534731D01*
X-23568Y1533797D01*
X-23668Y1532997D01*
X-24068Y1532197D01*
X-24668Y1531531D01*
X-25368Y1531264D01*
X-26168Y1531531D01*
X-26868Y1532330D01*
X-27268Y1533531D01*
X-27368Y1534864D01*
X-27168Y1536597D01*
X-26868Y1537531D01*
X-26368Y1538464D01*
X-25668Y1539131D01*
X-24968Y1539264D01*
X-24268Y1538997D01*
X-23768Y1538331D01*
G01X-17468Y1530997D02*
X-17668Y1531131D01*
Y1531397D01*
X-17468Y1531531D01*
X-17268Y1531397D01*
Y1531131D01*
X-17468Y1530997D01*
G01X-11368Y1537931D02*
X-10768Y1538731D01*
X-10068Y1539131D01*
X-9268Y1539264D01*
X-8268Y1538997D01*
X-7568Y1538331D01*
X-7368Y1537531D01*
X-7468Y1536730D01*
X-7868Y1536064D01*
X-9868Y1534731D01*
X-10768Y1533797D01*
X-11368Y1532464D01*
X-11568Y1531264D01*
X-7368D01*
G01X6532D02*
X5732Y1531397D01*
X5032Y1531931D01*
X4432Y1532731D01*
X4032Y1533664D01*
X3832Y1534731D01*
Y1535797D01*
X4032Y1536864D01*
X4432Y1537797D01*
X5032Y1538597D01*
X5732Y1539131D01*
X6532Y1539264D01*
X7332Y1539131D01*
X8032Y1538597D01*
X8632Y1537797D01*
X9032Y1536864D01*
X9232Y1535797D01*
Y1534731D01*
X9032Y1533664D01*
X8632Y1532731D01*
X8032Y1531931D01*
X7332Y1531397D01*
X6532Y1531264D01*
G01X12332Y1539264D02*
Y1533531D01*
X12732Y1532330D01*
X13532Y1531531D01*
X14532Y1531264D01*
X15532Y1531531D01*
X16332Y1532330D01*
X16732Y1533531D01*
Y1539264D01*
G01X22532D02*
Y1531264D01*
G01X20232Y1539264D02*
X24832D01*
G01X28432Y1532330D02*
X29232Y1531664D01*
X30132Y1531264D01*
X30932D01*
X31732Y1531664D01*
X32332Y1532330D01*
X32632Y1533264D01*
X32432Y1534197D01*
X31932Y1534997D01*
X31032Y1535531D01*
X29832Y1535797D01*
X29132Y1536331D01*
X28832Y1537264D01*
X29032Y1538197D01*
X29532Y1538864D01*
X30232Y1539264D01*
X30932D01*
X31632Y1538997D01*
X32232Y1538331D01*
G01X37332Y1539264D02*
X39732D01*
G01X38532D02*
Y1531264D01*
G01X37332D02*
X39732D01*
G01X44332D02*
Y1539264D01*
X46332D01*
X47132Y1538864D01*
X47732Y1538331D01*
X48232Y1537531D01*
X48632Y1536597D01*
X48732Y1535264D01*
X48632Y1533931D01*
X48232Y1532997D01*
X47732Y1532197D01*
X47132Y1531664D01*
X46332Y1531264D01*
X44332D01*
G01X56532D02*
X52532D01*
Y1539264D01*
X56532D01*
G01X54932Y1535397D02*
X52532D01*
G01X71332Y1535531D02*
X71732Y1535931D01*
X72032Y1536597D01*
X72232Y1537531D01*
X72032Y1538331D01*
X71632Y1538864D01*
X70932Y1539264D01*
X68232D01*
Y1531264D01*
X71532D01*
X72232Y1531797D01*
X72632Y1532597D01*
X72832Y1533531D01*
X72632Y1534464D01*
X72032Y1535264D01*
X71332Y1535531D01*
X68232D01*
G01X78532Y1531264D02*
X77732Y1531397D01*
X77032Y1531931D01*
X76432Y1532731D01*
X76032Y1533664D01*
X75832Y1534731D01*
Y1535797D01*
X76032Y1536864D01*
X76432Y1537797D01*
X77032Y1538597D01*
X77732Y1539131D01*
X78532Y1539264D01*
X79332Y1539131D01*
X80032Y1538597D01*
X80632Y1537797D01*
X81032Y1536864D01*
X81232Y1535797D01*
Y1534731D01*
X81032Y1533664D01*
X80632Y1532731D01*
X80032Y1531931D01*
X79332Y1531397D01*
X78532Y1531264D01*
G01X84032D02*
X86532Y1539264D01*
X89032Y1531264D01*
G01X88132Y1534064D02*
X84932D01*
G01X92532Y1531264D02*
Y1539264D01*
X95032D01*
X95832Y1538864D01*
X96332Y1538331D01*
X96532Y1537264D01*
X96332Y1536197D01*
X95732Y1535531D01*
X95032Y1535131D01*
X92532D01*
G01X95032D02*
X96532Y1531264D01*
G01X100332D02*
Y1539264D01*
X102332D01*
X103132Y1538864D01*
X103732Y1538331D01*
X104232Y1537531D01*
X104632Y1536597D01*
X104732Y1535264D01*
X104632Y1533931D01*
X104232Y1532997D01*
X103732Y1532197D01*
X103132Y1531664D01*
X102332Y1531264D01*
X100332D01*
G01X118532D02*
X117732Y1531397D01*
X117032Y1531931D01*
X116432Y1532731D01*
X116032Y1533664D01*
X115832Y1534731D01*
Y1535797D01*
X116032Y1536864D01*
X116432Y1537797D01*
X117032Y1538597D01*
X117732Y1539131D01*
X118532Y1539264D01*
X119332Y1539131D01*
X120032Y1538597D01*
X120632Y1537797D01*
X121032Y1536864D01*
X121232Y1535797D01*
Y1534731D01*
X121032Y1533664D01*
X120632Y1532731D01*
X120032Y1531931D01*
X119332Y1531397D01*
X118532Y1531264D01*
G01X124332Y1539264D02*
Y1533531D01*
X124732Y1532330D01*
X125532Y1531531D01*
X126532Y1531264D01*
X127532Y1531531D01*
X128332Y1532330D01*
X128732Y1533531D01*
Y1539264D01*
G01X134532D02*
Y1531264D01*
G01X132232Y1539264D02*
X136832D01*
G01X140532D02*
Y1531264D01*
X144532D01*
G01X149332Y1539264D02*
X151732D01*
G01X150532D02*
Y1531264D01*
G01X149332D02*
X151732D01*
G01X156232D02*
Y1539264D01*
X160832Y1531264D01*
Y1539264D01*
G01X168532Y1531264D02*
X164532D01*
Y1539264D01*
X168532D01*
G01X166932Y1535397D02*
X164532D01*
G01X180632Y1531264D02*
Y1539264D01*
X184432D01*
G01X183032Y1535397D02*
X180632D01*
G01X190532Y1531264D02*
X189732Y1531397D01*
X189032Y1531931D01*
X188432Y1532731D01*
X188032Y1533664D01*
X187832Y1534731D01*
Y1535797D01*
X188032Y1536864D01*
X188432Y1537797D01*
X189032Y1538597D01*
X189732Y1539131D01*
X190532Y1539264D01*
X191332Y1539131D01*
X192032Y1538597D01*
X192632Y1537797D01*
X193032Y1536864D01*
X193232Y1535797D01*
Y1534731D01*
X193032Y1533664D01*
X192632Y1532731D01*
X192032Y1531931D01*
X191332Y1531397D01*
X190532Y1531264D01*
G01X196532Y1539264D02*
Y1531264D01*
X200532D01*
G01X204532Y1539264D02*
Y1531264D01*
X208532D01*
G01X214532D02*
X213732Y1531397D01*
X213032Y1531931D01*
X212432Y1532731D01*
X212032Y1533664D01*
X211832Y1534731D01*
Y1535797D01*
X212032Y1536864D01*
X212432Y1537797D01*
X213032Y1538597D01*
X213732Y1539131D01*
X214532Y1539264D01*
X215332Y1539131D01*
X216032Y1538597D01*
X216632Y1537797D01*
X217032Y1536864D01*
X217232Y1535797D01*
Y1534731D01*
X217032Y1533664D01*
X216632Y1532731D01*
X216032Y1531931D01*
X215332Y1531397D01*
X214532Y1531264D01*
G01X219532Y1539264D02*
X220932Y1531264D01*
X222532Y1539264D01*
X224132Y1531264D01*
X225532Y1539264D01*
G01X236532Y1531264D02*
Y1539264D01*
X238932D01*
X239732Y1538864D01*
X240332Y1537931D01*
X240532Y1536864D01*
X240332Y1535797D01*
X239832Y1534997D01*
X238932Y1534597D01*
X236532D01*
G01X248732Y1538597D02*
X248132Y1538997D01*
X247432Y1539264D01*
X246632D01*
X245732Y1538864D01*
X245032Y1538197D01*
X244532Y1537397D01*
X244132Y1536064D01*
X244032Y1534864D01*
X244232Y1533664D01*
X244532Y1532864D01*
X245132Y1532064D01*
X245832Y1531531D01*
X246532Y1531264D01*
X247232D01*
X247932Y1531531D01*
X248532Y1531931D01*
X249032Y1532464D01*
G01X255332Y1535531D02*
X255732Y1535931D01*
X256032Y1536597D01*
X256232Y1537531D01*
X256032Y1538331D01*
X255632Y1538864D01*
X254932Y1539264D01*
X252232D01*
Y1531264D01*
X255532D01*
X256232Y1531797D01*
X256632Y1532597D01*
X256832Y1533531D01*
X256632Y1534464D01*
X256032Y1535264D01*
X255332Y1535531D01*
X252232D01*
G01X268432Y1532330D02*
X269232Y1531664D01*
X270132Y1531264D01*
X270932D01*
X271732Y1531664D01*
X272332Y1532330D01*
X272632Y1533264D01*
X272432Y1534197D01*
X271932Y1534997D01*
X271032Y1535531D01*
X269832Y1535797D01*
X269132Y1536331D01*
X268832Y1537264D01*
X269032Y1538197D01*
X269532Y1538864D01*
X270232Y1539264D01*
X270932D01*
X271632Y1538997D01*
X272232Y1538331D01*
G01X276432Y1531264D02*
Y1539264D01*
G01X280632D02*
Y1531264D01*
G01Y1535264D02*
X276432D01*
G01X286532Y1531264D02*
X285732Y1531397D01*
X285032Y1531931D01*
X284432Y1532731D01*
X284032Y1533664D01*
X283832Y1534731D01*
Y1535797D01*
X284032Y1536864D01*
X284432Y1537797D01*
X285032Y1538597D01*
X285732Y1539131D01*
X286532Y1539264D01*
X287332Y1539131D01*
X288032Y1538597D01*
X288632Y1537797D01*
X289032Y1536864D01*
X289232Y1535797D01*
Y1534731D01*
X289032Y1533664D01*
X288632Y1532731D01*
X288032Y1531931D01*
X287332Y1531397D01*
X286532Y1531264D01*
G01X292532D02*
Y1539264D01*
X294932D01*
X295732Y1538864D01*
X296332Y1537931D01*
X296532Y1536864D01*
X296332Y1535797D01*
X295832Y1534997D01*
X294932Y1534597D01*
X292532D01*
G01X308532Y1531264D02*
Y1539264D01*
X310932D01*
X311732Y1538864D01*
X312332Y1537931D01*
X312532Y1536864D01*
X312332Y1535797D01*
X311832Y1534997D01*
X310932Y1534597D01*
X308532D01*
G01X316532Y1531264D02*
Y1539264D01*
X319032D01*
X319832Y1538864D01*
X320332Y1538331D01*
X320532Y1537264D01*
X320332Y1536197D01*
X319732Y1535531D01*
X319032Y1535131D01*
X316532D01*
G01X319032D02*
X320532Y1531264D01*
G01X328532D02*
X324532D01*
Y1539264D01*
X328532D01*
G01X326932Y1535397D02*
X324532D01*
G01X332632Y1531264D02*
Y1539264D01*
X336432D01*
G01X335032Y1535397D02*
X332632D01*
G01X344532Y1531264D02*
X340532D01*
Y1539264D01*
X344532D01*
G01X342932Y1535397D02*
X340532D01*
G01X348532Y1531264D02*
Y1539264D01*
X351032D01*
X351832Y1538864D01*
X352332Y1538331D01*
X352532Y1537264D01*
X352332Y1536197D01*
X351732Y1535531D01*
X351032Y1535131D01*
X348532D01*
G01X351032D02*
X352532Y1531264D01*
G01X360532D02*
X356532D01*
Y1539264D01*
X360532D01*
G01X358932Y1535397D02*
X356532D01*
G01X364232Y1531264D02*
Y1539264D01*
X368832Y1531264D01*
Y1539264D01*
G01X376732Y1538597D02*
X376132Y1538997D01*
X375432Y1539264D01*
X374632D01*
X373732Y1538864D01*
X373032Y1538197D01*
X372532Y1537397D01*
X372132Y1536064D01*
X372032Y1534864D01*
X372232Y1533664D01*
X372532Y1532864D01*
X373132Y1532064D01*
X373832Y1531531D01*
X374532Y1531264D01*
X375232D01*
X375932Y1531531D01*
X376532Y1531931D01*
X377032Y1532464D01*
G01X384532Y1531264D02*
X380532D01*
Y1539264D01*
X384532D01*
G01X382932Y1535397D02*
X380532D01*
G01X399332Y1535531D02*
X399732Y1535931D01*
X400032Y1536597D01*
X400232Y1537531D01*
X400032Y1538331D01*
X399632Y1538864D01*
X398932Y1539264D01*
X396232D01*
Y1531264D01*
X399532D01*
X400232Y1531797D01*
X400632Y1532597D01*
X400832Y1533531D01*
X400632Y1534464D01*
X400032Y1535264D01*
X399332Y1535531D01*
X396232D01*
G01X404332Y1539264D02*
Y1533531D01*
X404732Y1532330D01*
X405532Y1531531D01*
X406532Y1531264D01*
X407532Y1531531D01*
X408332Y1532330D01*
X408732Y1533531D01*
Y1539264D01*
G01X414532D02*
Y1531264D01*
G01X412232Y1539264D02*
X416832D01*
G01X432732Y1538597D02*
X432132Y1538997D01*
X431432Y1539264D01*
X430632D01*
X429732Y1538864D01*
X429032Y1538197D01*
X428532Y1537397D01*
X428132Y1536064D01*
X428032Y1534864D01*
X428232Y1533664D01*
X428532Y1532864D01*
X429132Y1532064D01*
X429832Y1531531D01*
X430532Y1531264D01*
X431232D01*
X431932Y1531531D01*
X432532Y1531931D01*
X433032Y1532464D01*
G01X438532Y1531264D02*
X437732Y1531397D01*
X437032Y1531931D01*
X436432Y1532731D01*
X436032Y1533664D01*
X435832Y1534731D01*
Y1535797D01*
X436032Y1536864D01*
X436432Y1537797D01*
X437032Y1538597D01*
X437732Y1539131D01*
X438532Y1539264D01*
X439332Y1539131D01*
X440032Y1538597D01*
X440632Y1537797D01*
X441032Y1536864D01*
X441232Y1535797D01*
Y1534731D01*
X441032Y1533664D01*
X440632Y1532731D01*
X440032Y1531931D01*
X439332Y1531397D01*
X438532Y1531264D01*
G01X444332Y1539264D02*
Y1533531D01*
X444732Y1532330D01*
X445532Y1531531D01*
X446532Y1531264D01*
X447532Y1531531D01*
X448332Y1532330D01*
X448732Y1533531D01*
Y1539264D01*
G01X452532Y1531264D02*
Y1539264D01*
X454932D01*
X455732Y1538864D01*
X456332Y1537931D01*
X456532Y1536864D01*
X456332Y1535797D01*
X455832Y1534997D01*
X454932Y1534597D01*
X452532D01*
G01X462532Y1531264D02*
X461732Y1531397D01*
X461032Y1531931D01*
X460432Y1532731D01*
X460032Y1533664D01*
X459832Y1534731D01*
Y1535797D01*
X460032Y1536864D01*
X460432Y1537797D01*
X461032Y1538597D01*
X461732Y1539131D01*
X462532Y1539264D01*
X463332Y1539131D01*
X464032Y1538597D01*
X464632Y1537797D01*
X465032Y1536864D01*
X465232Y1535797D01*
Y1534731D01*
X465032Y1533664D01*
X464632Y1532731D01*
X464032Y1531931D01*
X463332Y1531397D01*
X462532Y1531264D01*
G01X468232D02*
Y1539264D01*
X472832Y1531264D01*
Y1539264D01*
G01X476732Y1530997D02*
X480332Y1539264D01*
G01X484632Y1531264D02*
Y1539264D01*
X488432D01*
G01X487032Y1535397D02*
X484632D01*
G01X493332Y1539264D02*
X495732D01*
G01X494532D02*
Y1531264D01*
G01X493332D02*
X495732D01*
G01X500332D02*
Y1539264D01*
X502332D01*
X503132Y1538864D01*
X503732Y1538331D01*
X504232Y1537531D01*
X504632Y1536597D01*
X504732Y1535264D01*
X504632Y1533931D01*
X504232Y1532997D01*
X503732Y1532197D01*
X503132Y1531664D01*
X502332Y1531264D01*
X500332D01*
G01X508332Y1539264D02*
Y1533531D01*
X508732Y1532330D01*
X509532Y1531531D01*
X510532Y1531264D01*
X511532Y1531531D01*
X512332Y1532330D01*
X512732Y1533531D01*
Y1539264D01*
G01X520732Y1538597D02*
X520132Y1538997D01*
X519432Y1539264D01*
X518632D01*
X517732Y1538864D01*
X517032Y1538197D01*
X516532Y1537397D01*
X516132Y1536064D01*
X516032Y1534864D01*
X516232Y1533664D01*
X516532Y1532864D01*
X517132Y1532064D01*
X517832Y1531531D01*
X518532Y1531264D01*
X519232D01*
X519932Y1531531D01*
X520532Y1531931D01*
X521032Y1532464D01*
G01X525332Y1539264D02*
X527732D01*
G01X526532D02*
Y1531264D01*
G01X525332D02*
X527732D01*
G01X532032D02*
X534532Y1539264D01*
X537032Y1531264D01*
G01X536132Y1534064D02*
X532932D01*
G01X540532Y1539264D02*
Y1531264D01*
X544532D01*
G01X555932D02*
Y1539264D01*
X558532Y1532597D01*
X561132Y1539264D01*
Y1531264D01*
G01X564032D02*
X566532Y1539264D01*
X569032Y1531264D01*
G01X568132Y1534064D02*
X564932D01*
G01X572532Y1531264D02*
Y1539264D01*
X575032D01*
X575832Y1538864D01*
X576332Y1538331D01*
X576532Y1537264D01*
X576332Y1536197D01*
X575732Y1535531D01*
X575032Y1535131D01*
X572532D01*
G01X575032D02*
X576532Y1531264D01*
G01X580332D02*
Y1539264D01*
G01X584132D02*
X580332Y1534330D01*
G01X584732Y1531264D02*
X582032Y1536597D01*
G01X588732Y1530997D02*
X592332Y1539264D01*
G01X598532D02*
Y1531264D01*
G01X596232Y1539264D02*
X600832D01*
G01X606532Y1531264D02*
X605732Y1531397D01*
X605032Y1531931D01*
X604432Y1532731D01*
X604032Y1533664D01*
X603832Y1534731D01*
Y1535797D01*
X604032Y1536864D01*
X604432Y1537797D01*
X605032Y1538597D01*
X605732Y1539131D01*
X606532Y1539264D01*
X607332Y1539131D01*
X608032Y1538597D01*
X608632Y1537797D01*
X609032Y1536864D01*
X609232Y1535797D01*
Y1534731D01*
X609032Y1533664D01*
X608632Y1532731D01*
X608032Y1531931D01*
X607332Y1531397D01*
X606532Y1531264D01*
G01X614532D02*
X613732Y1531397D01*
X613032Y1531931D01*
X612432Y1532731D01*
X612032Y1533664D01*
X611832Y1534731D01*
Y1535797D01*
X612032Y1536864D01*
X612432Y1537797D01*
X613032Y1538597D01*
X613732Y1539131D01*
X614532Y1539264D01*
X615332Y1539131D01*
X616032Y1538597D01*
X616632Y1537797D01*
X617032Y1536864D01*
X617232Y1535797D01*
Y1534731D01*
X617032Y1533664D01*
X616632Y1532731D01*
X616032Y1531931D01*
X615332Y1531397D01*
X614532Y1531264D01*
G01X620532Y1539264D02*
Y1531264D01*
X624532D01*
G01X629332Y1539264D02*
X631732D01*
G01X630532D02*
Y1531264D01*
G01X629332D02*
X631732D01*
G01X636232D02*
Y1539264D01*
X640832Y1531264D01*
Y1539264D01*
G01X647132Y1535264D02*
X649132D01*
Y1532864D01*
X648532Y1532064D01*
X647832Y1531531D01*
X646832Y1531264D01*
X645832Y1531531D01*
X645132Y1532064D01*
X644532Y1532864D01*
X644132Y1533797D01*
X643932Y1534864D01*
Y1535797D01*
X644132Y1536597D01*
X644532Y1537531D01*
X645132Y1538331D01*
X645732Y1538864D01*
X646532Y1539264D01*
X647232D01*
X648032Y1538997D01*
X648632Y1538464D01*
G01X660432Y1531264D02*
Y1539264D01*
G01X664632D02*
Y1531264D01*
G01Y1535264D02*
X660432D01*
G01X670532Y1531264D02*
X669732Y1531397D01*
X669032Y1531931D01*
X668432Y1532731D01*
X668032Y1533664D01*
X667832Y1534731D01*
Y1535797D01*
X668032Y1536864D01*
X668432Y1537797D01*
X669032Y1538597D01*
X669732Y1539131D01*
X670532Y1539264D01*
X671332Y1539131D01*
X672032Y1538597D01*
X672632Y1537797D01*
X673032Y1536864D01*
X673232Y1535797D01*
Y1534731D01*
X673032Y1533664D01*
X672632Y1532731D01*
X672032Y1531931D01*
X671332Y1531397D01*
X670532Y1531264D01*
G01X676532Y1539264D02*
Y1531264D01*
X680532D01*
G01X688532D02*
X684532D01*
Y1539264D01*
X688532D01*
G01X686932Y1535397D02*
X684532D01*
G01X700432Y1532330D02*
X701232Y1531664D01*
X702132Y1531264D01*
X702932D01*
X703732Y1531664D01*
X704332Y1532330D01*
X704632Y1533264D01*
X704432Y1534197D01*
X703932Y1534997D01*
X703032Y1535531D01*
X701832Y1535797D01*
X701132Y1536331D01*
X700832Y1537264D01*
X701032Y1538197D01*
X701532Y1538864D01*
X702232Y1539264D01*
X702932D01*
X703632Y1538997D01*
X704232Y1538331D01*
G01X708532Y1531264D02*
Y1539264D01*
X710932D01*
X711732Y1538864D01*
X712332Y1537931D01*
X712532Y1536864D01*
X712332Y1535797D01*
X711832Y1534997D01*
X710932Y1534597D01*
X708532D01*
G01X716032Y1531264D02*
X718532Y1539264D01*
X721032Y1531264D01*
G01X720132Y1534064D02*
X716932D01*
G01X728732Y1538597D02*
X728132Y1538997D01*
X727432Y1539264D01*
X726632D01*
X725732Y1538864D01*
X725032Y1538197D01*
X724532Y1537397D01*
X724132Y1536064D01*
X724032Y1534864D01*
X724232Y1533664D01*
X724532Y1532864D01*
X725132Y1532064D01*
X725832Y1531531D01*
X726532Y1531264D01*
X727232D01*
X727932Y1531531D01*
X728532Y1531931D01*
X729032Y1532464D01*
G01X733332Y1539264D02*
X735732D01*
G01X734532D02*
Y1531264D01*
G01X733332D02*
X735732D01*
G01X740232D02*
Y1539264D01*
X744832Y1531264D01*
Y1539264D01*
G01X751132Y1535264D02*
X753132D01*
Y1532864D01*
X752532Y1532064D01*
X751832Y1531531D01*
X750832Y1531264D01*
X749832Y1531531D01*
X749132Y1532064D01*
X748532Y1532864D01*
X748132Y1533797D01*
X747932Y1534864D01*
Y1535797D01*
X748132Y1536597D01*
X748532Y1537531D01*
X749132Y1538331D01*
X749732Y1538864D01*
X750532Y1539264D01*
X751232D01*
X752032Y1538997D01*
X752632Y1538464D01*
G01X764032Y1531264D02*
X766532Y1539264D01*
X769032Y1531264D01*
G01X768132Y1534064D02*
X764932D01*
G01X772532Y1539264D02*
Y1531264D01*
X776532D01*
G01X780532Y1539264D02*
Y1531264D01*
X784532D01*
G01X796332Y1539264D02*
Y1533531D01*
X796732Y1532330D01*
X797532Y1531531D01*
X798532Y1531264D01*
X799532Y1531531D01*
X800332Y1532330D01*
X800732Y1533531D01*
Y1539264D01*
G01X804432Y1532330D02*
X805232Y1531664D01*
X806132Y1531264D01*
X806932D01*
X807732Y1531664D01*
X808332Y1532330D01*
X808632Y1533264D01*
X808432Y1534197D01*
X807932Y1534997D01*
X807032Y1535531D01*
X805832Y1535797D01*
X805132Y1536331D01*
X804832Y1537264D01*
X805032Y1538197D01*
X805532Y1538864D01*
X806232Y1539264D01*
X806932D01*
X807632Y1538997D01*
X808232Y1538331D01*
G01X813332Y1539264D02*
X815732D01*
G01X814532D02*
Y1531264D01*
G01X813332D02*
X815732D01*
G01X820232D02*
Y1539264D01*
X824832Y1531264D01*
Y1539264D01*
G01X831132Y1535264D02*
X833132D01*
Y1532864D01*
X832532Y1532064D01*
X831832Y1531531D01*
X830832Y1531264D01*
X829832Y1531531D01*
X829132Y1532064D01*
X828532Y1532864D01*
X828132Y1533797D01*
X827932Y1534864D01*
Y1535797D01*
X828132Y1536597D01*
X828532Y1537531D01*
X829132Y1538331D01*
X829732Y1538864D01*
X830532Y1539264D01*
X831232D01*
X832032Y1538997D01*
X832632Y1538464D01*
G01X844332Y1532464D02*
X844932Y1531797D01*
X845632Y1531397D01*
X846532Y1531264D01*
X847432Y1531531D01*
X848132Y1532064D01*
X848632Y1532997D01*
X848732Y1534064D01*
X848532Y1535131D01*
X848032Y1535797D01*
X847332Y1536331D01*
X846632Y1536464D01*
X845932Y1536331D01*
X845032Y1535797D01*
X845332Y1539264D01*
X848032D01*
G01X854532D02*
X853732Y1538997D01*
X853132Y1538331D01*
X852732Y1537531D01*
X852432Y1536464D01*
X852332Y1535264D01*
X852432Y1534064D01*
X852732Y1532997D01*
X853132Y1532197D01*
X853732Y1531531D01*
X854532Y1531264D01*
X855332Y1531531D01*
X855932Y1532197D01*
X856332Y1532997D01*
X856632Y1534064D01*
X856732Y1535264D01*
X856632Y1536464D01*
X856332Y1537531D01*
X855932Y1538331D01*
X855332Y1538997D01*
X854532Y1539264D01*
G01X859932Y1531264D02*
Y1539264D01*
X862532Y1532597D01*
X865132Y1539264D01*
Y1531264D01*
G01X869332Y1539264D02*
X871732D01*
G01X870532D02*
Y1531264D01*
G01X869332D02*
X871732D01*
G01X876532Y1539264D02*
Y1531264D01*
X880532D01*
G01X884432Y1532330D02*
X885232Y1531664D01*
X886132Y1531264D01*
X886932D01*
X887732Y1531664D01*
X888332Y1532330D01*
X888632Y1533264D01*
X888432Y1534197D01*
X887932Y1534997D01*
X887032Y1535531D01*
X885832Y1535797D01*
X885132Y1536331D01*
X884832Y1537264D01*
X885032Y1538197D01*
X885532Y1538864D01*
X886232Y1539264D01*
X886932D01*
X887632Y1538997D01*
X888232Y1538331D01*
G01X894532Y1530997D02*
X894332Y1531131D01*
Y1531397D01*
X894532Y1531531D01*
X894732Y1531397D01*
Y1531131D01*
X894532Y1530997D01*
G01X-27368Y1549597D02*
X-26668Y1550531D01*
X-26068Y1551064D01*
X-25268Y1551331D01*
X-24568Y1551064D01*
X-24068Y1550531D01*
X-23668Y1549731D01*
X-23568Y1548797D01*
X-23668Y1547997D01*
X-24068Y1547197D01*
X-24668Y1546531D01*
X-25368Y1546264D01*
X-26168Y1546531D01*
X-26868Y1547330D01*
X-27268Y1548531D01*
X-27368Y1549864D01*
X-27168Y1551597D01*
X-26868Y1552531D01*
X-26368Y1553464D01*
X-25668Y1554131D01*
X-24968Y1554264D01*
X-24268Y1553997D01*
X-23768Y1553331D01*
G01X-17468Y1545997D02*
X-17668Y1546131D01*
Y1546397D01*
X-17468Y1546531D01*
X-17268Y1546397D01*
Y1546131D01*
X-17468Y1545997D01*
G01X-9468Y1546264D02*
Y1554264D01*
X-10668Y1552664D01*
G01Y1546264D02*
X-8268D01*
G01X5332Y1554264D02*
X7732D01*
G01X6532D02*
Y1546264D01*
G01X5332D02*
X7732D01*
G01X12232D02*
Y1554264D01*
X16832Y1546264D01*
Y1554264D01*
G01X20432Y1547330D02*
X21232Y1546664D01*
X22132Y1546264D01*
X22932D01*
X23732Y1546664D01*
X24332Y1547330D01*
X24632Y1548264D01*
X24432Y1549197D01*
X23932Y1549997D01*
X23032Y1550531D01*
X21832Y1550797D01*
X21132Y1551331D01*
X20832Y1552264D01*
X21032Y1553197D01*
X21532Y1553864D01*
X22232Y1554264D01*
X22932D01*
X23632Y1553997D01*
X24232Y1553331D01*
G01X29332Y1554264D02*
X31732D01*
G01X30532D02*
Y1546264D01*
G01X29332D02*
X31732D01*
G01X36332D02*
Y1554264D01*
X38332D01*
X39132Y1553864D01*
X39732Y1553331D01*
X40232Y1552531D01*
X40632Y1551597D01*
X40732Y1550264D01*
X40632Y1548931D01*
X40232Y1547997D01*
X39732Y1547197D01*
X39132Y1546664D01*
X38332Y1546264D01*
X36332D01*
G01X48532D02*
X44532D01*
Y1554264D01*
X48532D01*
G01X46932Y1550397D02*
X44532D01*
G01X63332Y1550531D02*
X63732Y1550931D01*
X64032Y1551597D01*
X64232Y1552531D01*
X64032Y1553331D01*
X63632Y1553864D01*
X62932Y1554264D01*
X60232D01*
Y1546264D01*
X63532D01*
X64232Y1546797D01*
X64632Y1547597D01*
X64832Y1548531D01*
X64632Y1549464D01*
X64032Y1550264D01*
X63332Y1550531D01*
X60232D01*
G01X70532Y1546264D02*
X69732Y1546397D01*
X69032Y1546931D01*
X68432Y1547731D01*
X68032Y1548664D01*
X67832Y1549731D01*
Y1550797D01*
X68032Y1551864D01*
X68432Y1552797D01*
X69032Y1553597D01*
X69732Y1554131D01*
X70532Y1554264D01*
X71332Y1554131D01*
X72032Y1553597D01*
X72632Y1552797D01*
X73032Y1551864D01*
X73232Y1550797D01*
Y1549731D01*
X73032Y1548664D01*
X72632Y1547731D01*
X72032Y1546931D01*
X71332Y1546397D01*
X70532Y1546264D01*
G01X76032D02*
X78532Y1554264D01*
X81032Y1546264D01*
G01X80132Y1549064D02*
X76932D01*
G01X84532Y1546264D02*
Y1554264D01*
X87032D01*
X87832Y1553864D01*
X88332Y1553331D01*
X88532Y1552264D01*
X88332Y1551197D01*
X87732Y1550531D01*
X87032Y1550131D01*
X84532D01*
G01X87032D02*
X88532Y1546264D01*
G01X92332D02*
Y1554264D01*
X94332D01*
X95132Y1553864D01*
X95732Y1553331D01*
X96232Y1552531D01*
X96632Y1551597D01*
X96732Y1550264D01*
X96632Y1548931D01*
X96232Y1547997D01*
X95732Y1547197D01*
X95132Y1546664D01*
X94332Y1546264D01*
X92332D01*
G01X110532D02*
X109732Y1546397D01*
X109032Y1546931D01*
X108432Y1547731D01*
X108032Y1548664D01*
X107832Y1549731D01*
Y1550797D01*
X108032Y1551864D01*
X108432Y1552797D01*
X109032Y1553597D01*
X109732Y1554131D01*
X110532Y1554264D01*
X111332Y1554131D01*
X112032Y1553597D01*
X112632Y1552797D01*
X113032Y1551864D01*
X113232Y1550797D01*
Y1549731D01*
X113032Y1548664D01*
X112632Y1547731D01*
X112032Y1546931D01*
X111332Y1546397D01*
X110532Y1546264D01*
G01X116332Y1554264D02*
Y1548531D01*
X116732Y1547330D01*
X117532Y1546531D01*
X118532Y1546264D01*
X119532Y1546531D01*
X120332Y1547330D01*
X120732Y1548531D01*
Y1554264D01*
G01X126532D02*
Y1546264D01*
G01X124232Y1554264D02*
X128832D01*
G01X132532D02*
Y1546264D01*
X136532D01*
G01X141332Y1554264D02*
X143732D01*
G01X142532D02*
Y1546264D01*
G01X141332D02*
X143732D01*
G01X148232D02*
Y1554264D01*
X152832Y1546264D01*
Y1554264D01*
G01X160532Y1546264D02*
X156532D01*
Y1554264D01*
X160532D01*
G01X158932Y1550397D02*
X156532D01*
G01X172332Y1546264D02*
Y1554264D01*
X174332D01*
X175132Y1553864D01*
X175732Y1553331D01*
X176232Y1552531D01*
X176632Y1551597D01*
X176732Y1550264D01*
X176632Y1548931D01*
X176232Y1547997D01*
X175732Y1547197D01*
X175132Y1546664D01*
X174332Y1546264D01*
X172332D01*
G01X180332Y1554264D02*
Y1548531D01*
X180732Y1547330D01*
X181532Y1546531D01*
X182532Y1546264D01*
X183532Y1546531D01*
X184332Y1547330D01*
X184732Y1548531D01*
Y1554264D01*
G01X187932Y1546264D02*
Y1554264D01*
X190532Y1547597D01*
X193132Y1554264D01*
Y1546264D01*
G01X195932D02*
Y1554264D01*
X198532Y1547597D01*
X201132Y1554264D01*
Y1546264D01*
G01X206532D02*
Y1549864D01*
X204532Y1554264D01*
G01X208532D02*
X206532Y1549864D01*
G01X220532Y1546264D02*
Y1554264D01*
X222932D01*
X223732Y1553864D01*
X224332Y1552931D01*
X224532Y1551864D01*
X224332Y1550797D01*
X223832Y1549997D01*
X222932Y1549597D01*
X220532D01*
G01X228032Y1546264D02*
X230532Y1554264D01*
X233032Y1546264D01*
G01X232132Y1549064D02*
X228932D01*
G01X236332Y1546264D02*
Y1554264D01*
X238332D01*
X239132Y1553864D01*
X239732Y1553331D01*
X240232Y1552531D01*
X240632Y1551597D01*
X240732Y1550264D01*
X240632Y1548931D01*
X240232Y1547997D01*
X239732Y1547197D01*
X239132Y1546664D01*
X238332Y1546264D01*
X236332D01*
G01X252332D02*
Y1554264D01*
X254332D01*
X255132Y1553864D01*
X255732Y1553331D01*
X256232Y1552531D01*
X256632Y1551597D01*
X256732Y1550264D01*
X256632Y1548931D01*
X256232Y1547997D01*
X255732Y1547197D01*
X255132Y1546664D01*
X254332Y1546264D01*
X252332D01*
G01X264532D02*
X260532D01*
Y1554264D01*
X264532D01*
G01X262932Y1550397D02*
X260532D01*
G01X268432Y1547330D02*
X269232Y1546664D01*
X270132Y1546264D01*
X270932D01*
X271732Y1546664D01*
X272332Y1547330D01*
X272632Y1548264D01*
X272432Y1549197D01*
X271932Y1549997D01*
X271032Y1550531D01*
X269832Y1550797D01*
X269132Y1551331D01*
X268832Y1552264D01*
X269032Y1553197D01*
X269532Y1553864D01*
X270232Y1554264D01*
X270932D01*
X271632Y1553997D01*
X272232Y1553331D01*
G01X277332Y1554264D02*
X279732D01*
G01X278532D02*
Y1546264D01*
G01X277332D02*
X279732D01*
G01X287132Y1550264D02*
X289132D01*
Y1547864D01*
X288532Y1547064D01*
X287832Y1546531D01*
X286832Y1546264D01*
X285832Y1546531D01*
X285132Y1547064D01*
X284532Y1547864D01*
X284132Y1548797D01*
X283932Y1549864D01*
Y1550797D01*
X284132Y1551597D01*
X284532Y1552531D01*
X285132Y1553331D01*
X285732Y1553864D01*
X286532Y1554264D01*
X287232D01*
X288032Y1553997D01*
X288632Y1553464D01*
G01X292232Y1546264D02*
Y1554264D01*
X296832Y1546264D01*
Y1554264D01*
G01X309332D02*
X311732D01*
G01X310532D02*
Y1546264D01*
G01X309332D02*
X311732D01*
G01X316232D02*
Y1554264D01*
X320832Y1546264D01*
Y1554264D01*
G01X332432Y1547330D02*
X333232Y1546664D01*
X334132Y1546264D01*
X334932D01*
X335732Y1546664D01*
X336332Y1547330D01*
X336632Y1548264D01*
X336432Y1549197D01*
X335932Y1549997D01*
X335032Y1550531D01*
X333832Y1550797D01*
X333132Y1551331D01*
X332832Y1552264D01*
X333032Y1553197D01*
X333532Y1553864D01*
X334232Y1554264D01*
X334932D01*
X335632Y1553997D01*
X336232Y1553331D01*
G01X342532Y1546264D02*
X341732Y1546397D01*
X341032Y1546931D01*
X340432Y1547731D01*
X340032Y1548664D01*
X339832Y1549731D01*
Y1550797D01*
X340032Y1551864D01*
X340432Y1552797D01*
X341032Y1553597D01*
X341732Y1554131D01*
X342532Y1554264D01*
X343332Y1554131D01*
X344032Y1553597D01*
X344632Y1552797D01*
X345032Y1551864D01*
X345232Y1550797D01*
Y1549731D01*
X345032Y1548664D01*
X344632Y1547731D01*
X344032Y1546931D01*
X343332Y1546397D01*
X342532Y1546264D01*
G01X343332Y1548397D02*
X344532Y1546264D01*
G01X348332Y1554264D02*
Y1548531D01*
X348732Y1547330D01*
X349532Y1546531D01*
X350532Y1546264D01*
X351532Y1546531D01*
X352332Y1547330D01*
X352732Y1548531D01*
Y1554264D01*
G01X356032Y1546264D02*
X358532Y1554264D01*
X361032Y1546264D01*
G01X360132Y1549064D02*
X356932D01*
G01X364532Y1546264D02*
Y1554264D01*
X367032D01*
X367832Y1553864D01*
X368332Y1553331D01*
X368532Y1552264D01*
X368332Y1551197D01*
X367732Y1550531D01*
X367032Y1550131D01*
X364532D01*
G01X367032D02*
X368532Y1546264D01*
G01X376532D02*
X372532D01*
Y1554264D01*
X376532D01*
G01X374932Y1550397D02*
X372532D01*
G01X388432Y1547330D02*
X389232Y1546664D01*
X390132Y1546264D01*
X390932D01*
X391732Y1546664D01*
X392332Y1547330D01*
X392632Y1548264D01*
X392432Y1549197D01*
X391932Y1549997D01*
X391032Y1550531D01*
X389832Y1550797D01*
X389132Y1551331D01*
X388832Y1552264D01*
X389032Y1553197D01*
X389532Y1553864D01*
X390232Y1554264D01*
X390932D01*
X391632Y1553997D01*
X392232Y1553331D01*
G01X396432Y1546264D02*
Y1554264D01*
G01X400632D02*
Y1546264D01*
G01Y1550264D02*
X396432D01*
G01X404032Y1546264D02*
X406532Y1554264D01*
X409032Y1546264D01*
G01X408132Y1549064D02*
X404932D01*
G01X412532Y1546264D02*
Y1554264D01*
X414932D01*
X415732Y1553864D01*
X416332Y1552931D01*
X416532Y1551864D01*
X416332Y1550797D01*
X415832Y1549997D01*
X414932Y1549597D01*
X412532D01*
G01X424532Y1546264D02*
X420532D01*
Y1554264D01*
X424532D01*
G01X422932Y1550397D02*
X420532D01*
G01X429232Y1548931D02*
X431832D01*
G01X444432Y1547330D02*
X445232Y1546664D01*
X446132Y1546264D01*
X446932D01*
X447732Y1546664D01*
X448332Y1547330D01*
X448632Y1548264D01*
X448432Y1549197D01*
X447932Y1549997D01*
X447032Y1550531D01*
X445832Y1550797D01*
X445132Y1551331D01*
X444832Y1552264D01*
X445032Y1553197D01*
X445532Y1553864D01*
X446232Y1554264D01*
X446932D01*
X447632Y1553997D01*
X448232Y1553331D01*
G01X452432Y1546264D02*
Y1554264D01*
G01X456632D02*
Y1546264D01*
G01Y1550264D02*
X452432D01*
G01X460032Y1546264D02*
X462532Y1554264D01*
X465032Y1546264D01*
G01X464132Y1549064D02*
X460932D01*
G01X468532Y1546264D02*
Y1554264D01*
X470932D01*
X471732Y1553864D01*
X472332Y1552931D01*
X472532Y1551864D01*
X472332Y1550797D01*
X471832Y1549997D01*
X470932Y1549597D01*
X468532D01*
G01X480532Y1546264D02*
X476532D01*
Y1554264D01*
X480532D01*
G01X478932Y1550397D02*
X476532D01*
G01X492432Y1547330D02*
X493232Y1546664D01*
X494132Y1546264D01*
X494932D01*
X495732Y1546664D01*
X496332Y1547330D01*
X496632Y1548264D01*
X496432Y1549197D01*
X495932Y1549997D01*
X495032Y1550531D01*
X493832Y1550797D01*
X493132Y1551331D01*
X492832Y1552264D01*
X493032Y1553197D01*
X493532Y1553864D01*
X494232Y1554264D01*
X494932D01*
X495632Y1553997D01*
X496232Y1553331D01*
G01X501332Y1554264D02*
X503732D01*
G01X502532D02*
Y1546264D01*
G01X501332D02*
X503732D01*
G01X508632Y1554264D02*
X512432D01*
X508632Y1546264D01*
X512432D01*
G01X520532D02*
X516532D01*
Y1554264D01*
X520532D01*
G01X518932Y1550397D02*
X516532D01*
G01X532332Y1547464D02*
X532932Y1546797D01*
X533632Y1546397D01*
X534532Y1546264D01*
X535432Y1546531D01*
X536132Y1547064D01*
X536632Y1547997D01*
X536732Y1549064D01*
X536532Y1550131D01*
X536032Y1550797D01*
X535332Y1551331D01*
X534632Y1551464D01*
X533932Y1551331D01*
X533032Y1550797D01*
X533332Y1554264D01*
X536032D01*
G01X542532D02*
X541732Y1553997D01*
X541132Y1553331D01*
X540732Y1552531D01*
X540432Y1551464D01*
X540332Y1550264D01*
X540432Y1549064D01*
X540732Y1547997D01*
X541132Y1547197D01*
X541732Y1546531D01*
X542532Y1546264D01*
X543332Y1546531D01*
X543932Y1547197D01*
X544332Y1547997D01*
X544632Y1549064D01*
X544732Y1550264D01*
X544632Y1551464D01*
X544332Y1552531D01*
X543932Y1553331D01*
X543332Y1553997D01*
X542532Y1554264D01*
G01X547932Y1546264D02*
Y1554264D01*
X550532Y1547597D01*
X553132Y1554264D01*
Y1546264D01*
G01X557332Y1554264D02*
X559732D01*
G01X558532D02*
Y1546264D01*
G01X557332D02*
X559732D01*
G01X564532Y1554264D02*
Y1546264D01*
X568532D01*
G01X572432Y1547330D02*
X573232Y1546664D01*
X574132Y1546264D01*
X574932D01*
X575732Y1546664D01*
X576332Y1547330D01*
X576632Y1548264D01*
X576432Y1549197D01*
X575932Y1549997D01*
X575032Y1550531D01*
X573832Y1550797D01*
X573132Y1551331D01*
X572832Y1552264D01*
X573032Y1553197D01*
X573532Y1553864D01*
X574232Y1554264D01*
X574932D01*
X575632Y1553997D01*
X576232Y1553331D01*
G01X582332Y1544797D02*
X582732Y1546531D01*
G01X596532Y1546264D02*
Y1554264D01*
X598932D01*
X599732Y1553864D01*
X600332Y1552931D01*
X600532Y1551864D01*
X600332Y1550797D01*
X599832Y1549997D01*
X598932Y1549597D01*
X596532D01*
G01X605332Y1554264D02*
X607732D01*
G01X606532D02*
Y1546264D01*
G01X605332D02*
X607732D01*
G01X614532Y1554264D02*
Y1546264D01*
G01X612232Y1554264D02*
X616832D01*
G01X624732Y1553597D02*
X624132Y1553997D01*
X623432Y1554264D01*
X622632D01*
X621732Y1553864D01*
X621032Y1553197D01*
X620532Y1552397D01*
X620132Y1551064D01*
X620032Y1549864D01*
X620232Y1548664D01*
X620532Y1547864D01*
X621132Y1547064D01*
X621832Y1546531D01*
X622532Y1546264D01*
X623232D01*
X623932Y1546531D01*
X624532Y1546931D01*
X625032Y1547464D01*
G01X628432Y1546264D02*
Y1554264D01*
G01X632632D02*
Y1546264D01*
G01Y1550264D02*
X628432D01*
G01X646032Y1543597D02*
X645032Y1544931D01*
X644532Y1546264D01*
Y1551597D01*
X645032Y1552931D01*
X646032Y1554264D01*
G01X652432Y1547330D02*
X653232Y1546664D01*
X654132Y1546264D01*
X654932D01*
X655732Y1546664D01*
X656332Y1547330D01*
X656632Y1548264D01*
X656432Y1549197D01*
X655932Y1549997D01*
X655032Y1550531D01*
X653832Y1550797D01*
X653132Y1551331D01*
X652832Y1552264D01*
X653032Y1553197D01*
X653532Y1553864D01*
X654232Y1554264D01*
X654932D01*
X655632Y1553997D01*
X656232Y1553331D01*
G01X660432Y1546264D02*
Y1554264D01*
G01X664632D02*
Y1546264D01*
G01Y1550264D02*
X660432D01*
G01X668032Y1546264D02*
X670532Y1554264D01*
X673032Y1546264D01*
G01X672132Y1549064D02*
X668932D01*
G01X676532Y1546264D02*
Y1554264D01*
X678932D01*
X679732Y1553864D01*
X680332Y1552931D01*
X680532Y1551864D01*
X680332Y1550797D01*
X679832Y1549997D01*
X678932Y1549597D01*
X676532D01*
G01X688532Y1546264D02*
X684532D01*
Y1554264D01*
X688532D01*
G01X686932Y1550397D02*
X684532D01*
G01X704732Y1553597D02*
X704132Y1553997D01*
X703432Y1554264D01*
X702632D01*
X701732Y1553864D01*
X701032Y1553197D01*
X700532Y1552397D01*
X700132Y1551064D01*
X700032Y1549864D01*
X700232Y1548664D01*
X700532Y1547864D01*
X701132Y1547064D01*
X701832Y1546531D01*
X702532Y1546264D01*
X703232D01*
X703932Y1546531D01*
X704532Y1546931D01*
X705032Y1547464D01*
G01X712532Y1546264D02*
X708532D01*
Y1554264D01*
X712532D01*
G01X710932Y1550397D02*
X708532D01*
G01X716232Y1546264D02*
Y1554264D01*
X720832Y1546264D01*
Y1554264D01*
G01X726532D02*
Y1546264D01*
G01X724232Y1554264D02*
X728832D01*
G01X736532Y1546264D02*
X732532D01*
Y1554264D01*
X736532D01*
G01X734932Y1550397D02*
X732532D01*
G01X740532Y1546264D02*
Y1554264D01*
X743032D01*
X743832Y1553864D01*
X744332Y1553331D01*
X744532Y1552264D01*
X744332Y1551197D01*
X743732Y1550531D01*
X743032Y1550131D01*
X740532D01*
G01X743032D02*
X744532Y1546264D01*
G01X758532Y1554264D02*
Y1546264D01*
G01X756232Y1554264D02*
X760832D01*
G01X766532Y1546264D02*
X765732Y1546397D01*
X765032Y1546931D01*
X764432Y1547731D01*
X764032Y1548664D01*
X763832Y1549731D01*
Y1550797D01*
X764032Y1551864D01*
X764432Y1552797D01*
X765032Y1553597D01*
X765732Y1554131D01*
X766532Y1554264D01*
X767332Y1554131D01*
X768032Y1553597D01*
X768632Y1552797D01*
X769032Y1551864D01*
X769232Y1550797D01*
Y1549731D01*
X769032Y1548664D01*
X768632Y1547731D01*
X768032Y1546931D01*
X767332Y1546397D01*
X766532Y1546264D01*
G01X784732Y1553597D02*
X784132Y1553997D01*
X783432Y1554264D01*
X782632D01*
X781732Y1553864D01*
X781032Y1553197D01*
X780532Y1552397D01*
X780132Y1551064D01*
X780032Y1549864D01*
X780232Y1548664D01*
X780532Y1547864D01*
X781132Y1547064D01*
X781832Y1546531D01*
X782532Y1546264D01*
X783232D01*
X783932Y1546531D01*
X784532Y1546931D01*
X785032Y1547464D01*
G01X792532Y1546264D02*
X788532D01*
Y1554264D01*
X792532D01*
G01X790932Y1550397D02*
X788532D01*
G01X796232Y1546264D02*
Y1554264D01*
X800832Y1546264D01*
Y1554264D01*
G01X806532D02*
Y1546264D01*
G01X804232Y1554264D02*
X808832D01*
G01X816532Y1546264D02*
X812532D01*
Y1554264D01*
X816532D01*
G01X814932Y1550397D02*
X812532D01*
G01X820532Y1546264D02*
Y1554264D01*
X823032D01*
X823832Y1553864D01*
X824332Y1553331D01*
X824532Y1552264D01*
X824332Y1551197D01*
X823732Y1550531D01*
X823032Y1550131D01*
X820532D01*
G01X823032D02*
X824532Y1546264D01*
G01X831032Y1543597D02*
X832032Y1544931D01*
X832532Y1546264D01*
Y1551597D01*
X832032Y1552931D01*
X831032Y1554264D01*
G01X838532Y1545997D02*
X838332Y1546131D01*
Y1546397D01*
X838532Y1546531D01*
X838732Y1546397D01*
Y1546131D01*
X838532Y1545997D01*
G01Y1549597D02*
X838332Y1549731D01*
Y1549997D01*
X838532Y1550131D01*
X838732Y1549997D01*
Y1549731D01*
X838532Y1549597D01*
G01X854532Y1546264D02*
Y1554264D01*
X853332Y1552664D01*
G01Y1546264D02*
X855732D01*
G01X862532Y1554264D02*
X861732Y1553997D01*
X861132Y1553331D01*
X860732Y1552531D01*
X860432Y1551464D01*
X860332Y1550264D01*
X860432Y1549064D01*
X860732Y1547997D01*
X861132Y1547197D01*
X861732Y1546531D01*
X862532Y1546264D01*
X863332Y1546531D01*
X863932Y1547197D01*
X864332Y1547997D01*
X864632Y1549064D01*
X864732Y1550264D01*
X864632Y1551464D01*
X864332Y1552531D01*
X863932Y1553331D01*
X863332Y1553997D01*
X862532Y1554264D01*
G01X870532D02*
X869732Y1553997D01*
X869132Y1553331D01*
X868732Y1552531D01*
X868432Y1551464D01*
X868332Y1550264D01*
X868432Y1549064D01*
X868732Y1547997D01*
X869132Y1547197D01*
X869732Y1546531D01*
X870532Y1546264D01*
X871332Y1546531D01*
X871932Y1547197D01*
X872332Y1547997D01*
X872632Y1549064D01*
X872732Y1550264D01*
X872632Y1551464D01*
X872332Y1552531D01*
X871932Y1553331D01*
X871332Y1553997D01*
X870532Y1554264D01*
G01X875932Y1546264D02*
Y1554264D01*
X878532Y1547597D01*
X881132Y1554264D01*
Y1546264D01*
G01X885332Y1554264D02*
X887732D01*
G01X886532D02*
Y1546264D01*
G01X885332D02*
X887732D01*
G01X892532Y1554264D02*
Y1546264D01*
X896532D01*
G01X900432Y1547330D02*
X901232Y1546664D01*
X902132Y1546264D01*
X902932D01*
X903732Y1546664D01*
X904332Y1547330D01*
X904632Y1548264D01*
X904432Y1549197D01*
X903932Y1549997D01*
X903032Y1550531D01*
X901832Y1550797D01*
X901132Y1551331D01*
X900832Y1552264D01*
X901032Y1553197D01*
X901532Y1553864D01*
X902232Y1554264D01*
X902932D01*
X903632Y1553997D01*
X904232Y1553331D01*
G01X910532Y1545997D02*
X910332Y1546131D01*
Y1546397D01*
X910532Y1546531D01*
X910732Y1546397D01*
Y1546131D01*
X910532Y1545997D01*
G01X924332Y1546264D02*
Y1554264D01*
X926332D01*
X927132Y1553864D01*
X927732Y1553331D01*
X928232Y1552531D01*
X928632Y1551597D01*
X928732Y1550264D01*
X928632Y1548931D01*
X928232Y1547997D01*
X927732Y1547197D01*
X927132Y1546664D01*
X926332Y1546264D01*
X924332D01*
G01X932532D02*
Y1554264D01*
X935032D01*
X935832Y1553864D01*
X936332Y1553331D01*
X936532Y1552264D01*
X936332Y1551197D01*
X935732Y1550531D01*
X935032Y1550131D01*
X932532D01*
G01X935032D02*
X936532Y1546264D01*
G01X941332Y1554264D02*
X943732D01*
G01X942532D02*
Y1546264D01*
G01X941332D02*
X943732D01*
G01X948532Y1554264D02*
Y1546264D01*
X952532D01*
G01X956532Y1554264D02*
Y1546264D01*
X960532D01*
G01X964732Y1545997D02*
X968332Y1554264D01*
G01X972632Y1546264D02*
Y1554264D01*
X976432D01*
G01X975032Y1550397D02*
X972632D01*
G01X984532Y1546264D02*
X980532D01*
Y1554264D01*
X984532D01*
G01X982932Y1550397D02*
X980532D01*
G01X988032Y1546264D02*
X990532Y1554264D01*
X993032Y1546264D01*
G01X992132Y1549064D02*
X988932D01*
G01X998532Y1554264D02*
Y1546264D01*
G01X996232Y1554264D02*
X1000832D01*
G01X1004332D02*
Y1548531D01*
X1004732Y1547330D01*
X1005532Y1546531D01*
X1006532Y1546264D01*
X1007532Y1546531D01*
X1008332Y1547330D01*
X1008732Y1548531D01*
Y1554264D01*
G01X1012532Y1546264D02*
Y1554264D01*
X1015032D01*
X1015832Y1553864D01*
X1016332Y1553331D01*
X1016532Y1552264D01*
X1016332Y1551197D01*
X1015732Y1550531D01*
X1015032Y1550131D01*
X1012532D01*
G01X1015032D02*
X1016532Y1546264D01*
G01X1024532D02*
X1020532D01*
Y1554264D01*
X1024532D01*
G01X1022932Y1550397D02*
X1020532D01*
G01X1028732Y1545997D02*
X1032332Y1554264D01*
G01X1036532Y1546264D02*
Y1554264D01*
X1039032D01*
X1039832Y1553864D01*
X1040332Y1553331D01*
X1040532Y1552264D01*
X1040332Y1551197D01*
X1039732Y1550531D01*
X1039032Y1550131D01*
X1036532D01*
G01X1039032D02*
X1040532Y1546264D01*
G01X1046532D02*
X1045732Y1546397D01*
X1045032Y1546931D01*
X1044432Y1547731D01*
X1044032Y1548664D01*
X1043832Y1549731D01*
Y1550797D01*
X1044032Y1551864D01*
X1044432Y1552797D01*
X1045032Y1553597D01*
X1045732Y1554131D01*
X1046532Y1554264D01*
X1047332Y1554131D01*
X1048032Y1553597D01*
X1048632Y1552797D01*
X1049032Y1551864D01*
X1049232Y1550797D01*
Y1549731D01*
X1049032Y1548664D01*
X1048632Y1547731D01*
X1048032Y1546931D01*
X1047332Y1546397D01*
X1046532Y1546264D01*
G01X1052332Y1554264D02*
Y1548531D01*
X1052732Y1547330D01*
X1053532Y1546531D01*
X1054532Y1546264D01*
X1055532Y1546531D01*
X1056332Y1547330D01*
X1056732Y1548531D01*
Y1554264D01*
G01X1062532D02*
Y1546264D01*
G01X1060232Y1554264D02*
X1064832D01*
G01X1072532Y1546264D02*
X1068532D01*
Y1554264D01*
X1072532D01*
G01X1070932Y1550397D02*
X1068532D01*
G01X1076732Y1545997D02*
X1080332Y1554264D01*
G01X1084532Y1546264D02*
Y1554264D01*
X1086932D01*
X1087732Y1553864D01*
X1088332Y1552931D01*
X1088532Y1551864D01*
X1088332Y1550797D01*
X1087832Y1549997D01*
X1086932Y1549597D01*
X1084532D01*
G01X1092532Y1546264D02*
Y1554264D01*
X1095032D01*
X1095832Y1553864D01*
X1096332Y1553331D01*
X1096532Y1552264D01*
X1096332Y1551197D01*
X1095732Y1550531D01*
X1095032Y1550131D01*
X1092532D01*
G01X1095032D02*
X1096532Y1546264D01*
G01X1102532D02*
X1101732Y1546397D01*
X1101032Y1546931D01*
X1100432Y1547731D01*
X1100032Y1548664D01*
X1099832Y1549731D01*
Y1550797D01*
X1100032Y1551864D01*
X1100432Y1552797D01*
X1101032Y1553597D01*
X1101732Y1554131D01*
X1102532Y1554264D01*
X1103332Y1554131D01*
X1104032Y1553597D01*
X1104632Y1552797D01*
X1105032Y1551864D01*
X1105232Y1550797D01*
Y1549731D01*
X1105032Y1548664D01*
X1104632Y1547731D01*
X1104032Y1546931D01*
X1103332Y1546397D01*
X1102532Y1546264D01*
G01X1108632D02*
Y1554264D01*
X1112432D01*
G01X1111032Y1550397D02*
X1108632D01*
G01X1117332Y1554264D02*
X1119732D01*
G01X1118532D02*
Y1546264D01*
G01X1117332D02*
X1119732D01*
G01X1124532Y1554264D02*
Y1546264D01*
X1128532D01*
G01X1136532D02*
X1132532D01*
Y1554264D01*
X1136532D01*
G01X1134932Y1550397D02*
X1132532D01*
G01X1148432Y1547330D02*
X1149232Y1546664D01*
X1150132Y1546264D01*
X1150932D01*
X1151732Y1546664D01*
X1152332Y1547330D01*
X1152632Y1548264D01*
X1152432Y1549197D01*
X1151932Y1549997D01*
X1151032Y1550531D01*
X1149832Y1550797D01*
X1149132Y1551331D01*
X1148832Y1552264D01*
X1149032Y1553197D01*
X1149532Y1553864D01*
X1150232Y1554264D01*
X1150932D01*
X1151632Y1553997D01*
X1152232Y1553331D01*
G01X1156532Y1546264D02*
Y1554264D01*
X1158932D01*
X1159732Y1553864D01*
X1160332Y1552931D01*
X1160532Y1551864D01*
X1160332Y1550797D01*
X1159832Y1549997D01*
X1158932Y1549597D01*
X1156532D01*
G01X1164032Y1546264D02*
X1166532Y1554264D01*
X1169032Y1546264D01*
G01X1168132Y1549064D02*
X1164932D01*
G01X1176732Y1553597D02*
X1176132Y1553997D01*
X1175432Y1554264D01*
X1174632D01*
X1173732Y1553864D01*
X1173032Y1553197D01*
X1172532Y1552397D01*
X1172132Y1551064D01*
X1172032Y1549864D01*
X1172232Y1548664D01*
X1172532Y1547864D01*
X1173132Y1547064D01*
X1173832Y1546531D01*
X1174532Y1546264D01*
X1175232D01*
X1175932Y1546531D01*
X1176532Y1546931D01*
X1177032Y1547464D01*
G01X1181332Y1554264D02*
X1183732D01*
G01X1182532D02*
Y1546264D01*
G01X1181332D02*
X1183732D01*
G01X1188232D02*
Y1554264D01*
X1192832Y1546264D01*
Y1554264D01*
G01X1199132Y1550264D02*
X1201132D01*
Y1547864D01*
X1200532Y1547064D01*
X1199832Y1546531D01*
X1198832Y1546264D01*
X1197832Y1546531D01*
X1197132Y1547064D01*
X1196532Y1547864D01*
X1196132Y1548797D01*
X1195932Y1549864D01*
Y1550797D01*
X1196132Y1551597D01*
X1196532Y1552531D01*
X1197132Y1553331D01*
X1197732Y1553864D01*
X1198532Y1554264D01*
X1199232D01*
X1200032Y1553997D01*
X1200632Y1553464D01*
G01X1212032Y1546264D02*
X1214532Y1554264D01*
X1217032Y1546264D01*
G01X1216132Y1549064D02*
X1212932D01*
G01X1220532Y1554264D02*
Y1546264D01*
X1224532D01*
G01X1228532Y1554264D02*
Y1546264D01*
X1232532D01*
G01X1244332Y1554264D02*
Y1548531D01*
X1244732Y1547330D01*
X1245532Y1546531D01*
X1246532Y1546264D01*
X1247532Y1546531D01*
X1248332Y1547330D01*
X1248732Y1548531D01*
Y1554264D01*
G01X1252432Y1547330D02*
X1253232Y1546664D01*
X1254132Y1546264D01*
X1254932D01*
X1255732Y1546664D01*
X1256332Y1547330D01*
X1256632Y1548264D01*
X1256432Y1549197D01*
X1255932Y1549997D01*
X1255032Y1550531D01*
X1253832Y1550797D01*
X1253132Y1551331D01*
X1252832Y1552264D01*
X1253032Y1553197D01*
X1253532Y1553864D01*
X1254232Y1554264D01*
X1254932D01*
X1255632Y1553997D01*
X1256232Y1553331D01*
G01X1261332Y1554264D02*
X1263732D01*
G01X1262532D02*
Y1546264D01*
G01X1261332D02*
X1263732D01*
G01X1268232D02*
Y1554264D01*
X1272832Y1546264D01*
Y1554264D01*
G01X1279132Y1550264D02*
X1281132D01*
Y1547864D01*
X1280532Y1547064D01*
X1279832Y1546531D01*
X1278832Y1546264D01*
X1277832Y1546531D01*
X1277132Y1547064D01*
X1276532Y1547864D01*
X1276132Y1548797D01*
X1275932Y1549864D01*
Y1550797D01*
X1276132Y1551597D01*
X1276532Y1552531D01*
X1277132Y1553331D01*
X1277732Y1553864D01*
X1278532Y1554264D01*
X1279232D01*
X1280032Y1553997D01*
X1280632Y1553464D01*
G01X1294532Y1546264D02*
Y1554264D01*
X1293332Y1552664D01*
G01Y1546264D02*
X1295732D01*
G01X1302532Y1554264D02*
X1301732Y1553997D01*
X1301132Y1553331D01*
X1300732Y1552531D01*
X1300432Y1551464D01*
X1300332Y1550264D01*
X1300432Y1549064D01*
X1300732Y1547997D01*
X1301132Y1547197D01*
X1301732Y1546531D01*
X1302532Y1546264D01*
X1303332Y1546531D01*
X1303932Y1547197D01*
X1304332Y1547997D01*
X1304632Y1549064D01*
X1304732Y1550264D01*
X1304632Y1551464D01*
X1304332Y1552531D01*
X1303932Y1553331D01*
X1303332Y1553997D01*
X1302532Y1554264D01*
G01X1310532D02*
X1309732Y1553997D01*
X1309132Y1553331D01*
X1308732Y1552531D01*
X1308432Y1551464D01*
X1308332Y1550264D01*
X1308432Y1549064D01*
X1308732Y1547997D01*
X1309132Y1547197D01*
X1309732Y1546531D01*
X1310532Y1546264D01*
X1311332Y1546531D01*
X1311932Y1547197D01*
X1312332Y1547997D01*
X1312632Y1549064D01*
X1312732Y1550264D01*
X1312632Y1551464D01*
X1312332Y1552531D01*
X1311932Y1553331D01*
X1311332Y1553997D01*
X1310532Y1554264D01*
G01X1315932Y1546264D02*
Y1554264D01*
X1318532Y1547597D01*
X1321132Y1554264D01*
Y1546264D01*
G01X1325332Y1554264D02*
X1327732D01*
G01X1326532D02*
Y1546264D01*
G01X1325332D02*
X1327732D01*
G01X1332532Y1554264D02*
Y1546264D01*
X1336532D01*
G01X1340432Y1547330D02*
X1341232Y1546664D01*
X1342132Y1546264D01*
X1342932D01*
X1343732Y1546664D01*
X1344332Y1547330D01*
X1344632Y1548264D01*
X1344432Y1549197D01*
X1343932Y1549997D01*
X1343032Y1550531D01*
X1341832Y1550797D01*
X1341132Y1551331D01*
X1340832Y1552264D01*
X1341032Y1553197D01*
X1341532Y1553864D01*
X1342232Y1554264D01*
X1342932D01*
X1343632Y1553997D01*
X1344232Y1553331D01*
G01X1350532Y1545997D02*
X1350332Y1546131D01*
Y1546397D01*
X1350532Y1546531D01*
X1350732Y1546397D01*
Y1546131D01*
X1350532Y1545997D01*
G01X1372532Y1554264D02*
Y1546264D01*
X1376532D01*
G01X1380032D02*
X1382532Y1554264D01*
X1385032Y1546264D01*
G01X1384132Y1549064D02*
X1380932D01*
G01X1391332Y1550531D02*
X1391732Y1550931D01*
X1392032Y1551597D01*
X1392232Y1552531D01*
X1392032Y1553331D01*
X1391632Y1553864D01*
X1390932Y1554264D01*
X1388232D01*
Y1546264D01*
X1391532D01*
X1392232Y1546797D01*
X1392632Y1547597D01*
X1392832Y1548531D01*
X1392632Y1549464D01*
X1392032Y1550264D01*
X1391332Y1550531D01*
X1388232D01*
G01X1400532Y1546264D02*
X1396532D01*
Y1554264D01*
X1400532D01*
G01X1398932Y1550397D02*
X1396532D01*
G01X1404532Y1554264D02*
Y1546264D01*
X1408532D01*
G01X1420032D02*
X1422532Y1554264D01*
X1425032Y1546264D01*
G01X1424132Y1549064D02*
X1420932D01*
G01X1428532Y1546264D02*
Y1554264D01*
X1431032D01*
X1431832Y1553864D01*
X1432332Y1553331D01*
X1432532Y1552264D01*
X1432332Y1551197D01*
X1431732Y1550531D01*
X1431032Y1550131D01*
X1428532D01*
G01X1431032D02*
X1432532Y1546264D01*
G01X1440532D02*
X1436532D01*
Y1554264D01*
X1440532D01*
G01X1438932Y1550397D02*
X1436532D01*
G01X1444032Y1546264D02*
X1446532Y1554264D01*
X1449032Y1546264D01*
G01X1448132Y1549064D02*
X1444932D01*
G01X1460232Y1546264D02*
Y1554264D01*
X1464832Y1546264D01*
Y1554264D01*
G01X1470532Y1546264D02*
X1469732Y1546397D01*
X1469032Y1546931D01*
X1468432Y1547731D01*
X1468032Y1548664D01*
X1467832Y1549731D01*
Y1550797D01*
X1468032Y1551864D01*
X1468432Y1552797D01*
X1469032Y1553597D01*
X1469732Y1554131D01*
X1470532Y1554264D01*
X1471332Y1554131D01*
X1472032Y1553597D01*
X1472632Y1552797D01*
X1473032Y1551864D01*
X1473232Y1550797D01*
Y1549731D01*
X1473032Y1548664D01*
X1472632Y1547731D01*
X1472032Y1546931D01*
X1471332Y1546397D01*
X1470532Y1546264D01*
G01X1484032D02*
X1486532Y1554264D01*
X1489032Y1546264D01*
G01X1488132Y1549064D02*
X1484932D01*
G01X1492332Y1546264D02*
Y1554264D01*
X1494332D01*
X1495132Y1553864D01*
X1495732Y1553331D01*
X1496232Y1552531D01*
X1496632Y1551597D01*
X1496732Y1550264D01*
X1496632Y1548931D01*
X1496232Y1547997D01*
X1495732Y1547197D01*
X1495132Y1546664D01*
X1494332Y1546264D01*
X1492332D01*
G01X1500332D02*
Y1554264D01*
X1502332D01*
X1503132Y1553864D01*
X1503732Y1553331D01*
X1504232Y1552531D01*
X1504632Y1551597D01*
X1504732Y1550264D01*
X1504632Y1548931D01*
X1504232Y1547997D01*
X1503732Y1547197D01*
X1503132Y1546664D01*
X1502332Y1546264D01*
X1500332D01*
G01X1516332D02*
Y1554264D01*
X1518332D01*
X1519132Y1553864D01*
X1519732Y1553331D01*
X1520232Y1552531D01*
X1520632Y1551597D01*
X1520732Y1550264D01*
X1520632Y1548931D01*
X1520232Y1547997D01*
X1519732Y1547197D01*
X1519132Y1546664D01*
X1518332Y1546264D01*
X1516332D01*
G01X1524332Y1554264D02*
Y1548531D01*
X1524732Y1547330D01*
X1525532Y1546531D01*
X1526532Y1546264D01*
X1527532Y1546531D01*
X1528332Y1547330D01*
X1528732Y1548531D01*
Y1554264D01*
G01X1531932Y1546264D02*
Y1554264D01*
X1534532Y1547597D01*
X1537132Y1554264D01*
Y1546264D01*
G01X1539932D02*
Y1554264D01*
X1542532Y1547597D01*
X1545132Y1554264D01*
Y1546264D01*
G01X1550532D02*
Y1549864D01*
X1548532Y1554264D01*
G01X1552532D02*
X1550532Y1549864D01*
G01X1564532Y1546264D02*
Y1554264D01*
X1566932D01*
X1567732Y1553864D01*
X1568332Y1552931D01*
X1568532Y1551864D01*
X1568332Y1550797D01*
X1567832Y1549997D01*
X1566932Y1549597D01*
X1564532D01*
G01X1572032Y1546264D02*
X1574532Y1554264D01*
X1577032Y1546264D01*
G01X1576132Y1549064D02*
X1572932D01*
G01X1580332Y1546264D02*
Y1554264D01*
X1582332D01*
X1583132Y1553864D01*
X1583732Y1553331D01*
X1584232Y1552531D01*
X1584632Y1551597D01*
X1584732Y1550264D01*
X1584632Y1548931D01*
X1584232Y1547997D01*
X1583732Y1547197D01*
X1583132Y1546664D01*
X1582332Y1546264D01*
X1580332D01*
G01X1590532Y1545997D02*
X1590332Y1546131D01*
Y1546397D01*
X1590532Y1546531D01*
X1590732Y1546397D01*
Y1546131D01*
X1590532Y1545997D01*
G01X-27668Y1607464D02*
X-27068Y1606797D01*
X-26368Y1606397D01*
X-25468Y1606264D01*
X-24568Y1606531D01*
X-23868Y1607064D01*
X-23368Y1607997D01*
X-23268Y1609064D01*
X-23468Y1610131D01*
X-23968Y1610797D01*
X-24668Y1611331D01*
X-25368Y1611464D01*
X-26068Y1611331D01*
X-26968Y1610797D01*
X-26668Y1614264D01*
X-23968D01*
G01X-17468Y1605997D02*
X-17668Y1606131D01*
Y1606397D01*
X-17468Y1606531D01*
X-17268Y1606397D01*
Y1606131D01*
X-17468Y1605997D01*
G01X-11468Y1606264D02*
Y1614264D01*
X-9068D01*
X-8268Y1613864D01*
X-7668Y1612931D01*
X-7468Y1611864D01*
X-7668Y1610797D01*
X-8168Y1609997D01*
X-9068Y1609597D01*
X-11468D01*
G01X532Y1606264D02*
X-3468D01*
Y1614264D01*
X532D01*
G01X-1068Y1610397D02*
X-3468D01*
G01X8532Y1606264D02*
X4532D01*
Y1614264D01*
X8532D01*
G01X6932Y1610397D02*
X4532D01*
G01X12532Y1614264D02*
Y1606264D01*
X16532D01*
G01X21332Y1614264D02*
X23732D01*
G01X22532D02*
Y1606264D01*
G01X21332D02*
X23732D01*
G01X28232D02*
Y1614264D01*
X32832Y1606264D01*
Y1614264D01*
G01X39132Y1610264D02*
X41132D01*
Y1607864D01*
X40532Y1607064D01*
X39832Y1606531D01*
X38832Y1606264D01*
X37832Y1606531D01*
X37132Y1607064D01*
X36532Y1607864D01*
X36132Y1608797D01*
X35932Y1609864D01*
Y1610797D01*
X36132Y1611597D01*
X36532Y1612531D01*
X37132Y1613331D01*
X37732Y1613864D01*
X38532Y1614264D01*
X39232D01*
X40032Y1613997D01*
X40632Y1613464D01*
G01X52432Y1607330D02*
X53232Y1606664D01*
X54132Y1606264D01*
X54932D01*
X55732Y1606664D01*
X56332Y1607330D01*
X56632Y1608264D01*
X56432Y1609197D01*
X55932Y1609997D01*
X55032Y1610531D01*
X53832Y1610797D01*
X53132Y1611331D01*
X52832Y1612264D01*
X53032Y1613197D01*
X53532Y1613864D01*
X54232Y1614264D01*
X54932D01*
X55632Y1613997D01*
X56232Y1613331D01*
G01X62532Y1614264D02*
Y1606264D01*
G01X60232Y1614264D02*
X64832D01*
G01X68532Y1606264D02*
Y1614264D01*
X71032D01*
X71832Y1613864D01*
X72332Y1613331D01*
X72532Y1612264D01*
X72332Y1611197D01*
X71732Y1610531D01*
X71032Y1610131D01*
X68532D01*
G01X71032D02*
X72532Y1606264D01*
G01X80532D02*
X76532D01*
Y1614264D01*
X80532D01*
G01X78932Y1610397D02*
X76532D01*
G01X84232Y1606264D02*
Y1614264D01*
X88832Y1606264D01*
Y1614264D01*
G01X95132Y1610264D02*
X97132D01*
Y1607864D01*
X96532Y1607064D01*
X95832Y1606531D01*
X94832Y1606264D01*
X93832Y1606531D01*
X93132Y1607064D01*
X92532Y1607864D01*
X92132Y1608797D01*
X91932Y1609864D01*
Y1610797D01*
X92132Y1611597D01*
X92532Y1612531D01*
X93132Y1613331D01*
X93732Y1613864D01*
X94532Y1614264D01*
X95232D01*
X96032Y1613997D01*
X96632Y1613464D01*
G01X102532Y1614264D02*
Y1606264D01*
G01X100232Y1614264D02*
X104832D01*
G01X108432Y1606264D02*
Y1614264D01*
G01X112632D02*
Y1606264D01*
G01Y1610264D02*
X108432D01*
G01X124032Y1606264D02*
X126532Y1614264D01*
X129032Y1606264D01*
G01X128132Y1609064D02*
X124932D01*
G01X132232Y1606264D02*
Y1614264D01*
X136832Y1606264D01*
Y1614264D01*
G01X140332Y1606264D02*
Y1614264D01*
X142332D01*
X143132Y1613864D01*
X143732Y1613331D01*
X144232Y1612531D01*
X144632Y1611597D01*
X144732Y1610264D01*
X144632Y1608931D01*
X144232Y1607997D01*
X143732Y1607197D01*
X143132Y1606664D01*
X142332Y1606264D01*
X140332D01*
G01X159332Y1610531D02*
X159732Y1610931D01*
X160032Y1611597D01*
X160232Y1612531D01*
X160032Y1613331D01*
X159632Y1613864D01*
X158932Y1614264D01*
X156232D01*
Y1606264D01*
X159532D01*
X160232Y1606797D01*
X160632Y1607597D01*
X160832Y1608531D01*
X160632Y1609464D01*
X160032Y1610264D01*
X159332Y1610531D01*
X156232D01*
G01X167132Y1610264D02*
X169132D01*
Y1607864D01*
X168532Y1607064D01*
X167832Y1606531D01*
X166832Y1606264D01*
X165832Y1606531D01*
X165132Y1607064D01*
X164532Y1607864D01*
X164132Y1608797D01*
X163932Y1609864D01*
Y1610797D01*
X164132Y1611597D01*
X164532Y1612531D01*
X165132Y1613331D01*
X165732Y1613864D01*
X166532Y1614264D01*
X167232D01*
X168032Y1613997D01*
X168632Y1613464D01*
G01X172032Y1606264D02*
X174532Y1614264D01*
X177032Y1606264D01*
G01X176132Y1609064D02*
X172932D01*
G01X188532Y1606264D02*
Y1614264D01*
X190932D01*
X191732Y1613864D01*
X192332Y1612931D01*
X192532Y1611864D01*
X192332Y1610797D01*
X191832Y1609997D01*
X190932Y1609597D01*
X188532D01*
G01X196032Y1606264D02*
X198532Y1614264D01*
X201032Y1606264D01*
G01X200132Y1609064D02*
X196932D01*
G01X204332Y1606264D02*
Y1614264D01*
X206332D01*
X207132Y1613864D01*
X207732Y1613331D01*
X208232Y1612531D01*
X208632Y1611597D01*
X208732Y1610264D01*
X208632Y1608931D01*
X208232Y1607997D01*
X207732Y1607197D01*
X207132Y1606664D01*
X206332Y1606264D01*
X204332D01*
G01X212432Y1607330D02*
X213232Y1606664D01*
X214132Y1606264D01*
X214932D01*
X215732Y1606664D01*
X216332Y1607330D01*
X216632Y1608264D01*
X216432Y1609197D01*
X215932Y1609997D01*
X215032Y1610531D01*
X213832Y1610797D01*
X213132Y1611331D01*
X212832Y1612264D01*
X213032Y1613197D01*
X213532Y1613864D01*
X214232Y1614264D01*
X214932D01*
X215632Y1613997D01*
X216232Y1613331D01*
G01X228032Y1606264D02*
X230532Y1614264D01*
X233032Y1606264D01*
G01X232132Y1609064D02*
X228932D01*
G01X236332Y1606264D02*
Y1614264D01*
X238332D01*
X239132Y1613864D01*
X239732Y1613331D01*
X240232Y1612531D01*
X240632Y1611597D01*
X240732Y1610264D01*
X240632Y1608931D01*
X240232Y1607997D01*
X239732Y1607197D01*
X239132Y1606664D01*
X238332Y1606264D01*
X236332D01*
G01X244432D02*
Y1614264D01*
G01X248632D02*
Y1606264D01*
G01Y1610264D02*
X244432D01*
G01X256532Y1606264D02*
X252532D01*
Y1614264D01*
X256532D01*
G01X254932Y1610397D02*
X252532D01*
G01X260432Y1607330D02*
X261232Y1606664D01*
X262132Y1606264D01*
X262932D01*
X263732Y1606664D01*
X264332Y1607330D01*
X264632Y1608264D01*
X264432Y1609197D01*
X263932Y1609997D01*
X263032Y1610531D01*
X261832Y1610797D01*
X261132Y1611331D01*
X260832Y1612264D01*
X261032Y1613197D01*
X261532Y1613864D01*
X262232Y1614264D01*
X262932D01*
X263632Y1613997D01*
X264232Y1613331D01*
G01X269332Y1614264D02*
X271732D01*
G01X270532D02*
Y1606264D01*
G01X269332D02*
X271732D01*
G01X278532D02*
X277732Y1606397D01*
X277032Y1606931D01*
X276432Y1607731D01*
X276032Y1608664D01*
X275832Y1609731D01*
Y1610797D01*
X276032Y1611864D01*
X276432Y1612797D01*
X277032Y1613597D01*
X277732Y1614131D01*
X278532Y1614264D01*
X279332Y1614131D01*
X280032Y1613597D01*
X280632Y1612797D01*
X281032Y1611864D01*
X281232Y1610797D01*
Y1609731D01*
X281032Y1608664D01*
X280632Y1607731D01*
X280032Y1606931D01*
X279332Y1606397D01*
X278532Y1606264D01*
G01X284232D02*
Y1614264D01*
X288832Y1606264D01*
Y1614264D01*
G01X302532D02*
Y1606264D01*
G01X300232Y1614264D02*
X304832D01*
G01X312532Y1606264D02*
X308532D01*
Y1614264D01*
X312532D01*
G01X310932Y1610397D02*
X308532D01*
G01X316432Y1607330D02*
X317232Y1606664D01*
X318132Y1606264D01*
X318932D01*
X319732Y1606664D01*
X320332Y1607330D01*
X320632Y1608264D01*
X320432Y1609197D01*
X319932Y1609997D01*
X319032Y1610531D01*
X317832Y1610797D01*
X317132Y1611331D01*
X316832Y1612264D01*
X317032Y1613197D01*
X317532Y1613864D01*
X318232Y1614264D01*
X318932D01*
X319632Y1613997D01*
X320232Y1613331D01*
G01X326532Y1614264D02*
Y1606264D01*
G01X324232Y1614264D02*
X328832D01*
G01X340532Y1606264D02*
Y1614264D01*
X342932D01*
X343732Y1613864D01*
X344332Y1612931D01*
X344532Y1611864D01*
X344332Y1610797D01*
X343832Y1609997D01*
X342932Y1609597D01*
X340532D01*
G01X348032Y1606264D02*
X350532Y1614264D01*
X353032Y1606264D01*
G01X352132Y1609064D02*
X348932D01*
G01X358532Y1614264D02*
Y1606264D01*
G01X356232Y1614264D02*
X360832D01*
G01X366532D02*
Y1606264D01*
G01X364232Y1614264D02*
X368832D01*
G01X376532Y1606264D02*
X372532D01*
Y1614264D01*
X376532D01*
G01X374932Y1610397D02*
X372532D01*
G01X380532Y1606264D02*
Y1614264D01*
X383032D01*
X383832Y1613864D01*
X384332Y1613331D01*
X384532Y1612264D01*
X384332Y1611197D01*
X383732Y1610531D01*
X383032Y1610131D01*
X380532D01*
G01X383032D02*
X384532Y1606264D01*
G01X388232D02*
Y1614264D01*
X392832Y1606264D01*
Y1614264D01*
G01X396432Y1607330D02*
X397232Y1606664D01*
X398132Y1606264D01*
X398932D01*
X399732Y1606664D01*
X400332Y1607330D01*
X400632Y1608264D01*
X400432Y1609197D01*
X399932Y1609997D01*
X399032Y1610531D01*
X397832Y1610797D01*
X397132Y1611331D01*
X396832Y1612264D01*
X397032Y1613197D01*
X397532Y1613864D01*
X398232Y1614264D01*
X398932D01*
X399632Y1613997D01*
X400232Y1613331D01*
G01X406532Y1605997D02*
X406332Y1606131D01*
Y1606397D01*
X406532Y1606531D01*
X406732Y1606397D01*
Y1606131D01*
X406532Y1605997D01*
G01X-24268Y1681264D02*
Y1689264D01*
X-27968Y1683531D01*
X-22968D01*
G01X-17468Y1680997D02*
X-17668Y1681131D01*
Y1681397D01*
X-17468Y1681531D01*
X-17268Y1681397D01*
Y1681131D01*
X-17468Y1680997D01*
G01X-7268Y1688597D02*
X-7868Y1688997D01*
X-8568Y1689264D01*
X-9368D01*
X-10268Y1688864D01*
X-10968Y1688197D01*
X-11468Y1687397D01*
X-11868Y1686064D01*
X-11968Y1684864D01*
X-11768Y1683664D01*
X-11468Y1682864D01*
X-10868Y1682064D01*
X-10168Y1681531D01*
X-9468Y1681264D01*
X-8768D01*
X-8068Y1681531D01*
X-7468Y1681931D01*
X-6968Y1682464D01*
G01X-1468Y1681264D02*
X-2268Y1681397D01*
X-2968Y1681931D01*
X-3568Y1682731D01*
X-3968Y1683664D01*
X-4168Y1684731D01*
Y1685797D01*
X-3968Y1686864D01*
X-3568Y1687797D01*
X-2968Y1688597D01*
X-2268Y1689131D01*
X-1468Y1689264D01*
X-668Y1689131D01*
X32Y1688597D01*
X632Y1687797D01*
X1032Y1686864D01*
X1232Y1685797D01*
Y1684731D01*
X1032Y1683664D01*
X632Y1682731D01*
X32Y1681931D01*
X-668Y1681397D01*
X-1468Y1681264D01*
G01X4232D02*
Y1689264D01*
X8832Y1681264D01*
Y1689264D01*
G01X14532D02*
Y1681264D01*
G01X12232Y1689264D02*
X16832D01*
G01X20532Y1681264D02*
Y1689264D01*
X23032D01*
X23832Y1688864D01*
X24332Y1688331D01*
X24532Y1687264D01*
X24332Y1686197D01*
X23732Y1685531D01*
X23032Y1685131D01*
X20532D01*
G01X23032D02*
X24532Y1681264D01*
G01X30532D02*
X29732Y1681397D01*
X29032Y1681931D01*
X28432Y1682731D01*
X28032Y1683664D01*
X27832Y1684731D01*
Y1685797D01*
X28032Y1686864D01*
X28432Y1687797D01*
X29032Y1688597D01*
X29732Y1689131D01*
X30532Y1689264D01*
X31332Y1689131D01*
X32032Y1688597D01*
X32632Y1687797D01*
X33032Y1686864D01*
X33232Y1685797D01*
Y1684731D01*
X33032Y1683664D01*
X32632Y1682731D01*
X32032Y1681931D01*
X31332Y1681397D01*
X30532Y1681264D01*
G01X36532Y1689264D02*
Y1681264D01*
X40532D01*
G01X44532Y1689264D02*
Y1681264D01*
X48532D01*
G01X56532D02*
X52532D01*
Y1689264D01*
X56532D01*
G01X54932Y1685397D02*
X52532D01*
G01X60332Y1681264D02*
Y1689264D01*
X62332D01*
X63132Y1688864D01*
X63732Y1688331D01*
X64232Y1687531D01*
X64632Y1686597D01*
X64732Y1685264D01*
X64632Y1683931D01*
X64232Y1682997D01*
X63732Y1682197D01*
X63132Y1681664D01*
X62332Y1681264D01*
X60332D01*
G01X77332Y1689264D02*
X79732D01*
G01X78532D02*
Y1681264D01*
G01X77332D02*
X79732D01*
G01X83932D02*
Y1689264D01*
X86532Y1682597D01*
X89132Y1689264D01*
Y1681264D01*
G01X92532D02*
Y1689264D01*
X94932D01*
X95732Y1688864D01*
X96332Y1687931D01*
X96532Y1686864D01*
X96332Y1685797D01*
X95832Y1684997D01*
X94932Y1684597D01*
X92532D01*
G01X104532Y1681264D02*
X100532D01*
Y1689264D01*
X104532D01*
G01X102932Y1685397D02*
X100532D01*
G01X108332Y1681264D02*
Y1689264D01*
X110332D01*
X111132Y1688864D01*
X111732Y1688331D01*
X112232Y1687531D01*
X112632Y1686597D01*
X112732Y1685264D01*
X112632Y1683931D01*
X112232Y1682997D01*
X111732Y1682197D01*
X111132Y1681664D01*
X110332Y1681264D01*
X108332D01*
G01X116032D02*
X118532Y1689264D01*
X121032Y1681264D01*
G01X120132Y1684064D02*
X116932D01*
G01X124232Y1681264D02*
Y1689264D01*
X128832Y1681264D01*
Y1689264D01*
G01X136732Y1688597D02*
X136132Y1688997D01*
X135432Y1689264D01*
X134632D01*
X133732Y1688864D01*
X133032Y1688197D01*
X132532Y1687397D01*
X132132Y1686064D01*
X132032Y1684864D01*
X132232Y1683664D01*
X132532Y1682864D01*
X133132Y1682064D01*
X133832Y1681531D01*
X134532Y1681264D01*
X135232D01*
X135932Y1681531D01*
X136532Y1681931D01*
X137032Y1682464D01*
G01X144532Y1681264D02*
X140532D01*
Y1689264D01*
X144532D01*
G01X142932Y1685397D02*
X140532D01*
G01X159332Y1685531D02*
X159732Y1685931D01*
X160032Y1686597D01*
X160232Y1687531D01*
X160032Y1688331D01*
X159632Y1688864D01*
X158932Y1689264D01*
X156232D01*
Y1681264D01*
X159532D01*
X160232Y1681797D01*
X160632Y1682597D01*
X160832Y1683531D01*
X160632Y1684464D01*
X160032Y1685264D01*
X159332Y1685531D01*
X156232D01*
G01X166532Y1681264D02*
X165732Y1681397D01*
X165032Y1681931D01*
X164432Y1682731D01*
X164032Y1683664D01*
X163832Y1684731D01*
Y1685797D01*
X164032Y1686864D01*
X164432Y1687797D01*
X165032Y1688597D01*
X165732Y1689131D01*
X166532Y1689264D01*
X167332Y1689131D01*
X168032Y1688597D01*
X168632Y1687797D01*
X169032Y1686864D01*
X169232Y1685797D01*
Y1684731D01*
X169032Y1683664D01*
X168632Y1682731D01*
X168032Y1681931D01*
X167332Y1681397D01*
X166532Y1681264D01*
G01X172032D02*
X174532Y1689264D01*
X177032Y1681264D01*
G01X176132Y1684064D02*
X172932D01*
G01X180532Y1681264D02*
Y1689264D01*
X183032D01*
X183832Y1688864D01*
X184332Y1688331D01*
X184532Y1687264D01*
X184332Y1686197D01*
X183732Y1685531D01*
X183032Y1685131D01*
X180532D01*
G01X183032D02*
X184532Y1681264D01*
G01X188332D02*
Y1689264D01*
X190332D01*
X191132Y1688864D01*
X191732Y1688331D01*
X192232Y1687531D01*
X192632Y1686597D01*
X192732Y1685264D01*
X192632Y1683931D01*
X192232Y1682997D01*
X191732Y1682197D01*
X191132Y1681664D01*
X190332Y1681264D01*
X188332D01*
G01X198532Y1680997D02*
X198332Y1681131D01*
Y1681397D01*
X198532Y1681531D01*
X198732Y1681397D01*
Y1681131D01*
X198532Y1680997D01*
G01X212432Y1682330D02*
X213232Y1681664D01*
X214132Y1681264D01*
X214932D01*
X215732Y1681664D01*
X216332Y1682330D01*
X216632Y1683264D01*
X216432Y1684197D01*
X215932Y1684997D01*
X215032Y1685531D01*
X213832Y1685797D01*
X213132Y1686331D01*
X212832Y1687264D01*
X213032Y1688197D01*
X213532Y1688864D01*
X214232Y1689264D01*
X214932D01*
X215632Y1688997D01*
X216232Y1688331D01*
G01X224532Y1681264D02*
X220532D01*
Y1689264D01*
X224532D01*
G01X222932Y1685397D02*
X220532D01*
G01X232532Y1681264D02*
X228532D01*
Y1689264D01*
X232532D01*
G01X230932Y1685397D02*
X228532D01*
G01X244532Y1689264D02*
Y1681264D01*
X248532D01*
G01X252032D02*
X254532Y1689264D01*
X257032Y1681264D01*
G01X256132Y1684064D02*
X252932D01*
G01X262532Y1681264D02*
Y1684864D01*
X260532Y1689264D01*
G01X264532D02*
X262532Y1684864D01*
G01X272532Y1681264D02*
X268532D01*
Y1689264D01*
X272532D01*
G01X270932Y1685397D02*
X268532D01*
G01X276532Y1681264D02*
Y1689264D01*
X279032D01*
X279832Y1688864D01*
X280332Y1688331D01*
X280532Y1687264D01*
X280332Y1686197D01*
X279732Y1685531D01*
X279032Y1685131D01*
X276532D01*
G01X279032D02*
X280532Y1681264D01*
G01X292432Y1682330D02*
X293232Y1681664D01*
X294132Y1681264D01*
X294932D01*
X295732Y1681664D01*
X296332Y1682330D01*
X296632Y1683264D01*
X296432Y1684197D01*
X295932Y1684997D01*
X295032Y1685531D01*
X293832Y1685797D01*
X293132Y1686331D01*
X292832Y1687264D01*
X293032Y1688197D01*
X293532Y1688864D01*
X294232Y1689264D01*
X294932D01*
X295632Y1688997D01*
X296232Y1688331D01*
G01X302532Y1689264D02*
Y1681264D01*
G01X300232Y1689264D02*
X304832D01*
G01X308032Y1681264D02*
X310532Y1689264D01*
X313032Y1681264D01*
G01X312132Y1684064D02*
X308932D01*
G01X320732Y1688597D02*
X320132Y1688997D01*
X319432Y1689264D01*
X318632D01*
X317732Y1688864D01*
X317032Y1688197D01*
X316532Y1687397D01*
X316132Y1686064D01*
X316032Y1684864D01*
X316232Y1683664D01*
X316532Y1682864D01*
X317132Y1682064D01*
X317832Y1681531D01*
X318532Y1681264D01*
X319232D01*
X319932Y1681531D01*
X320532Y1681931D01*
X321032Y1682464D01*
G01X324332Y1681264D02*
Y1689264D01*
G01X328132D02*
X324332Y1684330D01*
G01X328732Y1681264D02*
X326032Y1686597D01*
G01X332332Y1689264D02*
Y1683531D01*
X332732Y1682330D01*
X333532Y1681531D01*
X334532Y1681264D01*
X335532Y1681531D01*
X336332Y1682330D01*
X336732Y1683531D01*
Y1689264D01*
G01X340532Y1681264D02*
Y1689264D01*
X342932D01*
X343732Y1688864D01*
X344332Y1687931D01*
X344532Y1686864D01*
X344332Y1685797D01*
X343832Y1684997D01*
X342932Y1684597D01*
X340532D01*
G01X356032Y1681264D02*
X358532Y1689264D01*
X361032Y1681264D01*
G01X360132Y1684064D02*
X356932D01*
G01X364232Y1681264D02*
Y1689264D01*
X368832Y1681264D01*
Y1689264D01*
G01X372332Y1681264D02*
Y1689264D01*
X374332D01*
X375132Y1688864D01*
X375732Y1688331D01*
X376232Y1687531D01*
X376632Y1686597D01*
X376732Y1685264D01*
X376632Y1683931D01*
X376232Y1682997D01*
X375732Y1682197D01*
X375132Y1681664D01*
X374332Y1681264D01*
X372332D01*
G01X389332Y1689264D02*
X391732D01*
G01X390532D02*
Y1681264D01*
G01X389332D02*
X391732D01*
G01X395932D02*
Y1689264D01*
X398532Y1682597D01*
X401132Y1689264D01*
Y1681264D01*
G01X404532D02*
Y1689264D01*
X406932D01*
X407732Y1688864D01*
X408332Y1687931D01*
X408532Y1686864D01*
X408332Y1685797D01*
X407832Y1684997D01*
X406932Y1684597D01*
X404532D01*
G01X416532Y1681264D02*
X412532D01*
Y1689264D01*
X416532D01*
G01X414932Y1685397D02*
X412532D01*
G01X420332Y1681264D02*
Y1689264D01*
X422332D01*
X423132Y1688864D01*
X423732Y1688331D01*
X424232Y1687531D01*
X424632Y1686597D01*
X424732Y1685264D01*
X424632Y1683931D01*
X424232Y1682997D01*
X423732Y1682197D01*
X423132Y1681664D01*
X422332Y1681264D01*
X420332D01*
G01X428032D02*
X430532Y1689264D01*
X433032Y1681264D01*
G01X432132Y1684064D02*
X428932D01*
G01X436232Y1681264D02*
Y1689264D01*
X440832Y1681264D01*
Y1689264D01*
G01X448732Y1688597D02*
X448132Y1688997D01*
X447432Y1689264D01*
X446632D01*
X445732Y1688864D01*
X445032Y1688197D01*
X444532Y1687397D01*
X444132Y1686064D01*
X444032Y1684864D01*
X444232Y1683664D01*
X444532Y1682864D01*
X445132Y1682064D01*
X445832Y1681531D01*
X446532Y1681264D01*
X447232D01*
X447932Y1681531D01*
X448532Y1681931D01*
X449032Y1682464D01*
G01X456532Y1681264D02*
X452532D01*
Y1689264D01*
X456532D01*
G01X454932Y1685397D02*
X452532D01*
G01X-9368Y1711264D02*
Y1719264D01*
X-5568D01*
G01X-6968Y1715397D02*
X-9368D01*
G01X532Y1710997D02*
X332Y1711131D01*
Y1711397D01*
X532Y1711531D01*
X732Y1711397D01*
Y1711131D01*
X532Y1710997D01*
G01X6232Y1711264D02*
Y1719264D01*
X10832Y1711264D01*
Y1719264D01*
G01X18532Y1711264D02*
X14532D01*
Y1719264D01*
X18532D01*
G01X16932Y1715397D02*
X14532D01*
G01X26532Y1711264D02*
X22532D01*
Y1719264D01*
X26532D01*
G01X24932Y1715397D02*
X22532D01*
G01X30332Y1711264D02*
Y1719264D01*
X32332D01*
X33132Y1718864D01*
X33732Y1718331D01*
X34232Y1717531D01*
X34632Y1716597D01*
X34732Y1715264D01*
X34632Y1713931D01*
X34232Y1712997D01*
X33732Y1712197D01*
X33132Y1711664D01*
X32332Y1711264D01*
X30332D01*
G01X46532D02*
Y1719264D01*
X48932D01*
X49732Y1718864D01*
X50332Y1717931D01*
X50532Y1716864D01*
X50332Y1715797D01*
X49832Y1714997D01*
X48932Y1714597D01*
X46532D01*
G01X58732Y1718597D02*
X58132Y1718997D01*
X57432Y1719264D01*
X56632D01*
X55732Y1718864D01*
X55032Y1718197D01*
X54532Y1717397D01*
X54132Y1716064D01*
X54032Y1714864D01*
X54232Y1713664D01*
X54532Y1712864D01*
X55132Y1712064D01*
X55832Y1711531D01*
X56532Y1711264D01*
X57232D01*
X57932Y1711531D01*
X58532Y1711931D01*
X59032Y1712464D01*
G01X65332Y1715531D02*
X65732Y1715931D01*
X66032Y1716597D01*
X66232Y1717531D01*
X66032Y1718331D01*
X65632Y1718864D01*
X64932Y1719264D01*
X62232D01*
Y1711264D01*
X65532D01*
X66232Y1711797D01*
X66632Y1712597D01*
X66832Y1713531D01*
X66632Y1714464D01*
X66032Y1715264D01*
X65332Y1715531D01*
X62232D01*
G01X77932Y1711264D02*
Y1719264D01*
X80532Y1712597D01*
X83132Y1719264D01*
Y1711264D01*
G01X86032D02*
X88532Y1719264D01*
X91032Y1711264D01*
G01X90132Y1714064D02*
X86932D01*
G01X94332Y1711264D02*
Y1719264D01*
G01X98132D02*
X94332Y1714330D01*
G01X98732Y1711264D02*
X96032Y1716597D01*
G01X106532Y1711264D02*
X102532D01*
Y1719264D01*
X106532D01*
G01X104932Y1715397D02*
X102532D01*
G01X110532Y1711264D02*
Y1719264D01*
X113032D01*
X113832Y1718864D01*
X114332Y1718331D01*
X114532Y1717264D01*
X114332Y1716197D01*
X113732Y1715531D01*
X113032Y1715131D01*
X110532D01*
G01X113032D02*
X114532Y1711264D01*
G01X126532Y1719264D02*
Y1711264D01*
X130532D01*
G01X136532D02*
X135732Y1711397D01*
X135032Y1711931D01*
X134432Y1712731D01*
X134032Y1713664D01*
X133832Y1714731D01*
Y1715797D01*
X134032Y1716864D01*
X134432Y1717797D01*
X135032Y1718597D01*
X135732Y1719131D01*
X136532Y1719264D01*
X137332Y1719131D01*
X138032Y1718597D01*
X138632Y1717797D01*
X139032Y1716864D01*
X139232Y1715797D01*
Y1714731D01*
X139032Y1713664D01*
X138632Y1712731D01*
X138032Y1711931D01*
X137332Y1711397D01*
X136532Y1711264D01*
G01X145132Y1715264D02*
X147132D01*
Y1712864D01*
X146532Y1712064D01*
X145832Y1711531D01*
X144832Y1711264D01*
X143832Y1711531D01*
X143132Y1712064D01*
X142532Y1712864D01*
X142132Y1713797D01*
X141932Y1714864D01*
Y1715797D01*
X142132Y1716597D01*
X142532Y1717531D01*
X143132Y1718331D01*
X143732Y1718864D01*
X144532Y1719264D01*
X145232D01*
X146032Y1718997D01*
X146632Y1718464D01*
G01X152532Y1711264D02*
X151732Y1711397D01*
X151032Y1711931D01*
X150432Y1712731D01*
X150032Y1713664D01*
X149832Y1714731D01*
Y1715797D01*
X150032Y1716864D01*
X150432Y1717797D01*
X151032Y1718597D01*
X151732Y1719131D01*
X152532Y1719264D01*
X153332Y1719131D01*
X154032Y1718597D01*
X154632Y1717797D01*
X155032Y1716864D01*
X155232Y1715797D01*
Y1714731D01*
X155032Y1713664D01*
X154632Y1712731D01*
X154032Y1711931D01*
X153332Y1711397D01*
X152532Y1711264D01*
G01X166032D02*
X168532Y1719264D01*
X171032Y1711264D01*
G01X170132Y1714064D02*
X166932D01*
G01X174232Y1711264D02*
Y1719264D01*
X178832Y1711264D01*
Y1719264D01*
G01X182332Y1711264D02*
Y1719264D01*
X184332D01*
X185132Y1718864D01*
X185732Y1718331D01*
X186232Y1717531D01*
X186632Y1716597D01*
X186732Y1715264D01*
X186632Y1713931D01*
X186232Y1712997D01*
X185732Y1712197D01*
X185132Y1711664D01*
X184332Y1711264D01*
X182332D01*
G01X198332D02*
Y1719264D01*
X200332D01*
X201132Y1718864D01*
X201732Y1718331D01*
X202232Y1717531D01*
X202632Y1716597D01*
X202732Y1715264D01*
X202632Y1713931D01*
X202232Y1712997D01*
X201732Y1712197D01*
X201132Y1711664D01*
X200332Y1711264D01*
X198332D01*
G01X206032D02*
X208532Y1719264D01*
X211032Y1711264D01*
G01X210132Y1714064D02*
X206932D01*
G01X216532Y1719264D02*
Y1711264D01*
G01X214232Y1719264D02*
X218832D01*
G01X226532Y1711264D02*
X222532D01*
Y1719264D01*
X226532D01*
G01X224932Y1715397D02*
X222532D01*
G01X242732Y1718597D02*
X242132Y1718997D01*
X241432Y1719264D01*
X240632D01*
X239732Y1718864D01*
X239032Y1718197D01*
X238532Y1717397D01*
X238132Y1716064D01*
X238032Y1714864D01*
X238232Y1713664D01*
X238532Y1712864D01*
X239132Y1712064D01*
X239832Y1711531D01*
X240532Y1711264D01*
X241232D01*
X241932Y1711531D01*
X242532Y1711931D01*
X243032Y1712464D01*
G01X248532Y1711264D02*
X247732Y1711397D01*
X247032Y1711931D01*
X246432Y1712731D01*
X246032Y1713664D01*
X245832Y1714731D01*
Y1715797D01*
X246032Y1716864D01*
X246432Y1717797D01*
X247032Y1718597D01*
X247732Y1719131D01*
X248532Y1719264D01*
X249332Y1719131D01*
X250032Y1718597D01*
X250632Y1717797D01*
X251032Y1716864D01*
X251232Y1715797D01*
Y1714731D01*
X251032Y1713664D01*
X250632Y1712731D01*
X250032Y1711931D01*
X249332Y1711397D01*
X248532Y1711264D01*
G01X254332D02*
Y1719264D01*
X256332D01*
X257132Y1718864D01*
X257732Y1718331D01*
X258232Y1717531D01*
X258632Y1716597D01*
X258732Y1715264D01*
X258632Y1713931D01*
X258232Y1712997D01*
X257732Y1712197D01*
X257132Y1711664D01*
X256332Y1711264D01*
X254332D01*
G01X266532D02*
X262532D01*
Y1719264D01*
X266532D01*
G01X264932Y1715397D02*
X262532D01*
G01X280032Y1708597D02*
X279032Y1709931D01*
X278532Y1711264D01*
Y1716597D01*
X279032Y1717931D01*
X280032Y1719264D01*
G01X285532D02*
X286932Y1711264D01*
X288532Y1719264D01*
X290132Y1711264D01*
X291532Y1719264D01*
G01X293532D02*
X294932Y1711264D01*
X296532Y1719264D01*
X298132Y1711264D01*
X299532Y1719264D01*
G01X304532Y1711264D02*
Y1714864D01*
X302532Y1719264D01*
G01X306532D02*
X304532Y1714864D01*
G01X312532Y1711264D02*
Y1714864D01*
X310532Y1719264D01*
G01X314532D02*
X312532Y1714864D01*
G01X321032Y1708597D02*
X322032Y1709931D01*
X322532Y1711264D01*
Y1716597D01*
X322032Y1717931D01*
X321032Y1719264D01*
G01X336532Y1711264D02*
X335932Y1711397D01*
X335332Y1711931D01*
X334932Y1712864D01*
X334732Y1713931D01*
X334932Y1714997D01*
X335332Y1715931D01*
X335932Y1716464D01*
X336532Y1716597D01*
X337132Y1716464D01*
X337732Y1715931D01*
X338132Y1714997D01*
X338232Y1713931D01*
X338132Y1712864D01*
X337732Y1711931D01*
X337132Y1711397D01*
X336532Y1711264D01*
G01X342832D02*
Y1716597D01*
G01Y1715264D02*
X343232Y1715931D01*
X343832Y1716464D01*
X344632Y1716597D01*
X345332Y1716464D01*
X345932Y1715931D01*
X346232Y1714997D01*
Y1711264D01*
G01X358432Y1712330D02*
X359232Y1711664D01*
X360132Y1711264D01*
X360932D01*
X361732Y1711664D01*
X362332Y1712330D01*
X362632Y1713264D01*
X362432Y1714197D01*
X361932Y1714997D01*
X361032Y1715531D01*
X359832Y1715797D01*
X359132Y1716331D01*
X358832Y1717264D01*
X359032Y1718197D01*
X359532Y1718864D01*
X360232Y1719264D01*
X360932D01*
X361632Y1718997D01*
X362232Y1718331D01*
G01X367332Y1719264D02*
X369732D01*
G01X368532D02*
Y1711264D01*
G01X367332D02*
X369732D01*
G01X374532Y1719264D02*
Y1711264D01*
X378532D01*
G01X382332D02*
Y1719264D01*
G01X386132D02*
X382332Y1714330D01*
G01X386732Y1711264D02*
X384032Y1716597D01*
G01X390432Y1712330D02*
X391232Y1711664D01*
X392132Y1711264D01*
X392932D01*
X393732Y1711664D01*
X394332Y1712330D01*
X394632Y1713264D01*
X394432Y1714197D01*
X393932Y1714997D01*
X393032Y1715531D01*
X391832Y1715797D01*
X391132Y1716331D01*
X390832Y1717264D01*
X391032Y1718197D01*
X391532Y1718864D01*
X392232Y1719264D01*
X392932D01*
X393632Y1718997D01*
X394232Y1718331D01*
G01X402732Y1718597D02*
X402132Y1718997D01*
X401432Y1719264D01*
X400632D01*
X399732Y1718864D01*
X399032Y1718197D01*
X398532Y1717397D01*
X398132Y1716064D01*
X398032Y1714864D01*
X398232Y1713664D01*
X398532Y1712864D01*
X399132Y1712064D01*
X399832Y1711531D01*
X400532Y1711264D01*
X401232D01*
X401932Y1711531D01*
X402532Y1711931D01*
X403032Y1712464D01*
G01X406532Y1711264D02*
Y1719264D01*
X409032D01*
X409832Y1718864D01*
X410332Y1718331D01*
X410532Y1717264D01*
X410332Y1716197D01*
X409732Y1715531D01*
X409032Y1715131D01*
X406532D01*
G01X409032D02*
X410532Y1711264D01*
G01X418532D02*
X414532D01*
Y1719264D01*
X418532D01*
G01X416932Y1715397D02*
X414532D01*
G01X426532Y1711264D02*
X422532D01*
Y1719264D01*
X426532D01*
G01X424932Y1715397D02*
X422532D01*
G01X430232Y1711264D02*
Y1719264D01*
X434832Y1711264D01*
Y1719264D01*
G01X448532D02*
Y1711264D01*
G01X446232Y1719264D02*
X450832D01*
G01X456532Y1711264D02*
X455732Y1711397D01*
X455032Y1711931D01*
X454432Y1712731D01*
X454032Y1713664D01*
X453832Y1714731D01*
Y1715797D01*
X454032Y1716864D01*
X454432Y1717797D01*
X455032Y1718597D01*
X455732Y1719131D01*
X456532Y1719264D01*
X457332Y1719131D01*
X458032Y1718597D01*
X458632Y1717797D01*
X459032Y1716864D01*
X459232Y1715797D01*
Y1714731D01*
X459032Y1713664D01*
X458632Y1712731D01*
X458032Y1711931D01*
X457332Y1711397D01*
X456532Y1711264D01*
G01X462532D02*
Y1719264D01*
X464932D01*
X465732Y1718864D01*
X466332Y1717931D01*
X466532Y1716864D01*
X466332Y1715797D01*
X465832Y1714997D01*
X464932Y1714597D01*
X462532D01*
G01X478432Y1712330D02*
X479232Y1711664D01*
X480132Y1711264D01*
X480932D01*
X481732Y1711664D01*
X482332Y1712330D01*
X482632Y1713264D01*
X482432Y1714197D01*
X481932Y1714997D01*
X481032Y1715531D01*
X479832Y1715797D01*
X479132Y1716331D01*
X478832Y1717264D01*
X479032Y1718197D01*
X479532Y1718864D01*
X480232Y1719264D01*
X480932D01*
X481632Y1718997D01*
X482232Y1718331D01*
G01X487332Y1719264D02*
X489732D01*
G01X488532D02*
Y1711264D01*
G01X487332D02*
X489732D01*
G01X494332D02*
Y1719264D01*
X496332D01*
X497132Y1718864D01*
X497732Y1718331D01*
X498232Y1717531D01*
X498632Y1716597D01*
X498732Y1715264D01*
X498632Y1713931D01*
X498232Y1712997D01*
X497732Y1712197D01*
X497132Y1711664D01*
X496332Y1711264D01*
X494332D01*
G01X506532D02*
X502532D01*
Y1719264D01*
X506532D01*
G01X504932Y1715397D02*
X502532D01*
G01X523532Y1708597D02*
X518532Y1716597D01*
Y1717931D01*
X519532Y1719264D01*
X520532D01*
X521532Y1717931D01*
Y1716597D01*
X520532Y1715264D01*
X518532Y1713931D01*
X517532Y1712597D01*
Y1709931D01*
X518532Y1708597D01*
X521532D01*
X523532Y1711264D01*
G01X537332Y1715531D02*
X537732Y1715931D01*
X538032Y1716597D01*
X538232Y1717531D01*
X538032Y1718331D01*
X537632Y1718864D01*
X536932Y1719264D01*
X534232D01*
Y1711264D01*
X537532D01*
X538232Y1711797D01*
X538632Y1712597D01*
X538832Y1713531D01*
X538632Y1714464D01*
X538032Y1715264D01*
X537332Y1715531D01*
X534232D01*
G01X542532Y1711264D02*
Y1719264D01*
X545032D01*
X545832Y1718864D01*
X546332Y1718331D01*
X546532Y1717264D01*
X546332Y1716197D01*
X545732Y1715531D01*
X545032Y1715131D01*
X542532D01*
G01X545032D02*
X546532Y1711264D01*
G01X554532D02*
X550532D01*
Y1719264D01*
X554532D01*
G01X552932Y1715397D02*
X550532D01*
G01X558032Y1711264D02*
X560532Y1719264D01*
X563032Y1711264D01*
G01X562132Y1714064D02*
X558932D01*
G01X566332Y1711264D02*
Y1719264D01*
G01X570132D02*
X566332Y1714330D01*
G01X570732Y1711264D02*
X568032Y1716597D01*
G01X574032Y1711264D02*
X576532Y1719264D01*
X579032Y1711264D01*
G01X578132Y1714064D02*
X574932D01*
G01X581532Y1719264D02*
X582932Y1711264D01*
X584532Y1719264D01*
X586132Y1711264D01*
X587532Y1719264D01*
G01X590032Y1711264D02*
X592532Y1719264D01*
X595032Y1711264D01*
G01X594132Y1714064D02*
X590932D01*
G01X600532Y1711264D02*
Y1714864D01*
X598532Y1719264D01*
G01X602532D02*
X600532Y1714864D01*
G01X-6868Y1700264D02*
X-4868D01*
Y1697864D01*
X-5468Y1697064D01*
X-6168Y1696531D01*
X-7168Y1696264D01*
X-8168Y1696531D01*
X-8868Y1697064D01*
X-9468Y1697864D01*
X-9868Y1698797D01*
X-10068Y1699864D01*
Y1700797D01*
X-9868Y1701597D01*
X-9468Y1702531D01*
X-8868Y1703331D01*
X-8268Y1703864D01*
X-7468Y1704264D01*
X-6768D01*
X-5968Y1703997D01*
X-5368Y1703464D01*
G01X532Y1695997D02*
X332Y1696131D01*
Y1696397D01*
X532Y1696531D01*
X732Y1696397D01*
Y1696131D01*
X532Y1695997D01*
G01X6232Y1696264D02*
Y1704264D01*
X10832Y1696264D01*
Y1704264D01*
G01X18532Y1696264D02*
X14532D01*
Y1704264D01*
X18532D01*
G01X16932Y1700397D02*
X14532D01*
G01X26532Y1696264D02*
X22532D01*
Y1704264D01*
X26532D01*
G01X24932Y1700397D02*
X22532D01*
G01X30332Y1696264D02*
Y1704264D01*
X32332D01*
X33132Y1703864D01*
X33732Y1703331D01*
X34232Y1702531D01*
X34632Y1701597D01*
X34732Y1700264D01*
X34632Y1698931D01*
X34232Y1697997D01*
X33732Y1697197D01*
X33132Y1696664D01*
X32332Y1696264D01*
X30332D01*
G01X46332Y1704264D02*
Y1698531D01*
X46732Y1697330D01*
X47532Y1696531D01*
X48532Y1696264D01*
X49532Y1696531D01*
X50332Y1697330D01*
X50732Y1698531D01*
Y1704264D01*
G01X54532D02*
Y1696264D01*
X58532D01*
G01X69932D02*
Y1704264D01*
X72532Y1697597D01*
X75132Y1704264D01*
Y1696264D01*
G01X78032D02*
X80532Y1704264D01*
X83032Y1696264D01*
G01X82132Y1699064D02*
X78932D01*
G01X86532Y1696264D02*
Y1704264D01*
X89032D01*
X89832Y1703864D01*
X90332Y1703331D01*
X90532Y1702264D01*
X90332Y1701197D01*
X89732Y1700531D01*
X89032Y1700131D01*
X86532D01*
G01X89032D02*
X90532Y1696264D01*
G01X94332D02*
Y1704264D01*
G01X98132D02*
X94332Y1699330D01*
G01X98732Y1696264D02*
X96032Y1701597D01*
G01X110032Y1696264D02*
X112532Y1704264D01*
X115032Y1696264D01*
G01X114132Y1699064D02*
X110932D01*
G01X118232Y1696264D02*
Y1704264D01*
X122832Y1696264D01*
Y1704264D01*
G01X126332Y1696264D02*
Y1704264D01*
X128332D01*
X129132Y1703864D01*
X129732Y1703331D01*
X130232Y1702531D01*
X130632Y1701597D01*
X130732Y1700264D01*
X130632Y1698931D01*
X130232Y1697997D01*
X129732Y1697197D01*
X129132Y1696664D01*
X128332Y1696264D01*
X126332D01*
G01X142332Y1704264D02*
Y1698531D01*
X142732Y1697330D01*
X143532Y1696531D01*
X144532Y1696264D01*
X145532Y1696531D01*
X146332Y1697330D01*
X146732Y1698531D01*
Y1704264D01*
G01X150532D02*
Y1696264D01*
X154532D01*
G01X166632D02*
Y1704264D01*
X170432D01*
G01X169032Y1700397D02*
X166632D01*
G01X175332Y1704264D02*
X177732D01*
G01X176532D02*
Y1696264D01*
G01X175332D02*
X177732D01*
G01X182532Y1704264D02*
Y1696264D01*
X186532D01*
G01X194532D02*
X190532D01*
Y1704264D01*
X194532D01*
G01X192932Y1700397D02*
X190532D01*
G01X206232Y1696264D02*
Y1704264D01*
X210832Y1696264D01*
Y1704264D01*
G01X214332D02*
Y1698531D01*
X214732Y1697330D01*
X215532Y1696531D01*
X216532Y1696264D01*
X217532Y1696531D01*
X218332Y1697330D01*
X218732Y1698531D01*
Y1704264D01*
G01X221932Y1696264D02*
Y1704264D01*
X224532Y1697597D01*
X227132Y1704264D01*
Y1696264D01*
G01X233332Y1700531D02*
X233732Y1700931D01*
X234032Y1701597D01*
X234232Y1702531D01*
X234032Y1703331D01*
X233632Y1703864D01*
X232932Y1704264D01*
X230232D01*
Y1696264D01*
X233532D01*
X234232Y1696797D01*
X234632Y1697597D01*
X234832Y1698531D01*
X234632Y1699464D01*
X234032Y1700264D01*
X233332Y1700531D01*
X230232D01*
G01X242532Y1696264D02*
X238532D01*
Y1704264D01*
X242532D01*
G01X240932Y1700397D02*
X238532D01*
G01X246532Y1696264D02*
Y1704264D01*
X249032D01*
X249832Y1703864D01*
X250332Y1703331D01*
X250532Y1702264D01*
X250332Y1701197D01*
X249732Y1700531D01*
X249032Y1700131D01*
X246532D01*
G01X249032D02*
X250532Y1696264D01*
G01X264532D02*
X263932Y1696397D01*
X263332Y1696931D01*
X262932Y1697864D01*
X262732Y1698931D01*
X262932Y1699997D01*
X263332Y1700931D01*
X263932Y1701464D01*
X264532Y1701597D01*
X265132Y1701464D01*
X265732Y1700931D01*
X266132Y1699997D01*
X266232Y1698931D01*
X266132Y1697864D01*
X265732Y1696931D01*
X265132Y1696397D01*
X264532Y1696264D01*
G01X270832D02*
Y1701597D01*
G01Y1700264D02*
X271232Y1700931D01*
X271832Y1701464D01*
X272632Y1701597D01*
X273332Y1701464D01*
X273932Y1700931D01*
X274232Y1699997D01*
Y1696264D01*
G01X286432Y1697330D02*
X287232Y1696664D01*
X288132Y1696264D01*
X288932D01*
X289732Y1696664D01*
X290332Y1697330D01*
X290632Y1698264D01*
X290432Y1699197D01*
X289932Y1699997D01*
X289032Y1700531D01*
X287832Y1700797D01*
X287132Y1701331D01*
X286832Y1702264D01*
X287032Y1703197D01*
X287532Y1703864D01*
X288232Y1704264D01*
X288932D01*
X289632Y1703997D01*
X290232Y1703331D01*
G01X295332Y1704264D02*
X297732D01*
G01X296532D02*
Y1696264D01*
G01X295332D02*
X297732D01*
G01X302532Y1704264D02*
Y1696264D01*
X306532D01*
G01X310332D02*
Y1704264D01*
G01X314132D02*
X310332Y1699330D01*
G01X314732Y1696264D02*
X312032Y1701597D01*
G01X318432Y1697330D02*
X319232Y1696664D01*
X320132Y1696264D01*
X320932D01*
X321732Y1696664D01*
X322332Y1697330D01*
X322632Y1698264D01*
X322432Y1699197D01*
X321932Y1699997D01*
X321032Y1700531D01*
X319832Y1700797D01*
X319132Y1701331D01*
X318832Y1702264D01*
X319032Y1703197D01*
X319532Y1703864D01*
X320232Y1704264D01*
X320932D01*
X321632Y1703997D01*
X322232Y1703331D01*
G01X330732Y1703597D02*
X330132Y1703997D01*
X329432Y1704264D01*
X328632D01*
X327732Y1703864D01*
X327032Y1703197D01*
X326532Y1702397D01*
X326132Y1701064D01*
X326032Y1699864D01*
X326232Y1698664D01*
X326532Y1697864D01*
X327132Y1697064D01*
X327832Y1696531D01*
X328532Y1696264D01*
X329232D01*
X329932Y1696531D01*
X330532Y1696931D01*
X331032Y1697464D01*
G01X334532Y1696264D02*
Y1704264D01*
X337032D01*
X337832Y1703864D01*
X338332Y1703331D01*
X338532Y1702264D01*
X338332Y1701197D01*
X337732Y1700531D01*
X337032Y1700131D01*
X334532D01*
G01X337032D02*
X338532Y1696264D01*
G01X346532D02*
X342532D01*
Y1704264D01*
X346532D01*
G01X344932Y1700397D02*
X342532D01*
G01X354532Y1696264D02*
X350532D01*
Y1704264D01*
X354532D01*
G01X352932Y1700397D02*
X350532D01*
G01X358232Y1696264D02*
Y1704264D01*
X362832Y1696264D01*
Y1704264D01*
G01X376532D02*
Y1696264D01*
G01X374232Y1704264D02*
X378832D01*
G01X384532Y1696264D02*
X383732Y1696397D01*
X383032Y1696931D01*
X382432Y1697731D01*
X382032Y1698664D01*
X381832Y1699731D01*
Y1700797D01*
X382032Y1701864D01*
X382432Y1702797D01*
X383032Y1703597D01*
X383732Y1704131D01*
X384532Y1704264D01*
X385332Y1704131D01*
X386032Y1703597D01*
X386632Y1702797D01*
X387032Y1701864D01*
X387232Y1700797D01*
Y1699731D01*
X387032Y1698664D01*
X386632Y1697731D01*
X386032Y1696931D01*
X385332Y1696397D01*
X384532Y1696264D01*
G01X390532D02*
Y1704264D01*
X392932D01*
X393732Y1703864D01*
X394332Y1702931D01*
X394532Y1701864D01*
X394332Y1700797D01*
X393832Y1699997D01*
X392932Y1699597D01*
X390532D01*
G01X406432Y1697330D02*
X407232Y1696664D01*
X408132Y1696264D01*
X408932D01*
X409732Y1696664D01*
X410332Y1697330D01*
X410632Y1698264D01*
X410432Y1699197D01*
X409932Y1699997D01*
X409032Y1700531D01*
X407832Y1700797D01*
X407132Y1701331D01*
X406832Y1702264D01*
X407032Y1703197D01*
X407532Y1703864D01*
X408232Y1704264D01*
X408932D01*
X409632Y1703997D01*
X410232Y1703331D01*
G01X415332Y1704264D02*
X417732D01*
G01X416532D02*
Y1696264D01*
G01X415332D02*
X417732D01*
G01X422332D02*
Y1704264D01*
X424332D01*
X425132Y1703864D01*
X425732Y1703331D01*
X426232Y1702531D01*
X426632Y1701597D01*
X426732Y1700264D01*
X426632Y1698931D01*
X426232Y1697997D01*
X425732Y1697197D01*
X425132Y1696664D01*
X424332Y1696264D01*
X422332D01*
G01X434532D02*
X430532D01*
Y1704264D01*
X434532D01*
G01X432932Y1700397D02*
X430532D01*
G01X-9668Y1741264D02*
Y1749264D01*
X-7668D01*
X-6868Y1748864D01*
X-6268Y1748331D01*
X-5768Y1747531D01*
X-5368Y1746597D01*
X-5268Y1745264D01*
X-5368Y1743931D01*
X-5768Y1742997D01*
X-6268Y1742197D01*
X-6868Y1741664D01*
X-7668Y1741264D01*
X-9668D01*
G01X532Y1740997D02*
X332Y1741131D01*
Y1741397D01*
X532Y1741531D01*
X732Y1741397D01*
Y1741131D01*
X532Y1740997D01*
G01X6532Y1741264D02*
Y1749264D01*
X8932D01*
X9732Y1748864D01*
X10332Y1747931D01*
X10532Y1746864D01*
X10332Y1745797D01*
X9832Y1744997D01*
X8932Y1744597D01*
X6532D01*
G01X14532Y1741264D02*
Y1749264D01*
X17032D01*
X17832Y1748864D01*
X18332Y1748331D01*
X18532Y1747264D01*
X18332Y1746197D01*
X17732Y1745531D01*
X17032Y1745131D01*
X14532D01*
G01X17032D02*
X18532Y1741264D01*
G01X24532D02*
X23732Y1741397D01*
X23032Y1741931D01*
X22432Y1742731D01*
X22032Y1743664D01*
X21832Y1744731D01*
Y1745797D01*
X22032Y1746864D01*
X22432Y1747797D01*
X23032Y1748597D01*
X23732Y1749131D01*
X24532Y1749264D01*
X25332Y1749131D01*
X26032Y1748597D01*
X26632Y1747797D01*
X27032Y1746864D01*
X27232Y1745797D01*
Y1744731D01*
X27032Y1743664D01*
X26632Y1742731D01*
X26032Y1741931D01*
X25332Y1741397D01*
X24532Y1741264D01*
G01X30032Y1749264D02*
X32532Y1741264D01*
X35032Y1749264D01*
G01X39332D02*
X41732D01*
G01X40532D02*
Y1741264D01*
G01X39332D02*
X41732D01*
G01X46332D02*
Y1749264D01*
X48332D01*
X49132Y1748864D01*
X49732Y1748331D01*
X50232Y1747531D01*
X50632Y1746597D01*
X50732Y1745264D01*
X50632Y1743931D01*
X50232Y1742997D01*
X49732Y1742197D01*
X49132Y1741664D01*
X48332Y1741264D01*
X46332D01*
G01X58532D02*
X54532D01*
Y1749264D01*
X58532D01*
G01X56932Y1745397D02*
X54532D01*
G01X71332Y1749264D02*
X73732D01*
G01X72532D02*
Y1741264D01*
G01X71332D02*
X73732D01*
G01X77932D02*
Y1749264D01*
X80532Y1742597D01*
X83132Y1749264D01*
Y1741264D01*
G01X86532D02*
Y1749264D01*
X88932D01*
X89732Y1748864D01*
X90332Y1747931D01*
X90532Y1746864D01*
X90332Y1745797D01*
X89832Y1744997D01*
X88932Y1744597D01*
X86532D01*
G01X98532Y1741264D02*
X94532D01*
Y1749264D01*
X98532D01*
G01X96932Y1745397D02*
X94532D01*
G01X102332Y1741264D02*
Y1749264D01*
X104332D01*
X105132Y1748864D01*
X105732Y1748331D01*
X106232Y1747531D01*
X106632Y1746597D01*
X106732Y1745264D01*
X106632Y1743931D01*
X106232Y1742997D01*
X105732Y1742197D01*
X105132Y1741664D01*
X104332Y1741264D01*
X102332D01*
G01X110032D02*
X112532Y1749264D01*
X115032Y1741264D01*
G01X114132Y1744064D02*
X110932D01*
G01X118232Y1741264D02*
Y1749264D01*
X122832Y1741264D01*
Y1749264D01*
G01X130732Y1748597D02*
X130132Y1748997D01*
X129432Y1749264D01*
X128632D01*
X127732Y1748864D01*
X127032Y1748197D01*
X126532Y1747397D01*
X126132Y1746064D01*
X126032Y1744864D01*
X126232Y1743664D01*
X126532Y1742864D01*
X127132Y1742064D01*
X127832Y1741531D01*
X128532Y1741264D01*
X129232D01*
X129932Y1741531D01*
X130532Y1741931D01*
X131032Y1742464D01*
G01X138532Y1741264D02*
X134532D01*
Y1749264D01*
X138532D01*
G01X136932Y1745397D02*
X134532D01*
G01X154732Y1748597D02*
X154132Y1748997D01*
X153432Y1749264D01*
X152632D01*
X151732Y1748864D01*
X151032Y1748197D01*
X150532Y1747397D01*
X150132Y1746064D01*
X150032Y1744864D01*
X150232Y1743664D01*
X150532Y1742864D01*
X151132Y1742064D01*
X151832Y1741531D01*
X152532Y1741264D01*
X153232D01*
X153932Y1741531D01*
X154532Y1741931D01*
X155032Y1742464D01*
G01X160532Y1741264D02*
X159732Y1741397D01*
X159032Y1741931D01*
X158432Y1742731D01*
X158032Y1743664D01*
X157832Y1744731D01*
Y1745797D01*
X158032Y1746864D01*
X158432Y1747797D01*
X159032Y1748597D01*
X159732Y1749131D01*
X160532Y1749264D01*
X161332Y1749131D01*
X162032Y1748597D01*
X162632Y1747797D01*
X163032Y1746864D01*
X163232Y1745797D01*
Y1744731D01*
X163032Y1743664D01*
X162632Y1742731D01*
X162032Y1741931D01*
X161332Y1741397D01*
X160532Y1741264D01*
G01X166332Y1749264D02*
Y1743531D01*
X166732Y1742330D01*
X167532Y1741531D01*
X168532Y1741264D01*
X169532Y1741531D01*
X170332Y1742330D01*
X170732Y1743531D01*
Y1749264D01*
G01X174532Y1741264D02*
Y1749264D01*
X176932D01*
X177732Y1748864D01*
X178332Y1747931D01*
X178532Y1746864D01*
X178332Y1745797D01*
X177832Y1744997D01*
X176932Y1744597D01*
X174532D01*
G01X184532Y1741264D02*
X183732Y1741397D01*
X183032Y1741931D01*
X182432Y1742731D01*
X182032Y1743664D01*
X181832Y1744731D01*
Y1745797D01*
X182032Y1746864D01*
X182432Y1747797D01*
X183032Y1748597D01*
X183732Y1749131D01*
X184532Y1749264D01*
X185332Y1749131D01*
X186032Y1748597D01*
X186632Y1747797D01*
X187032Y1746864D01*
X187232Y1745797D01*
Y1744731D01*
X187032Y1743664D01*
X186632Y1742731D01*
X186032Y1741931D01*
X185332Y1741397D01*
X184532Y1741264D01*
G01X190232D02*
Y1749264D01*
X194832Y1741264D01*
Y1749264D01*
G01X206032Y1741264D02*
X208532Y1749264D01*
X211032Y1741264D01*
G01X210132Y1744064D02*
X206932D01*
G01X214232Y1741264D02*
Y1749264D01*
X218832Y1741264D01*
Y1749264D01*
G01X222332Y1741264D02*
Y1749264D01*
X224332D01*
X225132Y1748864D01*
X225732Y1748331D01*
X226232Y1747531D01*
X226632Y1746597D01*
X226732Y1745264D01*
X226632Y1743931D01*
X226232Y1742997D01*
X225732Y1742197D01*
X225132Y1741664D01*
X224332Y1741264D01*
X222332D01*
G01X237932D02*
Y1749264D01*
X240532Y1742597D01*
X243132Y1749264D01*
Y1741264D01*
G01X250532D02*
X246532D01*
Y1749264D01*
X250532D01*
G01X248932Y1745397D02*
X246532D01*
G01X254032Y1741264D02*
X256532Y1749264D01*
X259032Y1741264D01*
G01X258132Y1744064D02*
X254932D01*
G01X262432Y1742330D02*
X263232Y1741664D01*
X264132Y1741264D01*
X264932D01*
X265732Y1741664D01*
X266332Y1742330D01*
X266632Y1743264D01*
X266432Y1744197D01*
X265932Y1744997D01*
X265032Y1745531D01*
X263832Y1745797D01*
X263132Y1746331D01*
X262832Y1747264D01*
X263032Y1748197D01*
X263532Y1748864D01*
X264232Y1749264D01*
X264932D01*
X265632Y1748997D01*
X266232Y1748331D01*
G01X270332Y1749264D02*
Y1743531D01*
X270732Y1742330D01*
X271532Y1741531D01*
X272532Y1741264D01*
X273532Y1741531D01*
X274332Y1742330D01*
X274732Y1743531D01*
Y1749264D01*
G01X278532Y1741264D02*
Y1749264D01*
X281032D01*
X281832Y1748864D01*
X282332Y1748331D01*
X282532Y1747264D01*
X282332Y1746197D01*
X281732Y1745531D01*
X281032Y1745131D01*
X278532D01*
G01X281032D02*
X282532Y1741264D01*
G01X290532D02*
X286532D01*
Y1749264D01*
X290532D01*
G01X288932Y1745397D02*
X286532D01*
G01X293932Y1741264D02*
Y1749264D01*
X296532Y1742597D01*
X299132Y1749264D01*
Y1741264D01*
G01X306532D02*
X302532D01*
Y1749264D01*
X306532D01*
G01X304932Y1745397D02*
X302532D01*
G01X310232Y1741264D02*
Y1749264D01*
X314832Y1741264D01*
Y1749264D01*
G01X320532D02*
Y1741264D01*
G01X318232Y1749264D02*
X322832D01*
G01X334532Y1741264D02*
Y1749264D01*
X337032D01*
X337832Y1748864D01*
X338332Y1748331D01*
X338532Y1747264D01*
X338332Y1746197D01*
X337732Y1745531D01*
X337032Y1745131D01*
X334532D01*
G01X337032D02*
X338532Y1741264D01*
G01X346532D02*
X342532D01*
Y1749264D01*
X346532D01*
G01X344932Y1745397D02*
X342532D01*
G01X350532Y1741264D02*
Y1749264D01*
X352932D01*
X353732Y1748864D01*
X354332Y1747931D01*
X354532Y1746864D01*
X354332Y1745797D01*
X353832Y1744997D01*
X352932Y1744597D01*
X350532D01*
G01X360532Y1741264D02*
X359732Y1741397D01*
X359032Y1741931D01*
X358432Y1742731D01*
X358032Y1743664D01*
X357832Y1744731D01*
Y1745797D01*
X358032Y1746864D01*
X358432Y1747797D01*
X359032Y1748597D01*
X359732Y1749131D01*
X360532Y1749264D01*
X361332Y1749131D01*
X362032Y1748597D01*
X362632Y1747797D01*
X363032Y1746864D01*
X363232Y1745797D01*
Y1744731D01*
X363032Y1743664D01*
X362632Y1742731D01*
X362032Y1741931D01*
X361332Y1741397D01*
X360532Y1741264D01*
G01X366532D02*
Y1749264D01*
X369032D01*
X369832Y1748864D01*
X370332Y1748331D01*
X370532Y1747264D01*
X370332Y1746197D01*
X369732Y1745531D01*
X369032Y1745131D01*
X366532D01*
G01X369032D02*
X370532Y1741264D01*
G01X376532Y1749264D02*
Y1741264D01*
G01X374232Y1749264D02*
X378832D01*
G01X-5468Y1726264D02*
X-9468D01*
Y1734264D01*
X-5468D01*
G01X-7068Y1730397D02*
X-9468D01*
G01X532Y1725997D02*
X332Y1726131D01*
Y1726397D01*
X532Y1726531D01*
X732Y1726397D01*
Y1726131D01*
X532Y1725997D01*
G01X6532Y1726264D02*
Y1734264D01*
X8932D01*
X9732Y1733864D01*
X10332Y1732931D01*
X10532Y1731864D01*
X10332Y1730797D01*
X9832Y1729997D01*
X8932Y1729597D01*
X6532D01*
G01X14532Y1726264D02*
Y1734264D01*
X17032D01*
X17832Y1733864D01*
X18332Y1733331D01*
X18532Y1732264D01*
X18332Y1731197D01*
X17732Y1730531D01*
X17032Y1730131D01*
X14532D01*
G01X17032D02*
X18532Y1726264D01*
G01X24532D02*
X23732Y1726397D01*
X23032Y1726931D01*
X22432Y1727731D01*
X22032Y1728664D01*
X21832Y1729731D01*
Y1730797D01*
X22032Y1731864D01*
X22432Y1732797D01*
X23032Y1733597D01*
X23732Y1734131D01*
X24532Y1734264D01*
X25332Y1734131D01*
X26032Y1733597D01*
X26632Y1732797D01*
X27032Y1731864D01*
X27232Y1730797D01*
Y1729731D01*
X27032Y1728664D01*
X26632Y1727731D01*
X26032Y1726931D01*
X25332Y1726397D01*
X24532Y1726264D01*
G01X30032Y1734264D02*
X32532Y1726264D01*
X35032Y1734264D01*
G01X39332D02*
X41732D01*
G01X40532D02*
Y1726264D01*
G01X39332D02*
X41732D01*
G01X46332D02*
Y1734264D01*
X48332D01*
X49132Y1733864D01*
X49732Y1733331D01*
X50232Y1732531D01*
X50632Y1731597D01*
X50732Y1730264D01*
X50632Y1728931D01*
X50232Y1727997D01*
X49732Y1727197D01*
X49132Y1726664D01*
X48332Y1726264D01*
X46332D01*
G01X58532D02*
X54532D01*
Y1734264D01*
X58532D01*
G01X56932Y1730397D02*
X54532D01*
G01X70532Y1726264D02*
Y1734264D01*
X72932D01*
X73732Y1733864D01*
X74332Y1732931D01*
X74532Y1731864D01*
X74332Y1730797D01*
X73832Y1729997D01*
X72932Y1729597D01*
X70532D01*
G01X82732Y1733597D02*
X82132Y1733997D01*
X81432Y1734264D01*
X80632D01*
X79732Y1733864D01*
X79032Y1733197D01*
X78532Y1732397D01*
X78132Y1731064D01*
X78032Y1729864D01*
X78232Y1728664D01*
X78532Y1727864D01*
X79132Y1727064D01*
X79832Y1726531D01*
X80532Y1726264D01*
X81232D01*
X81932Y1726531D01*
X82532Y1726931D01*
X83032Y1727464D01*
G01X89332Y1730531D02*
X89732Y1730931D01*
X90032Y1731597D01*
X90232Y1732531D01*
X90032Y1733331D01*
X89632Y1733864D01*
X88932Y1734264D01*
X86232D01*
Y1726264D01*
X89532D01*
X90232Y1726797D01*
X90632Y1727597D01*
X90832Y1728531D01*
X90632Y1729464D01*
X90032Y1730264D01*
X89332Y1730531D01*
X86232D01*
G01X102632Y1726264D02*
Y1734264D01*
X106432D01*
G01X105032Y1730397D02*
X102632D01*
G01X111332Y1734264D02*
X113732D01*
G01X112532D02*
Y1726264D01*
G01X111332D02*
X113732D01*
G01X118532Y1734264D02*
Y1726264D01*
X122532D01*
G01X125932D02*
Y1734264D01*
X128532Y1727597D01*
X131132Y1734264D01*
Y1726264D01*
G01X-6668Y1775531D02*
X-6268Y1775931D01*
X-5968Y1776597D01*
X-5768Y1777531D01*
X-5968Y1778331D01*
X-6368Y1778864D01*
X-7068Y1779264D01*
X-9768D01*
Y1771264D01*
X-6468D01*
X-5768Y1771797D01*
X-5368Y1772597D01*
X-5168Y1773531D01*
X-5368Y1774464D01*
X-5968Y1775264D01*
X-6668Y1775531D01*
X-9768D01*
G01X532Y1770997D02*
X332Y1771131D01*
Y1771397D01*
X532Y1771531D01*
X732Y1771397D01*
Y1771131D01*
X532Y1770997D01*
G01X6032Y1771264D02*
X8532Y1779264D01*
X11032Y1771264D01*
G01X10132Y1774064D02*
X6932D01*
G01X14532Y1779264D02*
Y1771264D01*
X18532D01*
G01X22532Y1779264D02*
Y1771264D01*
X26532D01*
G01X38032Y1779264D02*
X40532Y1771264D01*
X43032Y1779264D01*
G01X47332D02*
X49732D01*
G01X48532D02*
Y1771264D01*
G01X47332D02*
X49732D01*
G01X54032D02*
X56532Y1779264D01*
X59032Y1771264D01*
G01X58132Y1774064D02*
X54932D01*
G01X62432Y1772330D02*
X63232Y1771664D01*
X64132Y1771264D01*
X64932D01*
X65732Y1771664D01*
X66332Y1772330D01*
X66632Y1773264D01*
X66432Y1774197D01*
X65932Y1774997D01*
X65032Y1775531D01*
X63832Y1775797D01*
X63132Y1776331D01*
X62832Y1777264D01*
X63032Y1778197D01*
X63532Y1778864D01*
X64232Y1779264D01*
X64932D01*
X65632Y1778997D01*
X66232Y1778331D01*
G01X78532Y1771264D02*
Y1779264D01*
X80932D01*
X81732Y1778864D01*
X82332Y1777931D01*
X82532Y1776864D01*
X82332Y1775797D01*
X81832Y1774997D01*
X80932Y1774597D01*
X78532D01*
G01X86532Y1779264D02*
Y1771264D01*
X90532D01*
G01X94332Y1779264D02*
Y1773531D01*
X94732Y1772330D01*
X95532Y1771531D01*
X96532Y1771264D01*
X97532Y1771531D01*
X98332Y1772330D01*
X98732Y1773531D01*
Y1779264D01*
G01X105132Y1775264D02*
X107132D01*
Y1772864D01*
X106532Y1772064D01*
X105832Y1771531D01*
X104832Y1771264D01*
X103832Y1771531D01*
X103132Y1772064D01*
X102532Y1772864D01*
X102132Y1773797D01*
X101932Y1774864D01*
Y1775797D01*
X102132Y1776597D01*
X102532Y1777531D01*
X103132Y1778331D01*
X103732Y1778864D01*
X104532Y1779264D01*
X105232D01*
X106032Y1778997D01*
X106632Y1778464D01*
G01X113132Y1775264D02*
X115132D01*
Y1772864D01*
X114532Y1772064D01*
X113832Y1771531D01*
X112832Y1771264D01*
X111832Y1771531D01*
X111132Y1772064D01*
X110532Y1772864D01*
X110132Y1773797D01*
X109932Y1774864D01*
Y1775797D01*
X110132Y1776597D01*
X110532Y1777531D01*
X111132Y1778331D01*
X111732Y1778864D01*
X112532Y1779264D01*
X113232D01*
X114032Y1778997D01*
X114632Y1778464D01*
G01X122532Y1771264D02*
X118532D01*
Y1779264D01*
X122532D01*
G01X120932Y1775397D02*
X118532D01*
G01X126332Y1771264D02*
Y1779264D01*
X128332D01*
X129132Y1778864D01*
X129732Y1778331D01*
X130232Y1777531D01*
X130632Y1776597D01*
X130732Y1775264D01*
X130632Y1773931D01*
X130232Y1772997D01*
X129732Y1772197D01*
X129132Y1771664D01*
X128332Y1771264D01*
X126332D01*
G01X146532D02*
X142532D01*
Y1779264D01*
X146532D01*
G01X144932Y1775397D02*
X142532D01*
G01X150432Y1771264D02*
X154632Y1779264D01*
G01X150432D02*
X154632Y1771264D01*
G01X162732Y1778597D02*
X162132Y1778997D01*
X161432Y1779264D01*
X160632D01*
X159732Y1778864D01*
X159032Y1778197D01*
X158532Y1777397D01*
X158132Y1776064D01*
X158032Y1774864D01*
X158232Y1773664D01*
X158532Y1772864D01*
X159132Y1772064D01*
X159832Y1771531D01*
X160532Y1771264D01*
X161232D01*
X161932Y1771531D01*
X162532Y1771931D01*
X163032Y1772464D01*
G01X170532Y1771264D02*
X166532D01*
Y1779264D01*
X170532D01*
G01X168932Y1775397D02*
X166532D01*
G01X174532Y1771264D02*
Y1779264D01*
X176932D01*
X177732Y1778864D01*
X178332Y1777931D01*
X178532Y1776864D01*
X178332Y1775797D01*
X177832Y1774997D01*
X176932Y1774597D01*
X174532D01*
G01X184532Y1779264D02*
Y1771264D01*
G01X182232Y1779264D02*
X186832D01*
G01X198632Y1771264D02*
Y1779264D01*
X202432D01*
G01X201032Y1775397D02*
X198632D01*
G01X208532Y1771264D02*
X207732Y1771397D01*
X207032Y1771931D01*
X206432Y1772731D01*
X206032Y1773664D01*
X205832Y1774731D01*
Y1775797D01*
X206032Y1776864D01*
X206432Y1777797D01*
X207032Y1778597D01*
X207732Y1779131D01*
X208532Y1779264D01*
X209332Y1779131D01*
X210032Y1778597D01*
X210632Y1777797D01*
X211032Y1776864D01*
X211232Y1775797D01*
Y1774731D01*
X211032Y1773664D01*
X210632Y1772731D01*
X210032Y1771931D01*
X209332Y1771397D01*
X208532Y1771264D01*
G01X214532D02*
Y1779264D01*
X217032D01*
X217832Y1778864D01*
X218332Y1778331D01*
X218532Y1777264D01*
X218332Y1776197D01*
X217732Y1775531D01*
X217032Y1775131D01*
X214532D01*
G01X217032D02*
X218532Y1771264D01*
G01X-5268Y1763597D02*
X-5868Y1763997D01*
X-6568Y1764264D01*
X-7368D01*
X-8268Y1763864D01*
X-8968Y1763197D01*
X-9468Y1762397D01*
X-9868Y1761064D01*
X-9968Y1759864D01*
X-9768Y1758664D01*
X-9468Y1757864D01*
X-8868Y1757064D01*
X-8168Y1756531D01*
X-7468Y1756264D01*
X-6768D01*
X-6068Y1756531D01*
X-5468Y1756931D01*
X-4968Y1757464D01*
G01X532Y1755997D02*
X332Y1756131D01*
Y1756397D01*
X532Y1756531D01*
X732Y1756397D01*
Y1756131D01*
X532Y1755997D01*
G01X6232Y1756264D02*
Y1764264D01*
X10832Y1756264D01*
Y1764264D01*
G01X16532Y1756264D02*
X15732Y1756397D01*
X15032Y1756931D01*
X14432Y1757731D01*
X14032Y1758664D01*
X13832Y1759731D01*
Y1760797D01*
X14032Y1761864D01*
X14432Y1762797D01*
X15032Y1763597D01*
X15732Y1764131D01*
X16532Y1764264D01*
X17332Y1764131D01*
X18032Y1763597D01*
X18632Y1762797D01*
X19032Y1761864D01*
X19232Y1760797D01*
Y1759731D01*
X19032Y1758664D01*
X18632Y1757731D01*
X18032Y1756931D01*
X17332Y1756397D01*
X16532Y1756264D01*
G01X30232D02*
Y1764264D01*
X34832Y1756264D01*
Y1764264D01*
G01X42532Y1756264D02*
X38532D01*
Y1764264D01*
X42532D01*
G01X40932Y1760397D02*
X38532D01*
G01X50532Y1756264D02*
X46532D01*
Y1764264D01*
X50532D01*
G01X48932Y1760397D02*
X46532D01*
G01X54332Y1756264D02*
Y1764264D01*
X56332D01*
X57132Y1763864D01*
X57732Y1763331D01*
X58232Y1762531D01*
X58632Y1761597D01*
X58732Y1760264D01*
X58632Y1758931D01*
X58232Y1757997D01*
X57732Y1757197D01*
X57132Y1756664D01*
X56332Y1756264D01*
X54332D01*
G01X72532Y1764264D02*
Y1756264D01*
G01X70232Y1764264D02*
X74832D01*
G01X80532Y1756264D02*
X79732Y1756397D01*
X79032Y1756931D01*
X78432Y1757731D01*
X78032Y1758664D01*
X77832Y1759731D01*
Y1760797D01*
X78032Y1761864D01*
X78432Y1762797D01*
X79032Y1763597D01*
X79732Y1764131D01*
X80532Y1764264D01*
X81332Y1764131D01*
X82032Y1763597D01*
X82632Y1762797D01*
X83032Y1761864D01*
X83232Y1760797D01*
Y1759731D01*
X83032Y1758664D01*
X82632Y1757731D01*
X82032Y1756931D01*
X81332Y1756397D01*
X80532Y1756264D01*
G01X94532D02*
Y1764264D01*
X96932D01*
X97732Y1763864D01*
X98332Y1762931D01*
X98532Y1761864D01*
X98332Y1760797D01*
X97832Y1759997D01*
X96932Y1759597D01*
X94532D01*
G01X102532Y1764264D02*
Y1756264D01*
X106532D01*
G01X110332Y1764264D02*
Y1758531D01*
X110732Y1757330D01*
X111532Y1756531D01*
X112532Y1756264D01*
X113532Y1756531D01*
X114332Y1757330D01*
X114732Y1758531D01*
Y1764264D01*
G01X121132Y1760264D02*
X123132D01*
Y1757864D01*
X122532Y1757064D01*
X121832Y1756531D01*
X120832Y1756264D01*
X119832Y1756531D01*
X119132Y1757064D01*
X118532Y1757864D01*
X118132Y1758797D01*
X117932Y1759864D01*
Y1760797D01*
X118132Y1761597D01*
X118532Y1762531D01*
X119132Y1763331D01*
X119732Y1763864D01*
X120532Y1764264D01*
X121232D01*
X122032Y1763997D01*
X122632Y1763464D01*
G01X136532Y1756264D02*
X137232Y1756397D01*
X138032Y1756797D01*
X138532Y1757464D01*
X138732Y1758397D01*
X138532Y1759330D01*
X137932Y1760131D01*
X137032Y1760531D01*
X136032D01*
X135432Y1760797D01*
X134932Y1761464D01*
X134732Y1762397D01*
X135032Y1763331D01*
X135732Y1763997D01*
X136532Y1764264D01*
X137332Y1763997D01*
X138032Y1763331D01*
X138332Y1762397D01*
X138132Y1761464D01*
X137632Y1760797D01*
X137032Y1760531D01*
X136032D01*
X135132Y1760131D01*
X134532Y1759330D01*
X134332Y1758397D01*
X134532Y1757464D01*
X135032Y1756797D01*
X135832Y1756397D01*
X136532Y1756264D01*
G01X150432D02*
Y1764264D01*
G01X154632D02*
Y1756264D01*
G01Y1760264D02*
X150432D01*
G01X160532Y1756264D02*
X159732Y1756397D01*
X159032Y1756931D01*
X158432Y1757731D01*
X158032Y1758664D01*
X157832Y1759731D01*
Y1760797D01*
X158032Y1761864D01*
X158432Y1762797D01*
X159032Y1763597D01*
X159732Y1764131D01*
X160532Y1764264D01*
X161332Y1764131D01*
X162032Y1763597D01*
X162632Y1762797D01*
X163032Y1761864D01*
X163232Y1760797D01*
Y1759731D01*
X163032Y1758664D01*
X162632Y1757731D01*
X162032Y1756931D01*
X161332Y1756397D01*
X160532Y1756264D01*
G01X166532Y1764264D02*
Y1756264D01*
X170532D01*
G01X178532D02*
X174532D01*
Y1764264D01*
X178532D01*
G01X176932Y1760397D02*
X174532D01*
G01X182432Y1757330D02*
X183232Y1756664D01*
X184132Y1756264D01*
X184932D01*
X185732Y1756664D01*
X186332Y1757330D01*
X186632Y1758264D01*
X186432Y1759197D01*
X185932Y1759997D01*
X185032Y1760531D01*
X183832Y1760797D01*
X183132Y1761331D01*
X182832Y1762264D01*
X183032Y1763197D01*
X183532Y1763864D01*
X184232Y1764264D01*
X184932D01*
X185632Y1763997D01*
X186232Y1763331D01*
G01X198432Y1757330D02*
X199232Y1756664D01*
X200132Y1756264D01*
X200932D01*
X201732Y1756664D01*
X202332Y1757330D01*
X202632Y1758264D01*
X202432Y1759197D01*
X201932Y1759997D01*
X201032Y1760531D01*
X199832Y1760797D01*
X199132Y1761331D01*
X198832Y1762264D01*
X199032Y1763197D01*
X199532Y1763864D01*
X200232Y1764264D01*
X200932D01*
X201632Y1763997D01*
X202232Y1763331D01*
G01X206332Y1764264D02*
Y1758531D01*
X206732Y1757330D01*
X207532Y1756531D01*
X208532Y1756264D01*
X209532Y1756531D01*
X210332Y1757330D01*
X210732Y1758531D01*
Y1764264D01*
G01X214532Y1756264D02*
Y1764264D01*
X217032D01*
X217832Y1763864D01*
X218332Y1763331D01*
X218532Y1762264D01*
X218332Y1761197D01*
X217732Y1760531D01*
X217032Y1760131D01*
X214532D01*
G01X217032D02*
X218532Y1756264D01*
G01X222532D02*
Y1764264D01*
X225032D01*
X225832Y1763864D01*
X226332Y1763331D01*
X226532Y1762264D01*
X226332Y1761197D01*
X225732Y1760531D01*
X225032Y1760131D01*
X222532D01*
G01X225032D02*
X226532Y1756264D01*
G01X232532D02*
X231732Y1756397D01*
X231032Y1756931D01*
X230432Y1757731D01*
X230032Y1758664D01*
X229832Y1759731D01*
Y1760797D01*
X230032Y1761864D01*
X230432Y1762797D01*
X231032Y1763597D01*
X231732Y1764131D01*
X232532Y1764264D01*
X233332Y1764131D01*
X234032Y1763597D01*
X234632Y1762797D01*
X235032Y1761864D01*
X235232Y1760797D01*
Y1759731D01*
X235032Y1758664D01*
X234632Y1757731D01*
X234032Y1756931D01*
X233332Y1756397D01*
X232532Y1756264D01*
G01X238332Y1764264D02*
Y1758531D01*
X238732Y1757330D01*
X239532Y1756531D01*
X240532Y1756264D01*
X241532Y1756531D01*
X242332Y1757330D01*
X242732Y1758531D01*
Y1764264D01*
G01X246232Y1756264D02*
Y1764264D01*
X250832Y1756264D01*
Y1764264D01*
G01X254332Y1756264D02*
Y1764264D01*
X256332D01*
X257132Y1763864D01*
X257732Y1763331D01*
X258232Y1762531D01*
X258632Y1761597D01*
X258732Y1760264D01*
X258632Y1758931D01*
X258232Y1757997D01*
X257732Y1757197D01*
X257132Y1756664D01*
X256332Y1756264D01*
X254332D01*
G01X263332Y1764264D02*
X265732D01*
G01X264532D02*
Y1756264D01*
G01X263332D02*
X265732D01*
G01X270232D02*
Y1764264D01*
X274832Y1756264D01*
Y1764264D01*
G01X281132Y1760264D02*
X283132D01*
Y1757864D01*
X282532Y1757064D01*
X281832Y1756531D01*
X280832Y1756264D01*
X279832Y1756531D01*
X279132Y1757064D01*
X278532Y1757864D01*
X278132Y1758797D01*
X277932Y1759864D01*
Y1760797D01*
X278132Y1761597D01*
X278532Y1762531D01*
X279132Y1763331D01*
X279732Y1763864D01*
X280532Y1764264D01*
X281232D01*
X282032Y1763997D01*
X282632Y1763464D01*
G01X294432Y1757330D02*
X295232Y1756664D01*
X296132Y1756264D01*
X296932D01*
X297732Y1756664D01*
X298332Y1757330D01*
X298632Y1758264D01*
X298432Y1759197D01*
X297932Y1759997D01*
X297032Y1760531D01*
X295832Y1760797D01*
X295132Y1761331D01*
X294832Y1762264D01*
X295032Y1763197D01*
X295532Y1763864D01*
X296232Y1764264D01*
X296932D01*
X297632Y1763997D01*
X298232Y1763331D01*
G01X306732Y1763597D02*
X306132Y1763997D01*
X305432Y1764264D01*
X304632D01*
X303732Y1763864D01*
X303032Y1763197D01*
X302532Y1762397D01*
X302132Y1761064D01*
X302032Y1759864D01*
X302232Y1758664D01*
X302532Y1757864D01*
X303132Y1757064D01*
X303832Y1756531D01*
X304532Y1756264D01*
X305232D01*
X305932Y1756531D01*
X306532Y1756931D01*
X307032Y1757464D01*
G01X310532Y1756264D02*
Y1764264D01*
X313032D01*
X313832Y1763864D01*
X314332Y1763331D01*
X314532Y1762264D01*
X314332Y1761197D01*
X313732Y1760531D01*
X313032Y1760131D01*
X310532D01*
G01X313032D02*
X314532Y1756264D01*
G01X322532D02*
X318532D01*
Y1764264D01*
X322532D01*
G01X320932Y1760397D02*
X318532D01*
G01X325532Y1764264D02*
X326932Y1756264D01*
X328532Y1764264D01*
X330132Y1756264D01*
X331532Y1764264D01*
G01X336532Y1755997D02*
X336332Y1756131D01*
Y1756397D01*
X336532Y1756531D01*
X336732Y1756397D01*
Y1756131D01*
X336532Y1755997D01*
G01X344032Y1753597D02*
X343032Y1754931D01*
X342532Y1756264D01*
Y1761597D01*
X343032Y1762931D01*
X344032Y1764264D01*
G01X350532Y1756264D02*
Y1764264D01*
X352932D01*
X353732Y1763864D01*
X354332Y1762931D01*
X354532Y1761864D01*
X354332Y1760797D01*
X353832Y1759997D01*
X352932Y1759597D01*
X350532D01*
G01X358532Y1764264D02*
Y1756264D01*
X362532D01*
G01X370532D02*
X366532D01*
Y1764264D01*
X370532D01*
G01X368932Y1760397D02*
X366532D01*
G01X374032Y1756264D02*
X376532Y1764264D01*
X379032Y1756264D01*
G01X378132Y1759064D02*
X374932D01*
G01X382432Y1757330D02*
X383232Y1756664D01*
X384132Y1756264D01*
X384932D01*
X385732Y1756664D01*
X386332Y1757330D01*
X386632Y1758264D01*
X386432Y1759197D01*
X385932Y1759997D01*
X385032Y1760531D01*
X383832Y1760797D01*
X383132Y1761331D01*
X382832Y1762264D01*
X383032Y1763197D01*
X383532Y1763864D01*
X384232Y1764264D01*
X384932D01*
X385632Y1763997D01*
X386232Y1763331D01*
G01X394532Y1756264D02*
X390532D01*
Y1764264D01*
X394532D01*
G01X392932Y1760397D02*
X390532D01*
G01X407332Y1764264D02*
X409732D01*
G01X408532D02*
Y1756264D01*
G01X407332D02*
X409732D01*
G01X417132Y1760264D02*
X419132D01*
Y1757864D01*
X418532Y1757064D01*
X417832Y1756531D01*
X416832Y1756264D01*
X415832Y1756531D01*
X415132Y1757064D01*
X414532Y1757864D01*
X414132Y1758797D01*
X413932Y1759864D01*
Y1760797D01*
X414132Y1761597D01*
X414532Y1762531D01*
X415132Y1763331D01*
X415732Y1763864D01*
X416532Y1764264D01*
X417232D01*
X418032Y1763997D01*
X418632Y1763464D01*
G01X422232Y1756264D02*
Y1764264D01*
X426832Y1756264D01*
Y1764264D01*
G01X432532Y1756264D02*
X431732Y1756397D01*
X431032Y1756931D01*
X430432Y1757731D01*
X430032Y1758664D01*
X429832Y1759731D01*
Y1760797D01*
X430032Y1761864D01*
X430432Y1762797D01*
X431032Y1763597D01*
X431732Y1764131D01*
X432532Y1764264D01*
X433332Y1764131D01*
X434032Y1763597D01*
X434632Y1762797D01*
X435032Y1761864D01*
X435232Y1760797D01*
Y1759731D01*
X435032Y1758664D01*
X434632Y1757731D01*
X434032Y1756931D01*
X433332Y1756397D01*
X432532Y1756264D01*
G01X438532D02*
Y1764264D01*
X441032D01*
X441832Y1763864D01*
X442332Y1763331D01*
X442532Y1762264D01*
X442332Y1761197D01*
X441732Y1760531D01*
X441032Y1760131D01*
X438532D01*
G01X441032D02*
X442532Y1756264D01*
G01X450532D02*
X446532D01*
Y1764264D01*
X450532D01*
G01X448932Y1760397D02*
X446532D01*
G01X464532Y1764264D02*
Y1756264D01*
G01X462232Y1764264D02*
X466832D01*
G01X470432Y1756264D02*
Y1764264D01*
G01X474632D02*
Y1756264D01*
G01Y1760264D02*
X470432D01*
G01X479332Y1764264D02*
X481732D01*
G01X480532D02*
Y1756264D01*
G01X479332D02*
X481732D01*
G01X486432Y1757330D02*
X487232Y1756664D01*
X488132Y1756264D01*
X488932D01*
X489732Y1756664D01*
X490332Y1757330D01*
X490632Y1758264D01*
X490432Y1759197D01*
X489932Y1759997D01*
X489032Y1760531D01*
X487832Y1760797D01*
X487132Y1761331D01*
X486832Y1762264D01*
X487032Y1763197D01*
X487532Y1763864D01*
X488232Y1764264D01*
X488932D01*
X489632Y1763997D01*
X490232Y1763331D01*
G01X503332Y1764264D02*
X505732D01*
G01X504532D02*
Y1756264D01*
G01X503332D02*
X505732D01*
G01X510632D02*
Y1764264D01*
X514432D01*
G01X513032Y1760397D02*
X510632D01*
G01X526232Y1756264D02*
Y1764264D01*
X530832Y1756264D01*
Y1764264D01*
G01X536532Y1756264D02*
X535732Y1756397D01*
X535032Y1756931D01*
X534432Y1757731D01*
X534032Y1758664D01*
X533832Y1759731D01*
Y1760797D01*
X534032Y1761864D01*
X534432Y1762797D01*
X535032Y1763597D01*
X535732Y1764131D01*
X536532Y1764264D01*
X537332Y1764131D01*
X538032Y1763597D01*
X538632Y1762797D01*
X539032Y1761864D01*
X539232Y1760797D01*
Y1759731D01*
X539032Y1758664D01*
X538632Y1757731D01*
X538032Y1756931D01*
X537332Y1756397D01*
X536532Y1756264D01*
G01X552532Y1764264D02*
Y1756264D01*
G01X550232Y1764264D02*
X554832D01*
G01X558432Y1756264D02*
Y1764264D01*
G01X562632D02*
Y1756264D01*
G01Y1760264D02*
X558432D01*
G01X567332Y1764264D02*
X569732D01*
G01X568532D02*
Y1756264D01*
G01X567332D02*
X569732D01*
G01X574432Y1757330D02*
X575232Y1756664D01*
X576132Y1756264D01*
X576932D01*
X577732Y1756664D01*
X578332Y1757330D01*
X578632Y1758264D01*
X578432Y1759197D01*
X577932Y1759997D01*
X577032Y1760531D01*
X575832Y1760797D01*
X575132Y1761331D01*
X574832Y1762264D01*
X575032Y1763197D01*
X575532Y1763864D01*
X576232Y1764264D01*
X576932D01*
X577632Y1763997D01*
X578232Y1763331D01*
G01X591332Y1764264D02*
X593732D01*
G01X592532D02*
Y1756264D01*
G01X591332D02*
X593732D01*
G01X600532Y1764264D02*
Y1756264D01*
G01X598232Y1764264D02*
X602832D01*
G01X610532Y1756264D02*
X606532D01*
Y1764264D01*
X610532D01*
G01X608932Y1760397D02*
X606532D01*
G01X613932Y1756264D02*
Y1764264D01*
X616532Y1757597D01*
X619132Y1764264D01*
Y1756264D01*
G01X631332Y1764264D02*
X633732D01*
G01X632532D02*
Y1756264D01*
G01X631332D02*
X633732D01*
G01X638232D02*
Y1764264D01*
X642832Y1756264D01*
Y1764264D01*
G01X657332Y1760531D02*
X657732Y1760931D01*
X658032Y1761597D01*
X658232Y1762531D01*
X658032Y1763331D01*
X657632Y1763864D01*
X656932Y1764264D01*
X654232D01*
Y1756264D01*
X657532D01*
X658232Y1756797D01*
X658632Y1757597D01*
X658832Y1758531D01*
X658632Y1759464D01*
X658032Y1760264D01*
X657332Y1760531D01*
X654232D01*
G01X664532Y1756264D02*
X663732Y1756397D01*
X663032Y1756931D01*
X662432Y1757731D01*
X662032Y1758664D01*
X661832Y1759731D01*
Y1760797D01*
X662032Y1761864D01*
X662432Y1762797D01*
X663032Y1763597D01*
X663732Y1764131D01*
X664532Y1764264D01*
X665332Y1764131D01*
X666032Y1763597D01*
X666632Y1762797D01*
X667032Y1761864D01*
X667232Y1760797D01*
Y1759731D01*
X667032Y1758664D01*
X666632Y1757731D01*
X666032Y1756931D01*
X665332Y1756397D01*
X664532Y1756264D01*
G01X670032D02*
X672532Y1764264D01*
X675032Y1756264D01*
G01X674132Y1759064D02*
X670932D01*
G01X678532Y1756264D02*
Y1764264D01*
X681032D01*
X681832Y1763864D01*
X682332Y1763331D01*
X682532Y1762264D01*
X682332Y1761197D01*
X681732Y1760531D01*
X681032Y1760131D01*
X678532D01*
G01X681032D02*
X682532Y1756264D01*
G01X686332D02*
Y1764264D01*
X688332D01*
X689132Y1763864D01*
X689732Y1763331D01*
X690232Y1762531D01*
X690632Y1761597D01*
X690732Y1760264D01*
X690632Y1758931D01*
X690232Y1757997D01*
X689732Y1757197D01*
X689132Y1756664D01*
X688332Y1756264D01*
X686332D01*
G01X702632D02*
Y1764264D01*
X706432D01*
G01X705032Y1760397D02*
X702632D01*
G01X711332Y1764264D02*
X713732D01*
G01X712532D02*
Y1756264D01*
G01X711332D02*
X713732D01*
G01X718532Y1764264D02*
Y1756264D01*
X722532D01*
G01X730532D02*
X726532D01*
Y1764264D01*
X730532D01*
G01X728932Y1760397D02*
X726532D01*
G01X737032Y1753597D02*
X738032Y1754931D01*
X738532Y1756264D01*
Y1761597D01*
X738032Y1762931D01*
X737032Y1764264D01*
G01X-9968Y1786264D02*
X-7468Y1794264D01*
X-4968Y1786264D01*
G01X-5868Y1789064D02*
X-9068D01*
G01X532Y1785997D02*
X332Y1786131D01*
Y1786397D01*
X532Y1786531D01*
X732Y1786397D01*
Y1786131D01*
X532Y1785997D01*
G01X6032Y1794264D02*
X8532Y1786264D01*
X11032Y1794264D01*
G01X15332D02*
X17732D01*
G01X16532D02*
Y1786264D01*
G01X15332D02*
X17732D01*
G01X22032D02*
X24532Y1794264D01*
X27032Y1786264D01*
G01X26132Y1789064D02*
X22932D01*
G01X40532Y1794264D02*
Y1786264D01*
G01X38232Y1794264D02*
X42832D01*
G01X50532Y1786264D02*
X46532D01*
Y1794264D01*
X50532D01*
G01X48932Y1790397D02*
X46532D01*
G01X54032Y1786264D02*
X56532Y1794264D01*
X59032Y1786264D01*
G01X58132Y1789064D02*
X54932D01*
G01X62532Y1786264D02*
Y1794264D01*
X65032D01*
X65832Y1793864D01*
X66332Y1793331D01*
X66532Y1792264D01*
X66332Y1791197D01*
X65732Y1790531D01*
X65032Y1790131D01*
X62532D01*
G01X65032D02*
X66532Y1786264D01*
G01X78332D02*
Y1794264D01*
X80332D01*
X81132Y1793864D01*
X81732Y1793331D01*
X82232Y1792531D01*
X82632Y1791597D01*
X82732Y1790264D01*
X82632Y1788931D01*
X82232Y1787997D01*
X81732Y1787197D01*
X81132Y1786664D01*
X80332Y1786264D01*
X78332D01*
G01X86532D02*
Y1794264D01*
X89032D01*
X89832Y1793864D01*
X90332Y1793331D01*
X90532Y1792264D01*
X90332Y1791197D01*
X89732Y1790531D01*
X89032Y1790131D01*
X86532D01*
G01X89032D02*
X90532Y1786264D01*
G01X96532D02*
X95732Y1786397D01*
X95032Y1786931D01*
X94432Y1787731D01*
X94032Y1788664D01*
X93832Y1789731D01*
Y1790797D01*
X94032Y1791864D01*
X94432Y1792797D01*
X95032Y1793597D01*
X95732Y1794131D01*
X96532Y1794264D01*
X97332Y1794131D01*
X98032Y1793597D01*
X98632Y1792797D01*
X99032Y1791864D01*
X99232Y1790797D01*
Y1789731D01*
X99032Y1788664D01*
X98632Y1787731D01*
X98032Y1786931D01*
X97332Y1786397D01*
X96532Y1786264D01*
G01X102532D02*
Y1794264D01*
X104932D01*
X105732Y1793864D01*
X106332Y1792931D01*
X106532Y1791864D01*
X106332Y1790797D01*
X105832Y1789997D01*
X104932Y1789597D01*
X102532D01*
G01X120032Y1783597D02*
X119032Y1784931D01*
X118532Y1786264D01*
Y1791597D01*
X119032Y1792931D01*
X120032Y1794264D01*
G01X126632Y1786264D02*
Y1794264D01*
X130432D01*
G01X129032Y1790397D02*
X126632D01*
G01X136532Y1786264D02*
X135732Y1786397D01*
X135032Y1786931D01*
X134432Y1787731D01*
X134032Y1788664D01*
X133832Y1789731D01*
Y1790797D01*
X134032Y1791864D01*
X134432Y1792797D01*
X135032Y1793597D01*
X135732Y1794131D01*
X136532Y1794264D01*
X137332Y1794131D01*
X138032Y1793597D01*
X138632Y1792797D01*
X139032Y1791864D01*
X139232Y1790797D01*
Y1789731D01*
X139032Y1788664D01*
X138632Y1787731D01*
X138032Y1786931D01*
X137332Y1786397D01*
X136532Y1786264D01*
G01X142532D02*
Y1794264D01*
X145032D01*
X145832Y1793864D01*
X146332Y1793331D01*
X146532Y1792264D01*
X146332Y1791197D01*
X145732Y1790531D01*
X145032Y1790131D01*
X142532D01*
G01X145032D02*
X146532Y1786264D01*
G01X158032D02*
X160532Y1794264D01*
X163032Y1786264D01*
G01X162132Y1789064D02*
X158932D01*
G01X166532Y1794264D02*
Y1786264D01*
X170532D01*
G01X174532Y1794264D02*
Y1786264D01*
X178532D01*
G01X190032Y1794264D02*
X192532Y1786264D01*
X195032Y1794264D01*
G01X199332D02*
X201732D01*
G01X200532D02*
Y1786264D01*
G01X199332D02*
X201732D01*
G01X206032D02*
X208532Y1794264D01*
X211032Y1786264D01*
G01X210132Y1789064D02*
X206932D01*
G01X214432Y1787330D02*
X215232Y1786664D01*
X216132Y1786264D01*
X216932D01*
X217732Y1786664D01*
X218332Y1787330D01*
X218632Y1788264D01*
X218432Y1789197D01*
X217932Y1789997D01*
X217032Y1790531D01*
X215832Y1790797D01*
X215132Y1791331D01*
X214832Y1792264D01*
X215032Y1793197D01*
X215532Y1793864D01*
X216232Y1794264D01*
X216932D01*
X217632Y1793997D01*
X218232Y1793331D01*
G01X230032Y1786264D02*
X232532Y1794264D01*
X235032Y1786264D01*
G01X234132Y1789064D02*
X230932D01*
G01X238232Y1786264D02*
Y1794264D01*
X242832Y1786264D01*
Y1794264D01*
G01X246332Y1786264D02*
Y1794264D01*
X248332D01*
X249132Y1793864D01*
X249732Y1793331D01*
X250232Y1792531D01*
X250632Y1791597D01*
X250732Y1790264D01*
X250632Y1788931D01*
X250232Y1787997D01*
X249732Y1787197D01*
X249132Y1786664D01*
X248332Y1786264D01*
X246332D01*
G01X262532D02*
Y1794264D01*
X264932D01*
X265732Y1793864D01*
X266332Y1792931D01*
X266532Y1791864D01*
X266332Y1790797D01*
X265832Y1789997D01*
X264932Y1789597D01*
X262532D01*
G01X271332Y1794264D02*
X273732D01*
G01X272532D02*
Y1786264D01*
G01X271332D02*
X273732D01*
G01X278232D02*
Y1794264D01*
X282832Y1786264D01*
Y1794264D01*
G01X286432Y1787330D02*
X287232Y1786664D01*
X288132Y1786264D01*
X288932D01*
X289732Y1786664D01*
X290332Y1787330D01*
X290632Y1788264D01*
X290432Y1789197D01*
X289932Y1789997D01*
X289032Y1790531D01*
X287832Y1790797D01*
X287132Y1791331D01*
X286832Y1792264D01*
X287032Y1793197D01*
X287532Y1793864D01*
X288232Y1794264D01*
X288932D01*
X289632Y1793997D01*
X290232Y1793331D01*
G01X297032Y1783597D02*
X298032Y1784931D01*
X298532Y1786264D01*
Y1791597D01*
X298032Y1792931D01*
X297032Y1794264D01*
G01X304532Y1785997D02*
X304332Y1786131D01*
Y1786397D01*
X304532Y1786531D01*
X304732Y1786397D01*
Y1786131D01*
X304532Y1785997D01*
G01X-27668Y1802864D02*
X-27068Y1801931D01*
X-26268Y1801397D01*
X-25368Y1801264D01*
X-24568Y1801397D01*
X-23768Y1802064D01*
X-23268Y1802864D01*
X-23168Y1803664D01*
X-23368Y1804597D01*
X-24068Y1805264D01*
X-24768Y1805531D01*
X-25668D01*
G01X-24768D02*
X-24168Y1805931D01*
X-23668Y1806597D01*
X-23468Y1807397D01*
X-23668Y1808197D01*
X-24168Y1808864D01*
X-25068Y1809264D01*
X-25968Y1809131D01*
X-26868Y1808597D01*
G01X-17468Y1800997D02*
X-17668Y1801131D01*
Y1801397D01*
X-17468Y1801531D01*
X-17268Y1801397D01*
Y1801131D01*
X-17468Y1800997D01*
G01X-11468Y1801264D02*
Y1809264D01*
X-9068D01*
X-8268Y1808864D01*
X-7668Y1807931D01*
X-7468Y1806864D01*
X-7668Y1805797D01*
X-8168Y1804997D01*
X-9068Y1804597D01*
X-11468D01*
G01X732Y1808597D02*
X132Y1808997D01*
X-568Y1809264D01*
X-1368D01*
X-2268Y1808864D01*
X-2968Y1808197D01*
X-3468Y1807397D01*
X-3868Y1806064D01*
X-3968Y1804864D01*
X-3768Y1803664D01*
X-3468Y1802864D01*
X-2868Y1802064D01*
X-2168Y1801531D01*
X-1468Y1801264D01*
X-768D01*
X-68Y1801531D01*
X532Y1801931D01*
X1032Y1802464D01*
G01X7332Y1805531D02*
X7732Y1805931D01*
X8032Y1806597D01*
X8232Y1807531D01*
X8032Y1808331D01*
X7632Y1808864D01*
X6932Y1809264D01*
X4232D01*
Y1801264D01*
X7532D01*
X8232Y1801797D01*
X8632Y1802597D01*
X8832Y1803531D01*
X8632Y1804464D01*
X8032Y1805264D01*
X7332Y1805531D01*
X4232D01*
G01X20532Y1801264D02*
Y1809264D01*
X22932D01*
X23732Y1808864D01*
X24332Y1807931D01*
X24532Y1806864D01*
X24332Y1805797D01*
X23832Y1804997D01*
X22932Y1804597D01*
X20532D01*
G01X28532Y1801264D02*
Y1809264D01*
X31032D01*
X31832Y1808864D01*
X32332Y1808331D01*
X32532Y1807264D01*
X32332Y1806197D01*
X31732Y1805531D01*
X31032Y1805131D01*
X28532D01*
G01X31032D02*
X32532Y1801264D01*
G01X38532D02*
X37732Y1801397D01*
X37032Y1801931D01*
X36432Y1802731D01*
X36032Y1803664D01*
X35832Y1804731D01*
Y1805797D01*
X36032Y1806864D01*
X36432Y1807797D01*
X37032Y1808597D01*
X37732Y1809131D01*
X38532Y1809264D01*
X39332Y1809131D01*
X40032Y1808597D01*
X40632Y1807797D01*
X41032Y1806864D01*
X41232Y1805797D01*
Y1804731D01*
X41032Y1803664D01*
X40632Y1802731D01*
X40032Y1801931D01*
X39332Y1801397D01*
X38532Y1801264D01*
G01X48732Y1808597D02*
X48132Y1808997D01*
X47432Y1809264D01*
X46632D01*
X45732Y1808864D01*
X45032Y1808197D01*
X44532Y1807397D01*
X44132Y1806064D01*
X44032Y1804864D01*
X44232Y1803664D01*
X44532Y1802864D01*
X45132Y1802064D01*
X45832Y1801531D01*
X46532Y1801264D01*
X47232D01*
X47932Y1801531D01*
X48532Y1801931D01*
X49032Y1802464D01*
G01X56532Y1801264D02*
X52532D01*
Y1809264D01*
X56532D01*
G01X54932Y1805397D02*
X52532D01*
G01X60432Y1802330D02*
X61232Y1801664D01*
X62132Y1801264D01*
X62932D01*
X63732Y1801664D01*
X64332Y1802330D01*
X64632Y1803264D01*
X64432Y1804197D01*
X63932Y1804997D01*
X63032Y1805531D01*
X61832Y1805797D01*
X61132Y1806331D01*
X60832Y1807264D01*
X61032Y1808197D01*
X61532Y1808864D01*
X62232Y1809264D01*
X62932D01*
X63632Y1808997D01*
X64232Y1808331D01*
G01X68432Y1802330D02*
X69232Y1801664D01*
X70132Y1801264D01*
X70932D01*
X71732Y1801664D01*
X72332Y1802330D01*
X72632Y1803264D01*
X72432Y1804197D01*
X71932Y1804997D01*
X71032Y1805531D01*
X69832Y1805797D01*
X69132Y1806331D01*
X68832Y1807264D01*
X69032Y1808197D01*
X69532Y1808864D01*
X70232Y1809264D01*
X70932D01*
X71632Y1808997D01*
X72232Y1808331D01*
G01X78532Y1800997D02*
X78332Y1801131D01*
Y1801397D01*
X78532Y1801531D01*
X78732Y1801397D01*
Y1801131D01*
X78532Y1800997D01*
G01Y1804597D02*
X78332Y1804731D01*
Y1804997D01*
X78532Y1805131D01*
X78732Y1804997D01*
Y1804731D01*
X78532Y1804597D01*
G01X-25468Y1831264D02*
Y1839264D01*
X-26668Y1837664D01*
G01Y1831264D02*
X-24268D01*
G01X-17468Y1830997D02*
X-17668Y1831131D01*
Y1831397D01*
X-17468Y1831531D01*
X-17268Y1831397D01*
Y1831131D01*
X-17468Y1830997D01*
G01X-11468Y1831264D02*
Y1839264D01*
X-9068D01*
X-8268Y1838864D01*
X-7668Y1837931D01*
X-7468Y1836864D01*
X-7668Y1835797D01*
X-8168Y1834997D01*
X-9068Y1834597D01*
X-11468D01*
G01X732Y1838597D02*
X132Y1838997D01*
X-568Y1839264D01*
X-1368D01*
X-2268Y1838864D01*
X-2968Y1838197D01*
X-3468Y1837397D01*
X-3868Y1836064D01*
X-3968Y1834864D01*
X-3768Y1833664D01*
X-3468Y1832864D01*
X-2868Y1832064D01*
X-2168Y1831531D01*
X-1468Y1831264D01*
X-768D01*
X-68Y1831531D01*
X532Y1831931D01*
X1032Y1832464D01*
G01X7332Y1835531D02*
X7732Y1835931D01*
X8032Y1836597D01*
X8232Y1837531D01*
X8032Y1838331D01*
X7632Y1838864D01*
X6932Y1839264D01*
X4232D01*
Y1831264D01*
X7532D01*
X8232Y1831797D01*
X8632Y1832597D01*
X8832Y1833531D01*
X8632Y1834464D01*
X8032Y1835264D01*
X7332Y1835531D01*
X4232D01*
G01X20432Y1832330D02*
X21232Y1831664D01*
X22132Y1831264D01*
X22932D01*
X23732Y1831664D01*
X24332Y1832330D01*
X24632Y1833264D01*
X24432Y1834197D01*
X23932Y1834997D01*
X23032Y1835531D01*
X21832Y1835797D01*
X21132Y1836331D01*
X20832Y1837264D01*
X21032Y1838197D01*
X21532Y1838864D01*
X22232Y1839264D01*
X22932D01*
X23632Y1838997D01*
X24232Y1838331D01*
G01X29332Y1839264D02*
X31732D01*
G01X30532D02*
Y1831264D01*
G01X29332D02*
X31732D01*
G01X36632Y1839264D02*
X40432D01*
X36632Y1831264D01*
X40432D01*
G01X48532D02*
X44532D01*
Y1839264D01*
X48532D01*
G01X46932Y1835397D02*
X44532D01*
G01X78532Y1830997D02*
X78332Y1831131D01*
Y1831397D01*
X78532Y1831531D01*
X78732Y1831397D01*
Y1831131D01*
X78532Y1830997D01*
G01Y1834597D02*
X78332Y1834731D01*
Y1834997D01*
X78532Y1835131D01*
X78732Y1834997D01*
Y1834731D01*
X78532Y1834597D01*
G01X92632Y1831264D02*
Y1839264D01*
X96432D01*
G01X95032Y1835397D02*
X92632D01*
G01X102532Y1831264D02*
X101732Y1831397D01*
X101032Y1831931D01*
X100432Y1832731D01*
X100032Y1833664D01*
X99832Y1834731D01*
Y1835797D01*
X100032Y1836864D01*
X100432Y1837797D01*
X101032Y1838597D01*
X101732Y1839131D01*
X102532Y1839264D01*
X103332Y1839131D01*
X104032Y1838597D01*
X104632Y1837797D01*
X105032Y1836864D01*
X105232Y1835797D01*
Y1834731D01*
X105032Y1833664D01*
X104632Y1832731D01*
X104032Y1831931D01*
X103332Y1831397D01*
X102532Y1831264D01*
G01X108532Y1839264D02*
Y1831264D01*
X112532D01*
G01X116532Y1839264D02*
Y1831264D01*
X120532D01*
G01X126532D02*
X125732Y1831397D01*
X125032Y1831931D01*
X124432Y1832731D01*
X124032Y1833664D01*
X123832Y1834731D01*
Y1835797D01*
X124032Y1836864D01*
X124432Y1837797D01*
X125032Y1838597D01*
X125732Y1839131D01*
X126532Y1839264D01*
X127332Y1839131D01*
X128032Y1838597D01*
X128632Y1837797D01*
X129032Y1836864D01*
X129232Y1835797D01*
Y1834731D01*
X129032Y1833664D01*
X128632Y1832731D01*
X128032Y1831931D01*
X127332Y1831397D01*
X126532Y1831264D01*
G01X131532Y1839264D02*
X132932Y1831264D01*
X134532Y1839264D01*
X136132Y1831264D01*
X137532Y1839264D01*
G01X151132Y1835264D02*
X153132D01*
Y1832864D01*
X152532Y1832064D01*
X151832Y1831531D01*
X150832Y1831264D01*
X149832Y1831531D01*
X149132Y1832064D01*
X148532Y1832864D01*
X148132Y1833797D01*
X147932Y1834864D01*
Y1835797D01*
X148132Y1836597D01*
X148532Y1837531D01*
X149132Y1838331D01*
X149732Y1838864D01*
X150532Y1839264D01*
X151232D01*
X152032Y1838997D01*
X152632Y1838464D01*
G01X160532Y1831264D02*
X156532D01*
Y1839264D01*
X160532D01*
G01X158932Y1835397D02*
X156532D01*
G01X164532Y1831264D02*
Y1839264D01*
X167032D01*
X167832Y1838864D01*
X168332Y1838331D01*
X168532Y1837264D01*
X168332Y1836197D01*
X167732Y1835531D01*
X167032Y1835131D01*
X164532D01*
G01X167032D02*
X168532Y1831264D01*
G01X175332Y1835531D02*
X175732Y1835931D01*
X176032Y1836597D01*
X176232Y1837531D01*
X176032Y1838331D01*
X175632Y1838864D01*
X174932Y1839264D01*
X172232D01*
Y1831264D01*
X175532D01*
X176232Y1831797D01*
X176632Y1832597D01*
X176832Y1833531D01*
X176632Y1834464D01*
X176032Y1835264D01*
X175332Y1835531D01*
X172232D01*
G01X184532Y1831264D02*
X180532D01*
Y1839264D01*
X184532D01*
G01X182932Y1835397D02*
X180532D01*
G01X188532Y1831264D02*
Y1839264D01*
X191032D01*
X191832Y1838864D01*
X192332Y1838331D01*
X192532Y1837264D01*
X192332Y1836197D01*
X191732Y1835531D01*
X191032Y1835131D01*
X188532D01*
G01X191032D02*
X192532Y1831264D01*
G01X204632D02*
Y1839264D01*
X208432D01*
G01X207032Y1835397D02*
X204632D01*
G01X213332Y1839264D02*
X215732D01*
G01X214532D02*
Y1831264D01*
G01X213332D02*
X215732D01*
G01X220532Y1839264D02*
Y1831264D01*
X224532D01*
G01X232532D02*
X228532D01*
Y1839264D01*
X232532D01*
G01X230932Y1835397D02*
X228532D01*
G01X237832Y1828864D02*
X239232Y1830731D01*
Y1832597D01*
X237832D01*
Y1830731D01*
X239232D01*
G01Y1833931D02*
Y1835797D01*
X237832D01*
Y1833931D01*
X239232D01*
G01X251532Y1839264D02*
X252932Y1831264D01*
X254532Y1839264D01*
X256132Y1831264D01*
X257532Y1839264D01*
G01X261332D02*
X263732D01*
G01X262532D02*
Y1831264D01*
G01X261332D02*
X263732D01*
G01X270532Y1839264D02*
Y1831264D01*
G01X268232Y1839264D02*
X272832D01*
G01X276432Y1831264D02*
Y1839264D01*
G01X280632D02*
Y1831264D01*
G01Y1835264D02*
X276432D01*
G01X294532Y1839264D02*
Y1831264D01*
G01X292232Y1839264D02*
X296832D01*
G01X302532Y1831264D02*
X301732Y1831397D01*
X301032Y1831931D01*
X300432Y1832731D01*
X300032Y1833664D01*
X299832Y1834731D01*
Y1835797D01*
X300032Y1836864D01*
X300432Y1837797D01*
X301032Y1838597D01*
X301732Y1839131D01*
X302532Y1839264D01*
X303332Y1839131D01*
X304032Y1838597D01*
X304632Y1837797D01*
X305032Y1836864D01*
X305232Y1835797D01*
Y1834731D01*
X305032Y1833664D01*
X304632Y1832731D01*
X304032Y1831931D01*
X303332Y1831397D01*
X302532Y1831264D01*
G01X308532Y1839264D02*
Y1831264D01*
X312532D01*
G01X320532D02*
X316532D01*
Y1839264D01*
X320532D01*
G01X318932Y1835397D02*
X316532D01*
G01X324532Y1831264D02*
Y1839264D01*
X327032D01*
X327832Y1838864D01*
X328332Y1838331D01*
X328532Y1837264D01*
X328332Y1836197D01*
X327732Y1835531D01*
X327032Y1835131D01*
X324532D01*
G01X327032D02*
X328532Y1831264D01*
G01X332032D02*
X334532Y1839264D01*
X337032Y1831264D01*
G01X336132Y1834064D02*
X332932D01*
G01X340232Y1831264D02*
Y1839264D01*
X344832Y1831264D01*
Y1839264D01*
G01X352732Y1838597D02*
X352132Y1838997D01*
X351432Y1839264D01*
X350632D01*
X349732Y1838864D01*
X349032Y1838197D01*
X348532Y1837397D01*
X348132Y1836064D01*
X348032Y1834864D01*
X348232Y1833664D01*
X348532Y1832864D01*
X349132Y1832064D01*
X349832Y1831531D01*
X350532Y1831264D01*
X351232D01*
X351932Y1831531D01*
X352532Y1831931D01*
X353032Y1832464D01*
G01X360532Y1831264D02*
X356532D01*
Y1839264D01*
X360532D01*
G01X358932Y1835397D02*
X356532D01*
G01X373232Y1832731D02*
X375832D01*
G01Y1835131D02*
X373232D01*
G01X381432Y1833931D02*
X383832D01*
G01X382532Y1835664D02*
Y1832197D01*
G01X388732Y1830997D02*
X392332Y1839264D01*
G01X397232Y1833931D02*
X399832D01*
G01X406532Y1839264D02*
X405732Y1838997D01*
X405132Y1838331D01*
X404732Y1837531D01*
X404432Y1836464D01*
X404332Y1835264D01*
X404432Y1834064D01*
X404732Y1832997D01*
X405132Y1832197D01*
X405732Y1831531D01*
X406532Y1831264D01*
X407332Y1831531D01*
X407932Y1832197D01*
X408332Y1832997D01*
X408632Y1834064D01*
X408732Y1835264D01*
X408632Y1836464D01*
X408332Y1837531D01*
X407932Y1838331D01*
X407332Y1838997D01*
X406532Y1839264D01*
G01X414532Y1830997D02*
X414332Y1831131D01*
Y1831397D01*
X414532Y1831531D01*
X414732Y1831397D01*
Y1831131D01*
X414532Y1830997D01*
G01X422532Y1831264D02*
Y1839264D01*
X421332Y1837664D01*
G01Y1831264D02*
X423732D01*
G01X428332Y1832464D02*
X428932Y1831797D01*
X429632Y1831397D01*
X430532Y1831264D01*
X431432Y1831531D01*
X432132Y1832064D01*
X432632Y1832997D01*
X432732Y1834064D01*
X432532Y1835131D01*
X432032Y1835797D01*
X431332Y1836331D01*
X430632Y1836464D01*
X429932Y1836331D01*
X429032Y1835797D01*
X429332Y1839264D01*
X432032D01*
G01X435932Y1831264D02*
Y1839264D01*
X438532Y1832597D01*
X441132Y1839264D01*
Y1831264D01*
G01X443932D02*
Y1839264D01*
X446532Y1832597D01*
X449132Y1839264D01*
Y1831264D01*
G01X-27368Y1822931D02*
X-26768Y1823731D01*
X-26068Y1824131D01*
X-25268Y1824264D01*
X-24268Y1823997D01*
X-23568Y1823331D01*
X-23368Y1822531D01*
X-23468Y1821730D01*
X-23868Y1821064D01*
X-25868Y1819731D01*
X-26768Y1818797D01*
X-27368Y1817464D01*
X-27568Y1816264D01*
X-23368D01*
G01X-17468Y1815997D02*
X-17668Y1816131D01*
Y1816397D01*
X-17468Y1816531D01*
X-17268Y1816397D01*
Y1816131D01*
X-17468Y1815997D01*
G01X-11368Y1816264D02*
Y1824264D01*
X-7568D01*
G01X-8968Y1820397D02*
X-11368D01*
G01X-3968Y1816264D02*
X-1468Y1824264D01*
X1032Y1816264D01*
G01X132Y1819064D02*
X-3068D01*
G01X7332Y1820531D02*
X7732Y1820931D01*
X8032Y1821597D01*
X8232Y1822531D01*
X8032Y1823331D01*
X7632Y1823864D01*
X6932Y1824264D01*
X4232D01*
Y1816264D01*
X7532D01*
X8232Y1816797D01*
X8632Y1817597D01*
X8832Y1818531D01*
X8632Y1819464D01*
X8032Y1820264D01*
X7332Y1820531D01*
X4232D01*
G01X12532Y1816264D02*
Y1824264D01*
X15032D01*
X15832Y1823864D01*
X16332Y1823331D01*
X16532Y1822264D01*
X16332Y1821197D01*
X15732Y1820531D01*
X15032Y1820131D01*
X12532D01*
G01X15032D02*
X16532Y1816264D01*
G01X21332Y1824264D02*
X23732D01*
G01X22532D02*
Y1816264D01*
G01X21332D02*
X23732D01*
G01X32732Y1823597D02*
X32132Y1823997D01*
X31432Y1824264D01*
X30632D01*
X29732Y1823864D01*
X29032Y1823197D01*
X28532Y1822397D01*
X28132Y1821064D01*
X28032Y1819864D01*
X28232Y1818664D01*
X28532Y1817864D01*
X29132Y1817064D01*
X29832Y1816531D01*
X30532Y1816264D01*
X31232D01*
X31932Y1816531D01*
X32532Y1816931D01*
X33032Y1817464D01*
G01X36032Y1816264D02*
X38532Y1824264D01*
X41032Y1816264D01*
G01X40132Y1819064D02*
X36932D01*
G01X46532Y1824264D02*
Y1816264D01*
G01X44232Y1824264D02*
X48832D01*
G01X56532Y1816264D02*
X52532D01*
Y1824264D01*
X56532D01*
G01X54932Y1820397D02*
X52532D01*
G01X68532Y1816264D02*
Y1824264D01*
X70932D01*
X71732Y1823864D01*
X72332Y1822931D01*
X72532Y1821864D01*
X72332Y1820797D01*
X71832Y1819997D01*
X70932Y1819597D01*
X68532D01*
G01X80532Y1816264D02*
X76532D01*
Y1824264D01*
X80532D01*
G01X78932Y1820397D02*
X76532D01*
G01X84532Y1816264D02*
Y1824264D01*
X87032D01*
X87832Y1823864D01*
X88332Y1823331D01*
X88532Y1822264D01*
X88332Y1821197D01*
X87732Y1820531D01*
X87032Y1820131D01*
X84532D01*
G01X87032D02*
X88532Y1816264D01*
G01X102532D02*
X101732Y1816397D01*
X101032Y1816931D01*
X100432Y1817731D01*
X100032Y1818664D01*
X99832Y1819731D01*
Y1820797D01*
X100032Y1821864D01*
X100432Y1822797D01*
X101032Y1823597D01*
X101732Y1824131D01*
X102532Y1824264D01*
X103332Y1824131D01*
X104032Y1823597D01*
X104632Y1822797D01*
X105032Y1821864D01*
X105232Y1820797D01*
Y1819731D01*
X105032Y1818664D01*
X104632Y1817731D01*
X104032Y1816931D01*
X103332Y1816397D01*
X102532Y1816264D01*
G01X103332Y1818397D02*
X104532Y1816264D01*
G01X108332Y1824264D02*
Y1818531D01*
X108732Y1817330D01*
X109532Y1816531D01*
X110532Y1816264D01*
X111532Y1816531D01*
X112332Y1817330D01*
X112732Y1818531D01*
Y1824264D01*
G01X116032Y1816264D02*
X118532Y1824264D01*
X121032Y1816264D01*
G01X120132Y1819064D02*
X116932D01*
G01X124232Y1816264D02*
Y1824264D01*
X128832Y1816264D01*
Y1824264D01*
G01X134532D02*
Y1816264D01*
G01X132232Y1824264D02*
X136832D01*
G01X140032Y1816264D02*
X142532Y1824264D01*
X145032Y1816264D01*
G01X144132Y1819064D02*
X140932D01*
G01X156532Y1816264D02*
Y1824264D01*
X158932D01*
X159732Y1823864D01*
X160332Y1822931D01*
X160532Y1821864D01*
X160332Y1820797D01*
X159832Y1819997D01*
X158932Y1819597D01*
X156532D01*
G01X168732Y1823597D02*
X168132Y1823997D01*
X167432Y1824264D01*
X166632D01*
X165732Y1823864D01*
X165032Y1823197D01*
X164532Y1822397D01*
X164132Y1821064D01*
X164032Y1819864D01*
X164232Y1818664D01*
X164532Y1817864D01*
X165132Y1817064D01*
X165832Y1816531D01*
X166532Y1816264D01*
X167232D01*
X167932Y1816531D01*
X168532Y1816931D01*
X169032Y1817464D01*
G01X175332Y1820531D02*
X175732Y1820931D01*
X176032Y1821597D01*
X176232Y1822531D01*
X176032Y1823331D01*
X175632Y1823864D01*
X174932Y1824264D01*
X172232D01*
Y1816264D01*
X175532D01*
X176232Y1816797D01*
X176632Y1817597D01*
X176832Y1818531D01*
X176632Y1819464D01*
X176032Y1820264D01*
X175332Y1820531D01*
X172232D01*
G01X188432Y1817330D02*
X189232Y1816664D01*
X190132Y1816264D01*
X190932D01*
X191732Y1816664D01*
X192332Y1817330D01*
X192632Y1818264D01*
X192432Y1819197D01*
X191932Y1819997D01*
X191032Y1820531D01*
X189832Y1820797D01*
X189132Y1821331D01*
X188832Y1822264D01*
X189032Y1823197D01*
X189532Y1823864D01*
X190232Y1824264D01*
X190932D01*
X191632Y1823997D01*
X192232Y1823331D01*
G01X196532Y1816264D02*
Y1824264D01*
X198932D01*
X199732Y1823864D01*
X200332Y1822931D01*
X200532Y1821864D01*
X200332Y1820797D01*
X199832Y1819997D01*
X198932Y1819597D01*
X196532D01*
G01X208532Y1816264D02*
X204532D01*
Y1824264D01*
X208532D01*
G01X206932Y1820397D02*
X204532D01*
G01X216732Y1823597D02*
X216132Y1823997D01*
X215432Y1824264D01*
X214632D01*
X213732Y1823864D01*
X213032Y1823197D01*
X212532Y1822397D01*
X212132Y1821064D01*
X212032Y1819864D01*
X212232Y1818664D01*
X212532Y1817864D01*
X213132Y1817064D01*
X213832Y1816531D01*
X214532Y1816264D01*
X215232D01*
X215932Y1816531D01*
X216532Y1816931D01*
X217032Y1817464D01*
G01X221332Y1824264D02*
X223732D01*
G01X222532D02*
Y1816264D01*
G01X221332D02*
X223732D01*
G01X228632D02*
Y1824264D01*
X232432D01*
G01X231032Y1820397D02*
X228632D01*
G01X237332Y1824264D02*
X239732D01*
G01X238532D02*
Y1816264D01*
G01X237332D02*
X239732D01*
G01X248732Y1823597D02*
X248132Y1823997D01*
X247432Y1824264D01*
X246632D01*
X245732Y1823864D01*
X245032Y1823197D01*
X244532Y1822397D01*
X244132Y1821064D01*
X244032Y1819864D01*
X244232Y1818664D01*
X244532Y1817864D01*
X245132Y1817064D01*
X245832Y1816531D01*
X246532Y1816264D01*
X247232D01*
X247932Y1816531D01*
X248532Y1816931D01*
X249032Y1817464D01*
G01X252032Y1816264D02*
X254532Y1824264D01*
X257032Y1816264D01*
G01X256132Y1819064D02*
X252932D01*
G01X262532Y1824264D02*
Y1816264D01*
G01X260232Y1824264D02*
X264832D01*
G01X269332D02*
X271732D01*
G01X270532D02*
Y1816264D01*
G01X269332D02*
X271732D01*
G01X278532D02*
X277732Y1816397D01*
X277032Y1816931D01*
X276432Y1817731D01*
X276032Y1818664D01*
X275832Y1819731D01*
Y1820797D01*
X276032Y1821864D01*
X276432Y1822797D01*
X277032Y1823597D01*
X277732Y1824131D01*
X278532Y1824264D01*
X279332Y1824131D01*
X280032Y1823597D01*
X280632Y1822797D01*
X281032Y1821864D01*
X281232Y1820797D01*
Y1819731D01*
X281032Y1818664D01*
X280632Y1817731D01*
X280032Y1816931D01*
X279332Y1816397D01*
X278532Y1816264D01*
G01X284232D02*
Y1824264D01*
X288832Y1816264D01*
Y1824264D01*
G01X305532Y1813597D02*
X300532Y1821597D01*
Y1822931D01*
X301532Y1824264D01*
X302532D01*
X303532Y1822931D01*
Y1821597D01*
X302532Y1820264D01*
X300532Y1818931D01*
X299532Y1817597D01*
Y1814931D01*
X300532Y1813597D01*
X303532D01*
X305532Y1816264D01*
G01X318532D02*
X317732Y1816397D01*
X317032Y1816931D01*
X316432Y1817731D01*
X316032Y1818664D01*
X315832Y1819731D01*
Y1820797D01*
X316032Y1821864D01*
X316432Y1822797D01*
X317032Y1823597D01*
X317732Y1824131D01*
X318532Y1824264D01*
X319332Y1824131D01*
X320032Y1823597D01*
X320632Y1822797D01*
X321032Y1821864D01*
X321232Y1820797D01*
Y1819731D01*
X321032Y1818664D01*
X320632Y1817731D01*
X320032Y1816931D01*
X319332Y1816397D01*
X318532Y1816264D01*
G01X319332Y1818397D02*
X320532Y1816264D01*
G01X328732Y1823597D02*
X328132Y1823997D01*
X327432Y1824264D01*
X326632D01*
X325732Y1823864D01*
X325032Y1823197D01*
X324532Y1822397D01*
X324132Y1821064D01*
X324032Y1819864D01*
X324232Y1818664D01*
X324532Y1817864D01*
X325132Y1817064D01*
X325832Y1816531D01*
X326532Y1816264D01*
X327232D01*
X327932Y1816531D01*
X328532Y1816931D01*
X329032Y1817464D01*
G01X334532Y1824264D02*
Y1816264D01*
G01X332232Y1824264D02*
X336832D01*
G01X352532Y1816264D02*
X348532D01*
Y1824264D01*
X352532D01*
G01X350932Y1820397D02*
X348532D01*
G01X358532Y1816264D02*
X357732Y1816397D01*
X357032Y1816931D01*
X356432Y1817731D01*
X356032Y1818664D01*
X355832Y1819731D01*
Y1820797D01*
X356032Y1821864D01*
X356432Y1822797D01*
X357032Y1823597D01*
X357732Y1824131D01*
X358532Y1824264D01*
X359332Y1824131D01*
X360032Y1823597D01*
X360632Y1822797D01*
X361032Y1821864D01*
X361232Y1820797D01*
Y1819731D01*
X361032Y1818664D01*
X360632Y1817731D01*
X360032Y1816931D01*
X359332Y1816397D01*
X358532Y1816264D01*
G01X359332Y1818397D02*
X360532Y1816264D01*
G01X372632D02*
Y1824264D01*
X376432D01*
G01X375032Y1820397D02*
X372632D01*
G01X380032Y1816264D02*
X382532Y1824264D01*
X385032Y1816264D01*
G01X384132Y1819064D02*
X380932D01*
G01X390532Y1816264D02*
X389732Y1816397D01*
X389032Y1816931D01*
X388432Y1817731D01*
X388032Y1818664D01*
X387832Y1819731D01*
Y1820797D01*
X388032Y1821864D01*
X388432Y1822797D01*
X389032Y1823597D01*
X389732Y1824131D01*
X390532Y1824264D01*
X391332Y1824131D01*
X392032Y1823597D01*
X392632Y1822797D01*
X393032Y1821864D01*
X393232Y1820797D01*
Y1819731D01*
X393032Y1818664D01*
X392632Y1817731D01*
X392032Y1816931D01*
X391332Y1816397D01*
X390532Y1816264D01*
G01X391332Y1818397D02*
X392532Y1816264D01*
G01X398532Y1815997D02*
X398332Y1816131D01*
Y1816397D01*
X398532Y1816531D01*
X398732Y1816397D01*
Y1816131D01*
X398532Y1815997D01*
G01X-25468Y1861264D02*
X-26268Y1861397D01*
X-26968Y1861931D01*
X-27568Y1862731D01*
X-27968Y1863664D01*
X-28168Y1864731D01*
Y1865797D01*
X-27968Y1866864D01*
X-27568Y1867797D01*
X-26968Y1868597D01*
X-26268Y1869131D01*
X-25468Y1869264D01*
X-24668Y1869131D01*
X-23968Y1868597D01*
X-23368Y1867797D01*
X-22968Y1866864D01*
X-22768Y1865797D01*
Y1864731D01*
X-22968Y1863664D01*
X-23368Y1862731D01*
X-23968Y1861931D01*
X-24668Y1861397D01*
X-25468Y1861264D01*
G01X-24668Y1863397D02*
X-23468Y1861264D01*
G01X-19168Y1866597D02*
Y1862864D01*
X-18768Y1861931D01*
X-18168Y1861397D01*
X-17468Y1861264D01*
X-16768Y1861397D01*
X-16168Y1861931D01*
X-15768Y1862864D01*
G01Y1861264D02*
Y1866597D01*
G01X-7668Y1861264D02*
Y1866597D01*
G01Y1865664D02*
X-8068Y1866197D01*
X-8668Y1866464D01*
X-9368Y1866597D01*
X-10068Y1866331D01*
X-10668Y1865797D01*
X-11068Y1864997D01*
X-11268Y1863931D01*
X-11068Y1862864D01*
X-10668Y1862064D01*
X-10068Y1861531D01*
X-9368Y1861264D01*
X-8668Y1861397D01*
X-8068Y1861797D01*
X-7668Y1862330D01*
G01X-3168Y1861264D02*
Y1866597D01*
G01Y1865264D02*
X-2768Y1865931D01*
X-2168Y1866464D01*
X-1368Y1866597D01*
X-668Y1866464D01*
X-68Y1865931D01*
X232Y1864997D01*
Y1861264D01*
G01X6532Y1869264D02*
Y1861264D01*
G01X5132Y1866597D02*
X7932D01*
G01X16332Y1861264D02*
Y1866597D01*
G01Y1865664D02*
X15932Y1866197D01*
X15332Y1866464D01*
X14632Y1866597D01*
X13932Y1866331D01*
X13332Y1865797D01*
X12932Y1864997D01*
X12732Y1863931D01*
X12932Y1862864D01*
X13332Y1862064D01*
X13932Y1861531D01*
X14632Y1861264D01*
X15332Y1861397D01*
X15932Y1861797D01*
X16332Y1862330D01*
G01X28632Y1861264D02*
Y1869264D01*
X32432D01*
G01X31032Y1865397D02*
X28632D01*
G01X36032Y1861264D02*
X38532Y1869264D01*
X41032Y1861264D01*
G01X40132Y1864064D02*
X36932D01*
G01X47332Y1865531D02*
X47732Y1865931D01*
X48032Y1866597D01*
X48232Y1867531D01*
X48032Y1868331D01*
X47632Y1868864D01*
X46932Y1869264D01*
X44232D01*
Y1861264D01*
X47532D01*
X48232Y1861797D01*
X48632Y1862597D01*
X48832Y1863531D01*
X48632Y1864464D01*
X48032Y1865264D01*
X47332Y1865531D01*
X44232D01*
G01X60232Y1861264D02*
Y1869264D01*
X64832Y1861264D01*
Y1869264D01*
G01X70532Y1861264D02*
X69732Y1861397D01*
X69032Y1861931D01*
X68432Y1862731D01*
X68032Y1863664D01*
X67832Y1864731D01*
Y1865797D01*
X68032Y1866864D01*
X68432Y1867797D01*
X69032Y1868597D01*
X69732Y1869131D01*
X70532Y1869264D01*
X71332Y1869131D01*
X72032Y1868597D01*
X72632Y1867797D01*
X73032Y1866864D01*
X73232Y1865797D01*
Y1864731D01*
X73032Y1863664D01*
X72632Y1862731D01*
X72032Y1861931D01*
X71332Y1861397D01*
X70532Y1861264D01*
G01X78532Y1869264D02*
Y1861264D01*
G01X76232Y1869264D02*
X80832D01*
G01X88532Y1861264D02*
X84532D01*
Y1869264D01*
X88532D01*
G01X86932Y1865397D02*
X84532D01*
G01X100532Y1861264D02*
Y1869264D01*
X103032D01*
X103832Y1868864D01*
X104332Y1868331D01*
X104532Y1867264D01*
X104332Y1866197D01*
X103732Y1865531D01*
X103032Y1865131D01*
X100532D01*
G01X103032D02*
X104532Y1861264D01*
G01X112532D02*
X108532D01*
Y1869264D01*
X112532D01*
G01X110932Y1865397D02*
X108532D01*
G01X116032Y1869264D02*
X118532Y1861264D01*
X121032Y1869264D01*
G01X126532Y1860997D02*
X126332Y1861131D01*
Y1861397D01*
X126532Y1861531D01*
X126732Y1861397D01*
Y1861131D01*
X126532Y1860997D01*
G01Y1864597D02*
X126332Y1864731D01*
Y1864997D01*
X126532Y1865131D01*
X126732Y1864997D01*
Y1864731D01*
X126532Y1864597D01*
G01X132632Y1861264D02*
Y1869264D01*
X136432D01*
G01X135032Y1865397D02*
X132632D01*
G01X-27768Y1846264D02*
Y1854264D01*
X-23168Y1846264D01*
Y1854264D01*
G01X-17468Y1846264D02*
X-18268Y1846397D01*
X-18968Y1846931D01*
X-19568Y1847731D01*
X-19968Y1848664D01*
X-20168Y1849731D01*
Y1850797D01*
X-19968Y1851864D01*
X-19568Y1852797D01*
X-18968Y1853597D01*
X-18268Y1854131D01*
X-17468Y1854264D01*
X-16668Y1854131D01*
X-15968Y1853597D01*
X-15368Y1852797D01*
X-14968Y1851864D01*
X-14768Y1850797D01*
Y1849731D01*
X-14968Y1848664D01*
X-15368Y1847731D01*
X-15968Y1846931D01*
X-16668Y1846397D01*
X-17468Y1846264D01*
G01X-9468Y1854264D02*
Y1846264D01*
G01X-11768Y1854264D02*
X-7168D01*
G01X532Y1846264D02*
X-3468D01*
Y1854264D01*
X532D01*
G01X-1068Y1850397D02*
X-3468D01*
G01X4432Y1847330D02*
X5232Y1846664D01*
X6132Y1846264D01*
X6932D01*
X7732Y1846664D01*
X8332Y1847330D01*
X8632Y1848264D01*
X8432Y1849197D01*
X7932Y1849997D01*
X7032Y1850531D01*
X5832Y1850797D01*
X5132Y1851331D01*
X4832Y1852264D01*
X5032Y1853197D01*
X5532Y1853864D01*
X6232Y1854264D01*
X6932D01*
X7632Y1853997D01*
X8232Y1853331D01*
G01X14532Y1845997D02*
X14332Y1846131D01*
Y1846397D01*
X14532Y1846531D01*
X14732Y1846397D01*
Y1846131D01*
X14532Y1845997D01*
G01Y1849597D02*
X14332Y1849731D01*
Y1849997D01*
X14532Y1850131D01*
X14732Y1849997D01*
Y1849731D01*
X14532Y1849597D01*
G01X30032Y1843597D02*
X29032Y1844931D01*
X28532Y1846264D01*
Y1851597D01*
X29032Y1852931D01*
X30032Y1854264D01*
G01X36332D02*
Y1848531D01*
X36732Y1847330D01*
X37532Y1846531D01*
X38532Y1846264D01*
X39532Y1846531D01*
X40332Y1847330D01*
X40732Y1848531D01*
Y1854264D01*
G01X44232Y1846264D02*
Y1854264D01*
X48832Y1846264D01*
Y1854264D01*
G01X52532D02*
Y1846264D01*
X56532D01*
G01X64532D02*
X60532D01*
Y1854264D01*
X64532D01*
G01X62932Y1850397D02*
X60532D01*
G01X68432Y1847330D02*
X69232Y1846664D01*
X70132Y1846264D01*
X70932D01*
X71732Y1846664D01*
X72332Y1847330D01*
X72632Y1848264D01*
X72432Y1849197D01*
X71932Y1849997D01*
X71032Y1850531D01*
X69832Y1850797D01*
X69132Y1851331D01*
X68832Y1852264D01*
X69032Y1853197D01*
X69532Y1853864D01*
X70232Y1854264D01*
X70932D01*
X71632Y1853997D01*
X72232Y1853331D01*
G01X76432Y1847330D02*
X77232Y1846664D01*
X78132Y1846264D01*
X78932D01*
X79732Y1846664D01*
X80332Y1847330D01*
X80632Y1848264D01*
X80432Y1849197D01*
X79932Y1849997D01*
X79032Y1850531D01*
X77832Y1850797D01*
X77132Y1851331D01*
X76832Y1852264D01*
X77032Y1853197D01*
X77532Y1853864D01*
X78232Y1854264D01*
X78932D01*
X79632Y1853997D01*
X80232Y1853331D01*
G01X94532Y1846264D02*
X93732Y1846397D01*
X93032Y1846931D01*
X92432Y1847731D01*
X92032Y1848664D01*
X91832Y1849731D01*
Y1850797D01*
X92032Y1851864D01*
X92432Y1852797D01*
X93032Y1853597D01*
X93732Y1854131D01*
X94532Y1854264D01*
X95332Y1854131D01*
X96032Y1853597D01*
X96632Y1852797D01*
X97032Y1851864D01*
X97232Y1850797D01*
Y1849731D01*
X97032Y1848664D01*
X96632Y1847731D01*
X96032Y1846931D01*
X95332Y1846397D01*
X94532Y1846264D01*
G01X102532Y1854264D02*
Y1846264D01*
G01X100232Y1854264D02*
X104832D01*
G01X108432Y1846264D02*
Y1854264D01*
G01X112632D02*
Y1846264D01*
G01Y1850264D02*
X108432D01*
G01X120532Y1846264D02*
X116532D01*
Y1854264D01*
X120532D01*
G01X118932Y1850397D02*
X116532D01*
G01X124532Y1846264D02*
Y1854264D01*
X127032D01*
X127832Y1853864D01*
X128332Y1853331D01*
X128532Y1852264D01*
X128332Y1851197D01*
X127732Y1850531D01*
X127032Y1850131D01*
X124532D01*
G01X127032D02*
X128532Y1846264D01*
G01X131532Y1854264D02*
X132932Y1846264D01*
X134532Y1854264D01*
X136132Y1846264D01*
X137532Y1854264D01*
G01X141332D02*
X143732D01*
G01X142532D02*
Y1846264D01*
G01X141332D02*
X143732D01*
G01X148432Y1847330D02*
X149232Y1846664D01*
X150132Y1846264D01*
X150932D01*
X151732Y1846664D01*
X152332Y1847330D01*
X152632Y1848264D01*
X152432Y1849197D01*
X151932Y1849997D01*
X151032Y1850531D01*
X149832Y1850797D01*
X149132Y1851331D01*
X148832Y1852264D01*
X149032Y1853197D01*
X149532Y1853864D01*
X150232Y1854264D01*
X150932D01*
X151632Y1853997D01*
X152232Y1853331D01*
G01X160532Y1846264D02*
X156532D01*
Y1854264D01*
X160532D01*
G01X158932Y1850397D02*
X156532D01*
G01X172432Y1847330D02*
X173232Y1846664D01*
X174132Y1846264D01*
X174932D01*
X175732Y1846664D01*
X176332Y1847330D01*
X176632Y1848264D01*
X176432Y1849197D01*
X175932Y1849997D01*
X175032Y1850531D01*
X173832Y1850797D01*
X173132Y1851331D01*
X172832Y1852264D01*
X173032Y1853197D01*
X173532Y1853864D01*
X174232Y1854264D01*
X174932D01*
X175632Y1853997D01*
X176232Y1853331D01*
G01X180532Y1846264D02*
Y1854264D01*
X182932D01*
X183732Y1853864D01*
X184332Y1852931D01*
X184532Y1851864D01*
X184332Y1850797D01*
X183832Y1849997D01*
X182932Y1849597D01*
X180532D01*
G01X192532Y1846264D02*
X188532D01*
Y1854264D01*
X192532D01*
G01X190932Y1850397D02*
X188532D01*
G01X200732Y1853597D02*
X200132Y1853997D01*
X199432Y1854264D01*
X198632D01*
X197732Y1853864D01*
X197032Y1853197D01*
X196532Y1852397D01*
X196132Y1851064D01*
X196032Y1849864D01*
X196232Y1848664D01*
X196532Y1847864D01*
X197132Y1847064D01*
X197832Y1846531D01*
X198532Y1846264D01*
X199232D01*
X199932Y1846531D01*
X200532Y1846931D01*
X201032Y1847464D01*
G01X205332Y1854264D02*
X207732D01*
G01X206532D02*
Y1846264D01*
G01X205332D02*
X207732D01*
G01X212632D02*
Y1854264D01*
X216432D01*
G01X215032Y1850397D02*
X212632D01*
G01X221332Y1854264D02*
X223732D01*
G01X222532D02*
Y1846264D01*
G01X221332D02*
X223732D01*
G01X232532D02*
X228532D01*
Y1854264D01*
X232532D01*
G01X230932Y1850397D02*
X228532D01*
G01X236332Y1846264D02*
Y1854264D01*
X238332D01*
X239132Y1853864D01*
X239732Y1853331D01*
X240232Y1852531D01*
X240632Y1851597D01*
X240732Y1850264D01*
X240632Y1848931D01*
X240232Y1847997D01*
X239732Y1847197D01*
X239132Y1846664D01*
X238332Y1846264D01*
X236332D01*
G01X253332Y1854264D02*
X255732D01*
G01X254532D02*
Y1846264D01*
G01X253332D02*
X255732D01*
G01X260232D02*
Y1854264D01*
X264832Y1846264D01*
Y1854264D01*
G01X276532Y1846264D02*
Y1854264D01*
X278932D01*
X279732Y1853864D01*
X280332Y1852931D01*
X280532Y1851864D01*
X280332Y1850797D01*
X279832Y1849997D01*
X278932Y1849597D01*
X276532D01*
G01X288732Y1853597D02*
X288132Y1853997D01*
X287432Y1854264D01*
X286632D01*
X285732Y1853864D01*
X285032Y1853197D01*
X284532Y1852397D01*
X284132Y1851064D01*
X284032Y1849864D01*
X284232Y1848664D01*
X284532Y1847864D01*
X285132Y1847064D01*
X285832Y1846531D01*
X286532Y1846264D01*
X287232D01*
X287932Y1846531D01*
X288532Y1846931D01*
X289032Y1847464D01*
G01X295332Y1850531D02*
X295732Y1850931D01*
X296032Y1851597D01*
X296232Y1852531D01*
X296032Y1853331D01*
X295632Y1853864D01*
X294932Y1854264D01*
X292232D01*
Y1846264D01*
X295532D01*
X296232Y1846797D01*
X296632Y1847597D01*
X296832Y1848531D01*
X296632Y1849464D01*
X296032Y1850264D01*
X295332Y1850531D01*
X292232D01*
G01X308432Y1847330D02*
X309232Y1846664D01*
X310132Y1846264D01*
X310932D01*
X311732Y1846664D01*
X312332Y1847330D01*
X312632Y1848264D01*
X312432Y1849197D01*
X311932Y1849997D01*
X311032Y1850531D01*
X309832Y1850797D01*
X309132Y1851331D01*
X308832Y1852264D01*
X309032Y1853197D01*
X309532Y1853864D01*
X310232Y1854264D01*
X310932D01*
X311632Y1853997D01*
X312232Y1853331D01*
G01X316532Y1846264D02*
Y1854264D01*
X318932D01*
X319732Y1853864D01*
X320332Y1852931D01*
X320532Y1851864D01*
X320332Y1850797D01*
X319832Y1849997D01*
X318932Y1849597D01*
X316532D01*
G01X328532Y1846264D02*
X324532D01*
Y1854264D01*
X328532D01*
G01X326932Y1850397D02*
X324532D01*
G01X336732Y1853597D02*
X336132Y1853997D01*
X335432Y1854264D01*
X334632D01*
X333732Y1853864D01*
X333032Y1853197D01*
X332532Y1852397D01*
X332132Y1851064D01*
X332032Y1849864D01*
X332232Y1848664D01*
X332532Y1847864D01*
X333132Y1847064D01*
X333832Y1846531D01*
X334532Y1846264D01*
X335232D01*
X335932Y1846531D01*
X336532Y1846931D01*
X337032Y1847464D01*
G01X343032Y1843597D02*
X344032Y1844931D01*
X344532Y1846264D01*
Y1851597D01*
X344032Y1852931D01*
X343032Y1854264D01*
G01X39370Y-734670D02*
Y-793725D01*
X0D01*
Y-734670D01*
X39370D01*
G01X18750Y-52061D02*
Y-56711D01*
X6250D01*
Y-52061D01*
G01X0Y-1000D02*
Y-19436D01*
G01X18750Y-33461D02*
Y-28811D01*
X6250D01*
Y-33461D01*
G01X1874016Y85709D02*
Y499094D01*
G03X1854331Y518780I-19686J0D01*
G01X1751969D01*
G02X1732283Y538465I0J19686D01*
G01Y603543D01*
G03X1712598Y623228I-19685J0D01*
G01X1629921D01*
G02X1610236Y642913I0J19685D01*
G01Y656102D01*
G03X1590551Y675787I-19685J0D01*
G01X1437008D01*
G03X1417323Y656102I0J-19685D01*
G01Y635039D01*
G02X1405512Y623228I-11811J0D01*
G01X1403543D01*
G03X1383858Y603543I0J-19685D01*
G01Y435039D01*
G02X1354331Y405512I-29527J0D01*
G01X377953D01*
G02X348425Y435039I-1J29527D01*
G01Y603543D01*
G03X328740Y623228I-19685J0D01*
G01X326772D01*
G02X314961Y635039I0J11811D01*
G01Y656102D01*
G03X295276Y675787I-19685J0D01*
G01X141732D01*
G03X122047Y656102I0J-19685D01*
G01Y642913D01*
G02X102362Y623228I-19685J0D01*
G01X19685D01*
G03X0Y603543I0J-19685D01*
G01Y19685D01*
G03X19685Y0I19685J0D01*
G01X1712598D01*
G03X1732283Y19685I0J19685D01*
G01Y46339D01*
G02X1751969Y66024I19685J0D01*
G01X1854331D01*
G03X1874016Y85709I0J19685D01*
G01X-1000Y0D02*
X-4441D01*
G01X0Y594864D02*
Y1027000D01*
G01X896375Y1026000D02*
X0D01*
G01X5000Y1027000D02*
X0Y1026000D01*
X5000Y1025000D01*
Y1027000D01*
G01X-14838Y1220716D02*
Y1189220D01*
G01D02*
Y1240401D01*
G01Y1260086D02*
Y1291582D01*
G01D02*
Y1240401D01*
G01X48154Y1295520D02*
X4847D01*
G01X48154Y1279771D02*
X4847D01*
G01X12721D02*
Y1332921D01*
G01X9832Y1307324D02*
X-2668D01*
X6290Y1301589D01*
Y1309339D01*
G01X9832Y1313834D02*
X-2668D01*
X7749Y1317864D01*
X-2668Y1321894D01*
X9832D01*
G01Y1326234D02*
X-2668D01*
X7749Y1330264D01*
X-2668Y1334294D01*
X9832D01*
G01X332Y1445531D02*
X732Y1445931D01*
X1032Y1446597D01*
X1232Y1447531D01*
X1032Y1448331D01*
X632Y1448864D01*
X-68Y1449264D01*
X-2768D01*
Y1441264D01*
X532D01*
X1232Y1441797D01*
X1632Y1442597D01*
X1832Y1443531D01*
X1632Y1444464D01*
X1032Y1445264D01*
X332Y1445531D01*
X-2768D01*
G01X7532Y1440997D02*
X7332Y1441131D01*
Y1441397D01*
X7532Y1441531D01*
X7732Y1441397D01*
Y1441131D01*
X7532Y1440997D01*
G01X14332Y1449264D02*
X16732D01*
G01X15532D02*
Y1441264D01*
G01X14332D02*
X16732D01*
G01X21632D02*
Y1449264D01*
X25432D01*
G01X24032Y1445397D02*
X21632D01*
G01X39532Y1449264D02*
Y1441264D01*
G01X37232Y1449264D02*
X41832D01*
G01X45432Y1441264D02*
Y1449264D01*
G01X49632D02*
Y1441264D01*
G01Y1445264D02*
X45432D01*
G01X57532Y1441264D02*
X53532D01*
Y1449264D01*
X57532D01*
G01X55932Y1445397D02*
X53532D01*
G01X69532Y1441264D02*
Y1449264D01*
X71932D01*
X72732Y1448864D01*
X73332Y1447931D01*
X73532Y1446864D01*
X73332Y1445797D01*
X72832Y1444997D01*
X71932Y1444597D01*
X69532D01*
G01X79532Y1449264D02*
Y1441264D01*
G01X77232Y1449264D02*
X81832D01*
G01X85432Y1441264D02*
Y1449264D01*
G01X89632D02*
Y1441264D01*
G01Y1445264D02*
X85432D01*
G01X103532Y1449264D02*
Y1441264D01*
G01X101232Y1449264D02*
X105832D01*
G01X111532Y1441264D02*
X110732Y1441397D01*
X110032Y1441931D01*
X109432Y1442731D01*
X109032Y1443664D01*
X108832Y1444731D01*
Y1445797D01*
X109032Y1446864D01*
X109432Y1447797D01*
X110032Y1448597D01*
X110732Y1449131D01*
X111532Y1449264D01*
X112332Y1449131D01*
X113032Y1448597D01*
X113632Y1447797D01*
X114032Y1446864D01*
X114232Y1445797D01*
Y1444731D01*
X114032Y1443664D01*
X113632Y1442731D01*
X113032Y1441931D01*
X112332Y1441397D01*
X111532Y1441264D01*
G01X119532D02*
X118732Y1441397D01*
X118032Y1441931D01*
X117432Y1442731D01*
X117032Y1443664D01*
X116832Y1444731D01*
Y1445797D01*
X117032Y1446864D01*
X117432Y1447797D01*
X118032Y1448597D01*
X118732Y1449131D01*
X119532Y1449264D01*
X120332Y1449131D01*
X121032Y1448597D01*
X121632Y1447797D01*
X122032Y1446864D01*
X122232Y1445797D01*
Y1444731D01*
X122032Y1443664D01*
X121632Y1442731D01*
X121032Y1441931D01*
X120332Y1441397D01*
X119532Y1441264D01*
G01X125532Y1449264D02*
Y1441264D01*
X129532D01*
G01X134332Y1449264D02*
X136732D01*
G01X135532D02*
Y1441264D01*
G01X134332D02*
X136732D01*
G01X141232D02*
Y1449264D01*
X145832Y1441264D01*
Y1449264D01*
G01X152132Y1445264D02*
X154132D01*
Y1442864D01*
X153532Y1442064D01*
X152832Y1441531D01*
X151832Y1441264D01*
X150832Y1441531D01*
X150132Y1442064D01*
X149532Y1442864D01*
X149132Y1443797D01*
X148932Y1444864D01*
Y1445797D01*
X149132Y1446597D01*
X149532Y1447531D01*
X150132Y1448331D01*
X150732Y1448864D01*
X151532Y1449264D01*
X152232D01*
X153032Y1448997D01*
X153632Y1448464D01*
G01X165432Y1441264D02*
Y1449264D01*
G01X169632D02*
Y1441264D01*
G01Y1445264D02*
X165432D01*
G01X175532Y1441264D02*
X174732Y1441397D01*
X174032Y1441931D01*
X173432Y1442731D01*
X173032Y1443664D01*
X172832Y1444731D01*
Y1445797D01*
X173032Y1446864D01*
X173432Y1447797D01*
X174032Y1448597D01*
X174732Y1449131D01*
X175532Y1449264D01*
X176332Y1449131D01*
X177032Y1448597D01*
X177632Y1447797D01*
X178032Y1446864D01*
X178232Y1445797D01*
Y1444731D01*
X178032Y1443664D01*
X177632Y1442731D01*
X177032Y1441931D01*
X176332Y1441397D01*
X175532Y1441264D01*
G01X181532Y1449264D02*
Y1441264D01*
X185532D01*
G01X193532D02*
X189532D01*
Y1449264D01*
X193532D01*
G01X191932Y1445397D02*
X189532D01*
G01X206332Y1449264D02*
X208732D01*
G01X207532D02*
Y1441264D01*
G01X206332D02*
X208732D01*
G01X213432Y1442330D02*
X214232Y1441664D01*
X215132Y1441264D01*
X215932D01*
X216732Y1441664D01*
X217332Y1442330D01*
X217632Y1443264D01*
X217432Y1444197D01*
X216932Y1444997D01*
X216032Y1445531D01*
X214832Y1445797D01*
X214132Y1446331D01*
X213832Y1447264D01*
X214032Y1448197D01*
X214532Y1448864D01*
X215232Y1449264D01*
X215932D01*
X216632Y1448997D01*
X217232Y1448331D01*
G01X228932Y1441264D02*
Y1449264D01*
X231532Y1442597D01*
X234132Y1449264D01*
Y1441264D01*
G01X237032D02*
X239532Y1449264D01*
X242032Y1441264D01*
G01X241132Y1444064D02*
X237932D01*
G01X245332Y1441264D02*
Y1449264D01*
X247332D01*
X248132Y1448864D01*
X248732Y1448331D01*
X249232Y1447531D01*
X249632Y1446597D01*
X249732Y1445264D01*
X249632Y1443931D01*
X249232Y1442997D01*
X248732Y1442197D01*
X248132Y1441664D01*
X247332Y1441264D01*
X245332D01*
G01X257532D02*
X253532D01*
Y1449264D01*
X257532D01*
G01X255932Y1445397D02*
X253532D01*
G01X272332Y1445531D02*
X272732Y1445931D01*
X273032Y1446597D01*
X273232Y1447531D01*
X273032Y1448331D01*
X272632Y1448864D01*
X271932Y1449264D01*
X269232D01*
Y1441264D01*
X272532D01*
X273232Y1441797D01*
X273632Y1442597D01*
X273832Y1443531D01*
X273632Y1444464D01*
X273032Y1445264D01*
X272332Y1445531D01*
X269232D01*
G01X279532Y1441264D02*
Y1444864D01*
X277532Y1449264D01*
G01X281532D02*
X279532Y1444864D01*
G01X293532Y1441264D02*
Y1449264D01*
X296032D01*
X296832Y1448864D01*
X297332Y1448331D01*
X297532Y1447264D01*
X297332Y1446197D01*
X296732Y1445531D01*
X296032Y1445131D01*
X293532D01*
G01X296032D02*
X297532Y1441264D01*
G01X303532D02*
X302732Y1441397D01*
X302032Y1441931D01*
X301432Y1442731D01*
X301032Y1443664D01*
X300832Y1444731D01*
Y1445797D01*
X301032Y1446864D01*
X301432Y1447797D01*
X302032Y1448597D01*
X302732Y1449131D01*
X303532Y1449264D01*
X304332Y1449131D01*
X305032Y1448597D01*
X305632Y1447797D01*
X306032Y1446864D01*
X306232Y1445797D01*
Y1444731D01*
X306032Y1443664D01*
X305632Y1442731D01*
X305032Y1441931D01*
X304332Y1441397D01*
X303532Y1441264D01*
G01X309332Y1449264D02*
Y1443531D01*
X309732Y1442330D01*
X310532Y1441531D01*
X311532Y1441264D01*
X312532Y1441531D01*
X313332Y1442330D01*
X313732Y1443531D01*
Y1449264D01*
G01X319532D02*
Y1441264D01*
G01X317232Y1449264D02*
X321832D01*
G01X326332D02*
X328732D01*
G01X327532D02*
Y1441264D01*
G01X326332D02*
X328732D01*
G01X333232D02*
Y1449264D01*
X337832Y1441264D01*
Y1449264D01*
G01X344132Y1445264D02*
X346132D01*
Y1442864D01*
X345532Y1442064D01*
X344832Y1441531D01*
X343832Y1441264D01*
X342832Y1441531D01*
X342132Y1442064D01*
X341532Y1442864D01*
X341132Y1443797D01*
X340932Y1444864D01*
Y1445797D01*
X341132Y1446597D01*
X341532Y1447531D01*
X342132Y1448331D01*
X342732Y1448864D01*
X343532Y1449264D01*
X344232D01*
X345032Y1448997D01*
X345632Y1448464D01*
G01X351332Y1439797D02*
X351732Y1441531D01*
G01X365232Y1441264D02*
Y1449264D01*
X369832Y1441264D01*
Y1449264D01*
G01X375532Y1441264D02*
X374732Y1441397D01*
X374032Y1441931D01*
X373432Y1442731D01*
X373032Y1443664D01*
X372832Y1444731D01*
Y1445797D01*
X373032Y1446864D01*
X373432Y1447797D01*
X374032Y1448597D01*
X374732Y1449131D01*
X375532Y1449264D01*
X376332Y1449131D01*
X377032Y1448597D01*
X377632Y1447797D01*
X378032Y1446864D01*
X378232Y1445797D01*
Y1444731D01*
X378032Y1443664D01*
X377632Y1442731D01*
X377032Y1441931D01*
X376332Y1441397D01*
X375532Y1441264D01*
G01X381232D02*
Y1449264D01*
X385832Y1441264D01*
Y1449264D01*
G01X390232Y1443931D02*
X392832D01*
G01X397632Y1441264D02*
Y1449264D01*
X401432D01*
G01X400032Y1445397D02*
X397632D01*
G01X405332Y1449264D02*
Y1443531D01*
X405732Y1442330D01*
X406532Y1441531D01*
X407532Y1441264D01*
X408532Y1441531D01*
X409332Y1442330D01*
X409732Y1443531D01*
Y1449264D01*
G01X413232Y1441264D02*
Y1449264D01*
X417832Y1441264D01*
Y1449264D01*
G01X425732Y1448597D02*
X425132Y1448997D01*
X424432Y1449264D01*
X423632D01*
X422732Y1448864D01*
X422032Y1448197D01*
X421532Y1447397D01*
X421132Y1446064D01*
X421032Y1444864D01*
X421232Y1443664D01*
X421532Y1442864D01*
X422132Y1442064D01*
X422832Y1441531D01*
X423532Y1441264D01*
X424232D01*
X424932Y1441531D01*
X425532Y1441931D01*
X426032Y1442464D01*
G01X431532Y1449264D02*
Y1441264D01*
G01X429232Y1449264D02*
X433832D01*
G01X438332D02*
X440732D01*
G01X439532D02*
Y1441264D01*
G01X438332D02*
X440732D01*
G01X447532D02*
X446732Y1441397D01*
X446032Y1441931D01*
X445432Y1442731D01*
X445032Y1443664D01*
X444832Y1444731D01*
Y1445797D01*
X445032Y1446864D01*
X445432Y1447797D01*
X446032Y1448597D01*
X446732Y1449131D01*
X447532Y1449264D01*
X448332Y1449131D01*
X449032Y1448597D01*
X449632Y1447797D01*
X450032Y1446864D01*
X450232Y1445797D01*
Y1444731D01*
X450032Y1443664D01*
X449632Y1442731D01*
X449032Y1441931D01*
X448332Y1441397D01*
X447532Y1441264D01*
G01X453232D02*
Y1449264D01*
X457832Y1441264D01*
Y1449264D01*
G01X461032Y1441264D02*
X463532Y1449264D01*
X466032Y1441264D01*
G01X465132Y1444064D02*
X461932D01*
G01X469532Y1449264D02*
Y1441264D01*
X473532D01*
G01X485532D02*
Y1449264D01*
X487932D01*
X488732Y1448864D01*
X489332Y1447931D01*
X489532Y1446864D01*
X489332Y1445797D01*
X488832Y1444997D01*
X487932Y1444597D01*
X485532D01*
G01X493032Y1441264D02*
X495532Y1449264D01*
X498032Y1441264D01*
G01X497132Y1444064D02*
X493932D01*
G01X501332Y1441264D02*
Y1449264D01*
X503332D01*
X504132Y1448864D01*
X504732Y1448331D01*
X505232Y1447531D01*
X505632Y1446597D01*
X505732Y1445264D01*
X505632Y1443931D01*
X505232Y1442997D01*
X504732Y1442197D01*
X504132Y1441664D01*
X503332Y1441264D01*
X501332D01*
G01X517432Y1442330D02*
X518232Y1441664D01*
X519132Y1441264D01*
X519932D01*
X520732Y1441664D01*
X521332Y1442330D01*
X521632Y1443264D01*
X521432Y1444197D01*
X520932Y1444997D01*
X520032Y1445531D01*
X518832Y1445797D01*
X518132Y1446331D01*
X517832Y1447264D01*
X518032Y1448197D01*
X518532Y1448864D01*
X519232Y1449264D01*
X519932D01*
X520632Y1448997D01*
X521232Y1448331D01*
G01X526332Y1449264D02*
X528732D01*
G01X527532D02*
Y1441264D01*
G01X526332D02*
X528732D01*
G01X533632Y1449264D02*
X537432D01*
X533632Y1441264D01*
X537432D01*
G01X545532D02*
X541532D01*
Y1449264D01*
X545532D01*
G01X543932Y1445397D02*
X541532D01*
G01X558332Y1449264D02*
X560732D01*
G01X559532D02*
Y1441264D01*
G01X558332D02*
X560732D01*
G01X565432Y1442330D02*
X566232Y1441664D01*
X567132Y1441264D01*
X567932D01*
X568732Y1441664D01*
X569332Y1442330D01*
X569632Y1443264D01*
X569432Y1444197D01*
X568932Y1444997D01*
X568032Y1445531D01*
X566832Y1445797D01*
X566132Y1446331D01*
X565832Y1447264D01*
X566032Y1448197D01*
X566532Y1448864D01*
X567232Y1449264D01*
X567932D01*
X568632Y1448997D01*
X569232Y1448331D01*
G01X583532Y1449264D02*
Y1441264D01*
G01X581232Y1449264D02*
X585832D01*
G01X589432Y1441264D02*
Y1449264D01*
G01X593632D02*
Y1441264D01*
G01Y1445264D02*
X589432D01*
G01X601532Y1441264D02*
X597532D01*
Y1449264D01*
X601532D01*
G01X599932Y1445397D02*
X597532D01*
G01X613532Y1441264D02*
Y1449264D01*
X615932D01*
X616732Y1448864D01*
X617332Y1447931D01*
X617532Y1446864D01*
X617332Y1445797D01*
X616832Y1444997D01*
X615932Y1444597D01*
X613532D01*
G01X621532Y1441264D02*
Y1449264D01*
X624032D01*
X624832Y1448864D01*
X625332Y1448331D01*
X625532Y1447264D01*
X625332Y1446197D01*
X624732Y1445531D01*
X624032Y1445131D01*
X621532D01*
G01X624032D02*
X625532Y1441264D01*
G01X631532D02*
X630732Y1441397D01*
X630032Y1441931D01*
X629432Y1442731D01*
X629032Y1443664D01*
X628832Y1444731D01*
Y1445797D01*
X629032Y1446864D01*
X629432Y1447797D01*
X630032Y1448597D01*
X630732Y1449131D01*
X631532Y1449264D01*
X632332Y1449131D01*
X633032Y1448597D01*
X633632Y1447797D01*
X634032Y1446864D01*
X634232Y1445797D01*
Y1444731D01*
X634032Y1443664D01*
X633632Y1442731D01*
X633032Y1441931D01*
X632332Y1441397D01*
X631532Y1441264D01*
G01X637632D02*
Y1449264D01*
X641432D01*
G01X640032Y1445397D02*
X637632D01*
G01X646332Y1449264D02*
X648732D01*
G01X647532D02*
Y1441264D01*
G01X646332D02*
X648732D01*
G01X653532Y1449264D02*
Y1441264D01*
X657532D01*
G01X665532D02*
X661532D01*
Y1449264D01*
X665532D01*
G01X663932Y1445397D02*
X661532D01*
G01X677432Y1442330D02*
X678232Y1441664D01*
X679132Y1441264D01*
X679932D01*
X680732Y1441664D01*
X681332Y1442330D01*
X681632Y1443264D01*
X681432Y1444197D01*
X680932Y1444997D01*
X680032Y1445531D01*
X678832Y1445797D01*
X678132Y1446331D01*
X677832Y1447264D01*
X678032Y1448197D01*
X678532Y1448864D01*
X679232Y1449264D01*
X679932D01*
X680632Y1448997D01*
X681232Y1448331D01*
G01X686332Y1449264D02*
X688732D01*
G01X687532D02*
Y1441264D01*
G01X686332D02*
X688732D01*
G01X693632Y1449264D02*
X697432D01*
X693632Y1441264D01*
X697432D01*
G01X705532D02*
X701532D01*
Y1449264D01*
X705532D01*
G01X703932Y1445397D02*
X701532D01*
G01X718432Y1443931D02*
X720832D01*
G01X719532Y1445664D02*
Y1442197D01*
G01X733632Y1447931D02*
X734232Y1448731D01*
X734932Y1449131D01*
X735732Y1449264D01*
X736732Y1448997D01*
X737432Y1448331D01*
X737632Y1447531D01*
X737532Y1446730D01*
X737132Y1446064D01*
X735132Y1444731D01*
X734232Y1443797D01*
X733632Y1442464D01*
X733432Y1441264D01*
X737632D01*
G01X743532Y1449264D02*
X742732Y1448997D01*
X742132Y1448331D01*
X741732Y1447531D01*
X741432Y1446464D01*
X741332Y1445264D01*
X741432Y1444064D01*
X741732Y1442997D01*
X742132Y1442197D01*
X742732Y1441531D01*
X743532Y1441264D01*
X744332Y1441531D01*
X744932Y1442197D01*
X745332Y1442997D01*
X745632Y1444064D01*
X745732Y1445264D01*
X745632Y1446464D01*
X745332Y1447531D01*
X744932Y1448331D01*
X744332Y1448997D01*
X743532Y1449264D01*
G01X748932Y1441264D02*
Y1449264D01*
X751532Y1442597D01*
X754132Y1449264D01*
Y1441264D01*
G01X758332Y1449264D02*
X760732D01*
G01X759532D02*
Y1441264D01*
G01X758332D02*
X760732D01*
G01X765532Y1449264D02*
Y1441264D01*
X769532D01*
G01X-2968Y1456264D02*
X-468Y1464264D01*
X2032Y1456264D01*
G01X1132Y1459064D02*
X-2068D01*
G01X7532Y1455997D02*
X7332Y1456131D01*
Y1456397D01*
X7532Y1456531D01*
X7732Y1456397D01*
Y1456131D01*
X7532Y1455997D01*
G01X14332Y1464264D02*
X16732D01*
G01X15532D02*
Y1456264D01*
G01X14332D02*
X16732D01*
G01X21632D02*
Y1464264D01*
X25432D01*
G01X24032Y1460397D02*
X21632D01*
G01X39532Y1464264D02*
Y1456264D01*
G01X37232Y1464264D02*
X41832D01*
G01X45432Y1456264D02*
Y1464264D01*
G01X49632D02*
Y1456264D01*
G01Y1460264D02*
X45432D01*
G01X57532Y1456264D02*
X53532D01*
Y1464264D01*
X57532D01*
G01X55932Y1460397D02*
X53532D01*
G01X69532Y1456264D02*
Y1464264D01*
X71932D01*
X72732Y1463864D01*
X73332Y1462931D01*
X73532Y1461864D01*
X73332Y1460797D01*
X72832Y1459997D01*
X71932Y1459597D01*
X69532D01*
G01X79532Y1464264D02*
Y1456264D01*
G01X77232Y1464264D02*
X81832D01*
G01X85432Y1456264D02*
Y1464264D01*
G01X89632D02*
Y1456264D01*
G01Y1460264D02*
X85432D01*
G01X103532Y1464264D02*
Y1456264D01*
G01X101232Y1464264D02*
X105832D01*
G01X111532Y1456264D02*
X110732Y1456397D01*
X110032Y1456931D01*
X109432Y1457731D01*
X109032Y1458664D01*
X108832Y1459731D01*
Y1460797D01*
X109032Y1461864D01*
X109432Y1462797D01*
X110032Y1463597D01*
X110732Y1464131D01*
X111532Y1464264D01*
X112332Y1464131D01*
X113032Y1463597D01*
X113632Y1462797D01*
X114032Y1461864D01*
X114232Y1460797D01*
Y1459731D01*
X114032Y1458664D01*
X113632Y1457731D01*
X113032Y1456931D01*
X112332Y1456397D01*
X111532Y1456264D01*
G01X119532D02*
X118732Y1456397D01*
X118032Y1456931D01*
X117432Y1457731D01*
X117032Y1458664D01*
X116832Y1459731D01*
Y1460797D01*
X117032Y1461864D01*
X117432Y1462797D01*
X118032Y1463597D01*
X118732Y1464131D01*
X119532Y1464264D01*
X120332Y1464131D01*
X121032Y1463597D01*
X121632Y1462797D01*
X122032Y1461864D01*
X122232Y1460797D01*
Y1459731D01*
X122032Y1458664D01*
X121632Y1457731D01*
X121032Y1456931D01*
X120332Y1456397D01*
X119532Y1456264D01*
G01X125532Y1464264D02*
Y1456264D01*
X129532D01*
G01X134332Y1464264D02*
X136732D01*
G01X135532D02*
Y1456264D01*
G01X134332D02*
X136732D01*
G01X141232D02*
Y1464264D01*
X145832Y1456264D01*
Y1464264D01*
G01X152132Y1460264D02*
X154132D01*
Y1457864D01*
X153532Y1457064D01*
X152832Y1456531D01*
X151832Y1456264D01*
X150832Y1456531D01*
X150132Y1457064D01*
X149532Y1457864D01*
X149132Y1458797D01*
X148932Y1459864D01*
Y1460797D01*
X149132Y1461597D01*
X149532Y1462531D01*
X150132Y1463331D01*
X150732Y1463864D01*
X151532Y1464264D01*
X152232D01*
X153032Y1463997D01*
X153632Y1463464D01*
G01X165432Y1456264D02*
Y1464264D01*
G01X169632D02*
Y1456264D01*
G01Y1460264D02*
X165432D01*
G01X175532Y1456264D02*
X174732Y1456397D01*
X174032Y1456931D01*
X173432Y1457731D01*
X173032Y1458664D01*
X172832Y1459731D01*
Y1460797D01*
X173032Y1461864D01*
X173432Y1462797D01*
X174032Y1463597D01*
X174732Y1464131D01*
X175532Y1464264D01*
X176332Y1464131D01*
X177032Y1463597D01*
X177632Y1462797D01*
X178032Y1461864D01*
X178232Y1460797D01*
Y1459731D01*
X178032Y1458664D01*
X177632Y1457731D01*
X177032Y1456931D01*
X176332Y1456397D01*
X175532Y1456264D01*
G01X181532Y1464264D02*
Y1456264D01*
X185532D01*
G01X193532D02*
X189532D01*
Y1464264D01*
X193532D01*
G01X191932Y1460397D02*
X189532D01*
G01X206332Y1464264D02*
X208732D01*
G01X207532D02*
Y1456264D01*
G01X206332D02*
X208732D01*
G01X213432Y1457330D02*
X214232Y1456664D01*
X215132Y1456264D01*
X215932D01*
X216732Y1456664D01*
X217332Y1457330D01*
X217632Y1458264D01*
X217432Y1459197D01*
X216932Y1459997D01*
X216032Y1460531D01*
X214832Y1460797D01*
X214132Y1461331D01*
X213832Y1462264D01*
X214032Y1463197D01*
X214532Y1463864D01*
X215232Y1464264D01*
X215932D01*
X216632Y1463997D01*
X217232Y1463331D01*
G01X228932Y1456264D02*
Y1464264D01*
X231532Y1457597D01*
X234132Y1464264D01*
Y1456264D01*
G01X237032D02*
X239532Y1464264D01*
X242032Y1456264D01*
G01X241132Y1459064D02*
X237932D01*
G01X245332Y1456264D02*
Y1464264D01*
X247332D01*
X248132Y1463864D01*
X248732Y1463331D01*
X249232Y1462531D01*
X249632Y1461597D01*
X249732Y1460264D01*
X249632Y1458931D01*
X249232Y1457997D01*
X248732Y1457197D01*
X248132Y1456664D01*
X247332Y1456264D01*
X245332D01*
G01X257532D02*
X253532D01*
Y1464264D01*
X257532D01*
G01X255932Y1460397D02*
X253532D01*
G01X272332Y1460531D02*
X272732Y1460931D01*
X273032Y1461597D01*
X273232Y1462531D01*
X273032Y1463331D01*
X272632Y1463864D01*
X271932Y1464264D01*
X269232D01*
Y1456264D01*
X272532D01*
X273232Y1456797D01*
X273632Y1457597D01*
X273832Y1458531D01*
X273632Y1459464D01*
X273032Y1460264D01*
X272332Y1460531D01*
X269232D01*
G01X279532Y1456264D02*
Y1459864D01*
X277532Y1464264D01*
G01X281532D02*
X279532Y1459864D01*
G01X293332Y1456264D02*
Y1464264D01*
X295332D01*
X296132Y1463864D01*
X296732Y1463331D01*
X297232Y1462531D01*
X297632Y1461597D01*
X297732Y1460264D01*
X297632Y1458931D01*
X297232Y1457997D01*
X296732Y1457197D01*
X296132Y1456664D01*
X295332Y1456264D01*
X293332D01*
G01X301532D02*
Y1464264D01*
X304032D01*
X304832Y1463864D01*
X305332Y1463331D01*
X305532Y1462264D01*
X305332Y1461197D01*
X304732Y1460531D01*
X304032Y1460131D01*
X301532D01*
G01X304032D02*
X305532Y1456264D01*
G01X310332Y1464264D02*
X312732D01*
G01X311532D02*
Y1456264D01*
G01X310332D02*
X312732D01*
G01X317532Y1464264D02*
Y1456264D01*
X321532D01*
G01X325532Y1464264D02*
Y1456264D01*
X329532D01*
G01X334332Y1464264D02*
X336732D01*
G01X335532D02*
Y1456264D01*
G01X334332D02*
X336732D01*
G01X341232D02*
Y1464264D01*
X345832Y1456264D01*
Y1464264D01*
G01X352132Y1460264D02*
X354132D01*
Y1457864D01*
X353532Y1457064D01*
X352832Y1456531D01*
X351832Y1456264D01*
X350832Y1456531D01*
X350132Y1457064D01*
X349532Y1457864D01*
X349132Y1458797D01*
X348932Y1459864D01*
Y1460797D01*
X349132Y1461597D01*
X349532Y1462531D01*
X350132Y1463331D01*
X350732Y1463864D01*
X351532Y1464264D01*
X352232D01*
X353032Y1463997D01*
X353632Y1463464D01*
G01X359332Y1454797D02*
X359732Y1456531D01*
G01X373232Y1456264D02*
Y1464264D01*
X377832Y1456264D01*
Y1464264D01*
G01X383532Y1456264D02*
X382732Y1456397D01*
X382032Y1456931D01*
X381432Y1457731D01*
X381032Y1458664D01*
X380832Y1459731D01*
Y1460797D01*
X381032Y1461864D01*
X381432Y1462797D01*
X382032Y1463597D01*
X382732Y1464131D01*
X383532Y1464264D01*
X384332Y1464131D01*
X385032Y1463597D01*
X385632Y1462797D01*
X386032Y1461864D01*
X386232Y1460797D01*
Y1459731D01*
X386032Y1458664D01*
X385632Y1457731D01*
X385032Y1456931D01*
X384332Y1456397D01*
X383532Y1456264D01*
G01X389232D02*
Y1464264D01*
X393832Y1456264D01*
Y1464264D01*
G01X398232Y1458931D02*
X400832D01*
G01X405632Y1456264D02*
Y1464264D01*
X409432D01*
G01X408032Y1460397D02*
X405632D01*
G01X413332Y1464264D02*
Y1458531D01*
X413732Y1457330D01*
X414532Y1456531D01*
X415532Y1456264D01*
X416532Y1456531D01*
X417332Y1457330D01*
X417732Y1458531D01*
Y1464264D01*
G01X421232Y1456264D02*
Y1464264D01*
X425832Y1456264D01*
Y1464264D01*
G01X433732Y1463597D02*
X433132Y1463997D01*
X432432Y1464264D01*
X431632D01*
X430732Y1463864D01*
X430032Y1463197D01*
X429532Y1462397D01*
X429132Y1461064D01*
X429032Y1459864D01*
X429232Y1458664D01*
X429532Y1457864D01*
X430132Y1457064D01*
X430832Y1456531D01*
X431532Y1456264D01*
X432232D01*
X432932Y1456531D01*
X433532Y1456931D01*
X434032Y1457464D01*
G01X439532Y1464264D02*
Y1456264D01*
G01X437232Y1464264D02*
X441832D01*
G01X446332D02*
X448732D01*
G01X447532D02*
Y1456264D01*
G01X446332D02*
X448732D01*
G01X455532D02*
X454732Y1456397D01*
X454032Y1456931D01*
X453432Y1457731D01*
X453032Y1458664D01*
X452832Y1459731D01*
Y1460797D01*
X453032Y1461864D01*
X453432Y1462797D01*
X454032Y1463597D01*
X454732Y1464131D01*
X455532Y1464264D01*
X456332Y1464131D01*
X457032Y1463597D01*
X457632Y1462797D01*
X458032Y1461864D01*
X458232Y1460797D01*
Y1459731D01*
X458032Y1458664D01*
X457632Y1457731D01*
X457032Y1456931D01*
X456332Y1456397D01*
X455532Y1456264D01*
G01X461232D02*
Y1464264D01*
X465832Y1456264D01*
Y1464264D01*
G01X469032Y1456264D02*
X471532Y1464264D01*
X474032Y1456264D01*
G01X473132Y1459064D02*
X469932D01*
G01X477532Y1464264D02*
Y1456264D01*
X481532D01*
G01X493532D02*
Y1464264D01*
X495932D01*
X496732Y1463864D01*
X497332Y1462931D01*
X497532Y1461864D01*
X497332Y1460797D01*
X496832Y1459997D01*
X495932Y1459597D01*
X493532D01*
G01X501032Y1456264D02*
X503532Y1464264D01*
X506032Y1456264D01*
G01X505132Y1459064D02*
X501932D01*
G01X509332Y1456264D02*
Y1464264D01*
X511332D01*
X512132Y1463864D01*
X512732Y1463331D01*
X513232Y1462531D01*
X513632Y1461597D01*
X513732Y1460264D01*
X513632Y1458931D01*
X513232Y1457997D01*
X512732Y1457197D01*
X512132Y1456664D01*
X511332Y1456264D01*
X509332D01*
G01X525432Y1457330D02*
X526232Y1456664D01*
X527132Y1456264D01*
X527932D01*
X528732Y1456664D01*
X529332Y1457330D01*
X529632Y1458264D01*
X529432Y1459197D01*
X528932Y1459997D01*
X528032Y1460531D01*
X526832Y1460797D01*
X526132Y1461331D01*
X525832Y1462264D01*
X526032Y1463197D01*
X526532Y1463864D01*
X527232Y1464264D01*
X527932D01*
X528632Y1463997D01*
X529232Y1463331D01*
G01X534332Y1464264D02*
X536732D01*
G01X535532D02*
Y1456264D01*
G01X534332D02*
X536732D01*
G01X541632Y1464264D02*
X545432D01*
X541632Y1456264D01*
X545432D01*
G01X553532D02*
X549532D01*
Y1464264D01*
X553532D01*
G01X551932Y1460397D02*
X549532D01*
G01X566332Y1464264D02*
X568732D01*
G01X567532D02*
Y1456264D01*
G01X566332D02*
X568732D01*
G01X573432Y1457330D02*
X574232Y1456664D01*
X575132Y1456264D01*
X575932D01*
X576732Y1456664D01*
X577332Y1457330D01*
X577632Y1458264D01*
X577432Y1459197D01*
X576932Y1459997D01*
X576032Y1460531D01*
X574832Y1460797D01*
X574132Y1461331D01*
X573832Y1462264D01*
X574032Y1463197D01*
X574532Y1463864D01*
X575232Y1464264D01*
X575932D01*
X576632Y1463997D01*
X577232Y1463331D01*
G01X591532Y1464264D02*
Y1456264D01*
G01X589232Y1464264D02*
X593832D01*
G01X597432Y1456264D02*
Y1464264D01*
G01X601632D02*
Y1456264D01*
G01Y1460264D02*
X597432D01*
G01X609532Y1456264D02*
X605532D01*
Y1464264D01*
X609532D01*
G01X607932Y1460397D02*
X605532D01*
G01X621332Y1456264D02*
Y1464264D01*
X623332D01*
X624132Y1463864D01*
X624732Y1463331D01*
X625232Y1462531D01*
X625632Y1461597D01*
X625732Y1460264D01*
X625632Y1458931D01*
X625232Y1457997D01*
X624732Y1457197D01*
X624132Y1456664D01*
X623332Y1456264D01*
X621332D01*
G01X629532D02*
Y1464264D01*
X632032D01*
X632832Y1463864D01*
X633332Y1463331D01*
X633532Y1462264D01*
X633332Y1461197D01*
X632732Y1460531D01*
X632032Y1460131D01*
X629532D01*
G01X632032D02*
X633532Y1456264D01*
G01X638332Y1464264D02*
X640732D01*
G01X639532D02*
Y1456264D01*
G01X638332D02*
X640732D01*
G01X645532Y1464264D02*
Y1456264D01*
X649532D01*
G01X653532Y1464264D02*
Y1456264D01*
X657532D01*
G01X669432Y1457330D02*
X670232Y1456664D01*
X671132Y1456264D01*
X671932D01*
X672732Y1456664D01*
X673332Y1457330D01*
X673632Y1458264D01*
X673432Y1459197D01*
X672932Y1459997D01*
X672032Y1460531D01*
X670832Y1460797D01*
X670132Y1461331D01*
X669832Y1462264D01*
X670032Y1463197D01*
X670532Y1463864D01*
X671232Y1464264D01*
X671932D01*
X672632Y1463997D01*
X673232Y1463331D01*
G01X678332Y1464264D02*
X680732D01*
G01X679532D02*
Y1456264D01*
G01X678332D02*
X680732D01*
G01X685632Y1464264D02*
X689432D01*
X685632Y1456264D01*
X689432D01*
G01X697532D02*
X693532D01*
Y1464264D01*
X697532D01*
G01X695932Y1460397D02*
X693532D01*
G01X710432Y1458931D02*
X712832D01*
G01X711532Y1460664D02*
Y1457197D01*
G01X727532Y1456264D02*
Y1464264D01*
X726332Y1462664D01*
G01Y1456264D02*
X728732D01*
G01X735532Y1464264D02*
X734732Y1463997D01*
X734132Y1463331D01*
X733732Y1462531D01*
X733432Y1461464D01*
X733332Y1460264D01*
X733432Y1459064D01*
X733732Y1457997D01*
X734132Y1457197D01*
X734732Y1456531D01*
X735532Y1456264D01*
X736332Y1456531D01*
X736932Y1457197D01*
X737332Y1457997D01*
X737632Y1459064D01*
X737732Y1460264D01*
X737632Y1461464D01*
X737332Y1462531D01*
X736932Y1463331D01*
X736332Y1463997D01*
X735532Y1464264D01*
G01X740932Y1456264D02*
Y1464264D01*
X743532Y1457597D01*
X746132Y1464264D01*
Y1456264D01*
G01X750332Y1464264D02*
X752732D01*
G01X751532D02*
Y1456264D01*
G01X750332D02*
X752732D01*
G01X757532Y1464264D02*
Y1456264D01*
X761532D01*
G01X-9868Y1565264D02*
X-7868D01*
Y1562864D01*
X-8468Y1562064D01*
X-9168Y1561531D01*
X-10168Y1561264D01*
X-11168Y1561531D01*
X-11868Y1562064D01*
X-12468Y1562864D01*
X-12868Y1563797D01*
X-13068Y1564864D01*
Y1565797D01*
X-12868Y1566597D01*
X-12468Y1567531D01*
X-11868Y1568331D01*
X-11268Y1568864D01*
X-10468Y1569264D01*
X-9768D01*
X-8968Y1568997D01*
X-8368Y1568464D01*
G01X-4468Y1561264D02*
Y1569264D01*
X-1968D01*
X-1168Y1568864D01*
X-668Y1568331D01*
X-468Y1567264D01*
X-668Y1566197D01*
X-1268Y1565531D01*
X-1968Y1565131D01*
X-4468D01*
G01X-1968D02*
X-468Y1561264D01*
G01X5532D02*
X4732Y1561397D01*
X4032Y1561931D01*
X3432Y1562731D01*
X3032Y1563664D01*
X2832Y1564731D01*
Y1565797D01*
X3032Y1566864D01*
X3432Y1567797D01*
X4032Y1568597D01*
X4732Y1569131D01*
X5532Y1569264D01*
X6332Y1569131D01*
X7032Y1568597D01*
X7632Y1567797D01*
X8032Y1566864D01*
X8232Y1565797D01*
Y1564731D01*
X8032Y1563664D01*
X7632Y1562731D01*
X7032Y1561931D01*
X6332Y1561397D01*
X5532Y1561264D01*
G01X11332Y1569264D02*
Y1563531D01*
X11732Y1562330D01*
X12532Y1561531D01*
X13532Y1561264D01*
X14532Y1561531D01*
X15332Y1562330D01*
X15732Y1563531D01*
Y1569264D01*
G01X19532Y1561264D02*
Y1569264D01*
X21932D01*
X22732Y1568864D01*
X23332Y1567931D01*
X23532Y1566864D01*
X23332Y1565797D01*
X22832Y1564997D01*
X21932Y1564597D01*
X19532D01*
G01X27432Y1562330D02*
X28232Y1561664D01*
X29132Y1561264D01*
X29932D01*
X30732Y1561664D01*
X31332Y1562330D01*
X31632Y1563264D01*
X31432Y1564197D01*
X30932Y1564997D01*
X30032Y1565531D01*
X28832Y1565797D01*
X28132Y1566331D01*
X27832Y1567264D01*
X28032Y1568197D01*
X28532Y1568864D01*
X29232Y1569264D01*
X29932D01*
X30632Y1568997D01*
X31232Y1568331D01*
G01X43032Y1561264D02*
X45532Y1569264D01*
X48032Y1561264D01*
G01X47132Y1564064D02*
X43932D01*
G01X59032Y1561264D02*
X61532Y1569264D01*
X64032Y1561264D01*
G01X63132Y1564064D02*
X59932D01*
G01X67232Y1561264D02*
Y1569264D01*
X71832Y1561264D01*
Y1569264D01*
G01X75332Y1561264D02*
Y1569264D01*
X77332D01*
X78132Y1568864D01*
X78732Y1568331D01*
X79232Y1567531D01*
X79632Y1566597D01*
X79732Y1565264D01*
X79632Y1563931D01*
X79232Y1562997D01*
X78732Y1562197D01*
X78132Y1561664D01*
X77332Y1561264D01*
X75332D01*
G01X94332Y1565531D02*
X94732Y1565931D01*
X95032Y1566597D01*
X95232Y1567531D01*
X95032Y1568331D01*
X94632Y1568864D01*
X93932Y1569264D01*
X91232D01*
Y1561264D01*
X94532D01*
X95232Y1561797D01*
X95632Y1562597D01*
X95832Y1563531D01*
X95632Y1564464D01*
X95032Y1565264D01*
X94332Y1565531D01*
X91232D01*
G01X101332Y1559797D02*
X101732Y1561531D01*
G01X109532Y1569264D02*
Y1561264D01*
G01X107232Y1569264D02*
X111832D01*
G01X115432Y1561264D02*
Y1569264D01*
G01X119632D02*
Y1561264D01*
G01Y1565264D02*
X115432D01*
G01X127532Y1561264D02*
X123532D01*
Y1569264D01*
X127532D01*
G01X125932Y1565397D02*
X123532D01*
G01X131232Y1561264D02*
Y1569264D01*
X135832Y1561264D01*
Y1569264D01*
G01X150132Y1565264D02*
X152132D01*
Y1562864D01*
X151532Y1562064D01*
X150832Y1561531D01*
X149832Y1561264D01*
X148832Y1561531D01*
X148132Y1562064D01*
X147532Y1562864D01*
X147132Y1563797D01*
X146932Y1564864D01*
Y1565797D01*
X147132Y1566597D01*
X147532Y1567531D01*
X148132Y1568331D01*
X148732Y1568864D01*
X149532Y1569264D01*
X150232D01*
X151032Y1568997D01*
X151632Y1568464D01*
G01X155532Y1561264D02*
Y1569264D01*
X158032D01*
X158832Y1568864D01*
X159332Y1568331D01*
X159532Y1567264D01*
X159332Y1566197D01*
X158732Y1565531D01*
X158032Y1565131D01*
X155532D01*
G01X158032D02*
X159532Y1561264D01*
G01X165532D02*
X164732Y1561397D01*
X164032Y1561931D01*
X163432Y1562731D01*
X163032Y1563664D01*
X162832Y1564731D01*
Y1565797D01*
X163032Y1566864D01*
X163432Y1567797D01*
X164032Y1568597D01*
X164732Y1569131D01*
X165532Y1569264D01*
X166332Y1569131D01*
X167032Y1568597D01*
X167632Y1567797D01*
X168032Y1566864D01*
X168232Y1565797D01*
Y1564731D01*
X168032Y1563664D01*
X167632Y1562731D01*
X167032Y1561931D01*
X166332Y1561397D01*
X165532Y1561264D01*
G01X171332Y1569264D02*
Y1563531D01*
X171732Y1562330D01*
X172532Y1561531D01*
X173532Y1561264D01*
X174532Y1561531D01*
X175332Y1562330D01*
X175732Y1563531D01*
Y1569264D01*
G01X179532Y1561264D02*
Y1569264D01*
X181932D01*
X182732Y1568864D01*
X183332Y1567931D01*
X183532Y1566864D01*
X183332Y1565797D01*
X182832Y1564997D01*
X181932Y1564597D01*
X179532D01*
G01X195032Y1561264D02*
X197532Y1569264D01*
X200032Y1561264D01*
G01X199132Y1564064D02*
X195932D01*
G01X215732Y1568597D02*
X215132Y1568997D01*
X214432Y1569264D01*
X213632D01*
X212732Y1568864D01*
X212032Y1568197D01*
X211532Y1567397D01*
X211132Y1566064D01*
X211032Y1564864D01*
X211232Y1563664D01*
X211532Y1562864D01*
X212132Y1562064D01*
X212832Y1561531D01*
X213532Y1561264D01*
X214232D01*
X214932Y1561531D01*
X215532Y1561931D01*
X216032Y1562464D01*
G01X219032Y1561264D02*
X221532Y1569264D01*
X224032Y1561264D01*
G01X223132Y1564064D02*
X219932D01*
G01X227232Y1561264D02*
Y1569264D01*
X231832Y1561264D01*
Y1569264D01*
G01X246332Y1565531D02*
X246732Y1565931D01*
X247032Y1566597D01*
X247232Y1567531D01*
X247032Y1568331D01*
X246632Y1568864D01*
X245932Y1569264D01*
X243232D01*
Y1561264D01*
X246532D01*
X247232Y1561797D01*
X247632Y1562597D01*
X247832Y1563531D01*
X247632Y1564464D01*
X247032Y1565264D01*
X246332Y1565531D01*
X243232D01*
G01X255532Y1561264D02*
X251532D01*
Y1569264D01*
X255532D01*
G01X253932Y1565397D02*
X251532D01*
G01X267532Y1561264D02*
Y1569264D01*
X269932D01*
X270732Y1568864D01*
X271332Y1567931D01*
X271532Y1566864D01*
X271332Y1565797D01*
X270832Y1564997D01*
X269932Y1564597D01*
X267532D01*
G01X275532Y1569264D02*
Y1561264D01*
X279532D01*
G01X283032D02*
X285532Y1569264D01*
X288032Y1561264D01*
G01X287132Y1564064D02*
X283932D01*
G01X295732Y1568597D02*
X295132Y1568997D01*
X294432Y1569264D01*
X293632D01*
X292732Y1568864D01*
X292032Y1568197D01*
X291532Y1567397D01*
X291132Y1566064D01*
X291032Y1564864D01*
X291232Y1563664D01*
X291532Y1562864D01*
X292132Y1562064D01*
X292832Y1561531D01*
X293532Y1561264D01*
X294232D01*
X294932Y1561531D01*
X295532Y1561931D01*
X296032Y1562464D01*
G01X303532Y1561264D02*
X299532D01*
Y1569264D01*
X303532D01*
G01X301932Y1565397D02*
X299532D01*
G01X307332Y1561264D02*
Y1569264D01*
X309332D01*
X310132Y1568864D01*
X310732Y1568331D01*
X311232Y1567531D01*
X311632Y1566597D01*
X311732Y1565264D01*
X311632Y1563931D01*
X311232Y1562997D01*
X310732Y1562197D01*
X310132Y1561664D01*
X309332Y1561264D01*
X307332D01*
G01X323432Y1562330D02*
X324232Y1561664D01*
X325132Y1561264D01*
X325932D01*
X326732Y1561664D01*
X327332Y1562330D01*
X327632Y1563264D01*
X327432Y1564197D01*
X326932Y1564997D01*
X326032Y1565531D01*
X324832Y1565797D01*
X324132Y1566331D01*
X323832Y1567264D01*
X324032Y1568197D01*
X324532Y1568864D01*
X325232Y1569264D01*
X325932D01*
X326632Y1568997D01*
X327232Y1568331D01*
G01X335532Y1561264D02*
X331532D01*
Y1569264D01*
X335532D01*
G01X333932Y1565397D02*
X331532D01*
G01X339532Y1561264D02*
Y1569264D01*
X341932D01*
X342732Y1568864D01*
X343332Y1567931D01*
X343532Y1566864D01*
X343332Y1565797D01*
X342832Y1564997D01*
X341932Y1564597D01*
X339532D01*
G01X347032Y1561264D02*
X349532Y1569264D01*
X352032Y1561264D01*
G01X351132Y1564064D02*
X347932D01*
G01X355532Y1561264D02*
Y1569264D01*
X358032D01*
X358832Y1568864D01*
X359332Y1568331D01*
X359532Y1567264D01*
X359332Y1566197D01*
X358732Y1565531D01*
X358032Y1565131D01*
X355532D01*
G01X358032D02*
X359532Y1561264D01*
G01X363032D02*
X365532Y1569264D01*
X368032Y1561264D01*
G01X367132Y1564064D02*
X363932D01*
G01X373532Y1569264D02*
Y1561264D01*
G01X371232Y1569264D02*
X375832D01*
G01X383532Y1561264D02*
X379532D01*
Y1569264D01*
X383532D01*
G01X381932Y1565397D02*
X379532D01*
G01X387532Y1569264D02*
Y1561264D01*
X391532D01*
G01X397532D02*
Y1564864D01*
X395532Y1569264D01*
G01X399532D02*
X397532Y1564864D01*
G01X411632Y1561264D02*
Y1569264D01*
X415432D01*
G01X414032Y1565397D02*
X411632D01*
G01X419532Y1561264D02*
Y1569264D01*
X422032D01*
X422832Y1568864D01*
X423332Y1568331D01*
X423532Y1567264D01*
X423332Y1566197D01*
X422732Y1565531D01*
X422032Y1565131D01*
X419532D01*
G01X422032D02*
X423532Y1561264D01*
G01X429532D02*
X428732Y1561397D01*
X428032Y1561931D01*
X427432Y1562731D01*
X427032Y1563664D01*
X426832Y1564731D01*
Y1565797D01*
X427032Y1566864D01*
X427432Y1567797D01*
X428032Y1568597D01*
X428732Y1569131D01*
X429532Y1569264D01*
X430332Y1569131D01*
X431032Y1568597D01*
X431632Y1567797D01*
X432032Y1566864D01*
X432232Y1565797D01*
Y1564731D01*
X432032Y1563664D01*
X431632Y1562731D01*
X431032Y1561931D01*
X430332Y1561397D01*
X429532Y1561264D01*
G01X434932D02*
Y1569264D01*
X437532Y1562597D01*
X440132Y1569264D01*
Y1561264D01*
G01X454132Y1565264D02*
X456132D01*
Y1562864D01*
X455532Y1562064D01*
X454832Y1561531D01*
X453832Y1561264D01*
X452832Y1561531D01*
X452132Y1562064D01*
X451532Y1562864D01*
X451132Y1563797D01*
X450932Y1564864D01*
Y1565797D01*
X451132Y1566597D01*
X451532Y1567531D01*
X452132Y1568331D01*
X452732Y1568864D01*
X453532Y1569264D01*
X454232D01*
X455032Y1568997D01*
X455632Y1568464D01*
G01X459532Y1561264D02*
Y1569264D01*
X462032D01*
X462832Y1568864D01*
X463332Y1568331D01*
X463532Y1567264D01*
X463332Y1566197D01*
X462732Y1565531D01*
X462032Y1565131D01*
X459532D01*
G01X462032D02*
X463532Y1561264D01*
G01X469532D02*
X468732Y1561397D01*
X468032Y1561931D01*
X467432Y1562731D01*
X467032Y1563664D01*
X466832Y1564731D01*
Y1565797D01*
X467032Y1566864D01*
X467432Y1567797D01*
X468032Y1568597D01*
X468732Y1569131D01*
X469532Y1569264D01*
X470332Y1569131D01*
X471032Y1568597D01*
X471632Y1567797D01*
X472032Y1566864D01*
X472232Y1565797D01*
Y1564731D01*
X472032Y1563664D01*
X471632Y1562731D01*
X471032Y1561931D01*
X470332Y1561397D01*
X469532Y1561264D01*
G01X475332Y1569264D02*
Y1563531D01*
X475732Y1562330D01*
X476532Y1561531D01*
X477532Y1561264D01*
X478532Y1561531D01*
X479332Y1562330D01*
X479732Y1563531D01*
Y1569264D01*
G01X483532Y1561264D02*
Y1569264D01*
X485932D01*
X486732Y1568864D01*
X487332Y1567931D01*
X487532Y1566864D01*
X487332Y1565797D01*
X486832Y1564997D01*
X485932Y1564597D01*
X483532D01*
G01X502332Y1565531D02*
X502732Y1565931D01*
X503032Y1566597D01*
X503232Y1567531D01*
X503032Y1568331D01*
X502632Y1568864D01*
X501932Y1569264D01*
X499232D01*
Y1561264D01*
X502532D01*
X503232Y1561797D01*
X503632Y1562597D01*
X503832Y1563531D01*
X503632Y1564464D01*
X503032Y1565264D01*
X502332Y1565531D01*
X499232D01*
G01X509532Y1560997D02*
X509332Y1561131D01*
Y1561397D01*
X509532Y1561531D01*
X509732Y1561397D01*
Y1561131D01*
X509532Y1560997D01*
G01X-10468Y1584264D02*
Y1576264D01*
G01X-12768Y1584264D02*
X-8168D01*
G01X-2468Y1576264D02*
X-3268Y1576397D01*
X-3968Y1576931D01*
X-4568Y1577731D01*
X-4968Y1578664D01*
X-5168Y1579731D01*
Y1580797D01*
X-4968Y1581864D01*
X-4568Y1582797D01*
X-3968Y1583597D01*
X-3268Y1584131D01*
X-2468Y1584264D01*
X-1668Y1584131D01*
X-968Y1583597D01*
X-368Y1582797D01*
X32Y1581864D01*
X232Y1580797D01*
Y1579731D01*
X32Y1578664D01*
X-368Y1577731D01*
X-968Y1576931D01*
X-1668Y1576397D01*
X-2468Y1576264D01*
G01X13532Y1584264D02*
Y1576264D01*
G01X11232Y1584264D02*
X15832D01*
G01X19432Y1576264D02*
Y1584264D01*
G01X23632D02*
Y1576264D01*
G01Y1580264D02*
X19432D01*
G01X31532Y1576264D02*
X27532D01*
Y1584264D01*
X31532D01*
G01X29932Y1580397D02*
X27532D01*
G01X46332Y1580531D02*
X46732Y1580931D01*
X47032Y1581597D01*
X47232Y1582531D01*
X47032Y1583331D01*
X46632Y1583864D01*
X45932Y1584264D01*
X43232D01*
Y1576264D01*
X46532D01*
X47232Y1576797D01*
X47632Y1577597D01*
X47832Y1578531D01*
X47632Y1579464D01*
X47032Y1580264D01*
X46332Y1580531D01*
X43232D01*
G01X53532Y1576264D02*
X52732Y1576397D01*
X52032Y1576931D01*
X51432Y1577731D01*
X51032Y1578664D01*
X50832Y1579731D01*
Y1580797D01*
X51032Y1581864D01*
X51432Y1582797D01*
X52032Y1583597D01*
X52732Y1584131D01*
X53532Y1584264D01*
X54332Y1584131D01*
X55032Y1583597D01*
X55632Y1582797D01*
X56032Y1581864D01*
X56232Y1580797D01*
Y1579731D01*
X56032Y1578664D01*
X55632Y1577731D01*
X55032Y1576931D01*
X54332Y1576397D01*
X53532Y1576264D01*
G01X59032D02*
X61532Y1584264D01*
X64032Y1576264D01*
G01X63132Y1579064D02*
X59932D01*
G01X67532Y1576264D02*
Y1584264D01*
X70032D01*
X70832Y1583864D01*
X71332Y1583331D01*
X71532Y1582264D01*
X71332Y1581197D01*
X70732Y1580531D01*
X70032Y1580131D01*
X67532D01*
G01X70032D02*
X71532Y1576264D01*
G01X75332D02*
Y1584264D01*
X77332D01*
X78132Y1583864D01*
X78732Y1583331D01*
X79232Y1582531D01*
X79632Y1581597D01*
X79732Y1580264D01*
X79632Y1578931D01*
X79232Y1577997D01*
X78732Y1577197D01*
X78132Y1576664D01*
X77332Y1576264D01*
X75332D01*
G01X95732Y1583597D02*
X95132Y1583997D01*
X94432Y1584264D01*
X93632D01*
X92732Y1583864D01*
X92032Y1583197D01*
X91532Y1582397D01*
X91132Y1581064D01*
X91032Y1579864D01*
X91232Y1578664D01*
X91532Y1577864D01*
X92132Y1577064D01*
X92832Y1576531D01*
X93532Y1576264D01*
X94232D01*
X94932Y1576531D01*
X95532Y1576931D01*
X96032Y1577464D01*
G01X101532Y1576264D02*
X100732Y1576397D01*
X100032Y1576931D01*
X99432Y1577731D01*
X99032Y1578664D01*
X98832Y1579731D01*
Y1580797D01*
X99032Y1581864D01*
X99432Y1582797D01*
X100032Y1583597D01*
X100732Y1584131D01*
X101532Y1584264D01*
X102332Y1584131D01*
X103032Y1583597D01*
X103632Y1582797D01*
X104032Y1581864D01*
X104232Y1580797D01*
Y1579731D01*
X104032Y1578664D01*
X103632Y1577731D01*
X103032Y1576931D01*
X102332Y1576397D01*
X101532Y1576264D01*
G01X107332Y1584264D02*
Y1578531D01*
X107732Y1577330D01*
X108532Y1576531D01*
X109532Y1576264D01*
X110532Y1576531D01*
X111332Y1577330D01*
X111732Y1578531D01*
Y1584264D01*
G01X115532Y1576264D02*
Y1584264D01*
X117932D01*
X118732Y1583864D01*
X119332Y1582931D01*
X119532Y1581864D01*
X119332Y1580797D01*
X118832Y1579997D01*
X117932Y1579597D01*
X115532D01*
G01X125532Y1576264D02*
X124732Y1576397D01*
X124032Y1576931D01*
X123432Y1577731D01*
X123032Y1578664D01*
X122832Y1579731D01*
Y1580797D01*
X123032Y1581864D01*
X123432Y1582797D01*
X124032Y1583597D01*
X124732Y1584131D01*
X125532Y1584264D01*
X126332Y1584131D01*
X127032Y1583597D01*
X127632Y1582797D01*
X128032Y1581864D01*
X128232Y1580797D01*
Y1579731D01*
X128032Y1578664D01*
X127632Y1577731D01*
X127032Y1576931D01*
X126332Y1576397D01*
X125532Y1576264D01*
G01X131232D02*
Y1584264D01*
X135832Y1576264D01*
Y1584264D01*
G01X139432Y1577330D02*
X140232Y1576664D01*
X141132Y1576264D01*
X141932D01*
X142732Y1576664D01*
X143332Y1577330D01*
X143632Y1578264D01*
X143432Y1579197D01*
X142932Y1579997D01*
X142032Y1580531D01*
X140832Y1580797D01*
X140132Y1581331D01*
X139832Y1582264D01*
X140032Y1583197D01*
X140532Y1583864D01*
X141232Y1584264D01*
X141932D01*
X142632Y1583997D01*
X143232Y1583331D01*
G01X149532Y1575997D02*
X149332Y1576131D01*
Y1576397D01*
X149532Y1576531D01*
X149732Y1576397D01*
Y1576131D01*
X149532Y1575997D01*
G01X156332Y1584264D02*
X158732D01*
G01X157532D02*
Y1576264D01*
G01X156332D02*
X158732D01*
G01X163632D02*
Y1584264D01*
X167432D01*
G01X166032Y1580397D02*
X163632D01*
G01X180332Y1584264D02*
X182732D01*
G01X181532D02*
Y1576264D01*
G01X180332D02*
X182732D01*
G01X189532Y1584264D02*
Y1576264D01*
G01X187232Y1584264D02*
X191832D01*
G01X204332D02*
X206732D01*
G01X205532D02*
Y1576264D01*
G01X204332D02*
X206732D01*
G01X211432Y1577330D02*
X212232Y1576664D01*
X213132Y1576264D01*
X213932D01*
X214732Y1576664D01*
X215332Y1577330D01*
X215632Y1578264D01*
X215432Y1579197D01*
X214932Y1579997D01*
X214032Y1580531D01*
X212832Y1580797D01*
X212132Y1581331D01*
X211832Y1582264D01*
X212032Y1583197D01*
X212532Y1583864D01*
X213232Y1584264D01*
X213932D01*
X214632Y1583997D01*
X215232Y1583331D01*
G01X227232Y1576264D02*
Y1584264D01*
X231832Y1576264D01*
Y1584264D01*
G01X237532Y1576264D02*
X236732Y1576397D01*
X236032Y1576931D01*
X235432Y1577731D01*
X235032Y1578664D01*
X234832Y1579731D01*
Y1580797D01*
X235032Y1581864D01*
X235432Y1582797D01*
X236032Y1583597D01*
X236732Y1584131D01*
X237532Y1584264D01*
X238332Y1584131D01*
X239032Y1583597D01*
X239632Y1582797D01*
X240032Y1581864D01*
X240232Y1580797D01*
Y1579731D01*
X240032Y1578664D01*
X239632Y1577731D01*
X239032Y1576931D01*
X238332Y1576397D01*
X237532Y1576264D01*
G01X245532Y1584264D02*
Y1576264D01*
G01X243232Y1584264D02*
X247832D01*
G01X259532Y1576264D02*
Y1584264D01*
X261932D01*
X262732Y1583864D01*
X263332Y1582931D01*
X263532Y1581864D01*
X263332Y1580797D01*
X262832Y1579997D01*
X261932Y1579597D01*
X259532D01*
G01X269532Y1576264D02*
X268732Y1576397D01*
X268032Y1576931D01*
X267432Y1577731D01*
X267032Y1578664D01*
X266832Y1579731D01*
Y1580797D01*
X267032Y1581864D01*
X267432Y1582797D01*
X268032Y1583597D01*
X268732Y1584131D01*
X269532Y1584264D01*
X270332Y1584131D01*
X271032Y1583597D01*
X271632Y1582797D01*
X272032Y1581864D01*
X272232Y1580797D01*
Y1579731D01*
X272032Y1578664D01*
X271632Y1577731D01*
X271032Y1576931D01*
X270332Y1576397D01*
X269532Y1576264D01*
G01X275432Y1577330D02*
X276232Y1576664D01*
X277132Y1576264D01*
X277932D01*
X278732Y1576664D01*
X279332Y1577330D01*
X279632Y1578264D01*
X279432Y1579197D01*
X278932Y1579997D01*
X278032Y1580531D01*
X276832Y1580797D01*
X276132Y1581331D01*
X275832Y1582264D01*
X276032Y1583197D01*
X276532Y1583864D01*
X277232Y1584264D01*
X277932D01*
X278632Y1583997D01*
X279232Y1583331D01*
G01X283432Y1577330D02*
X284232Y1576664D01*
X285132Y1576264D01*
X285932D01*
X286732Y1576664D01*
X287332Y1577330D01*
X287632Y1578264D01*
X287432Y1579197D01*
X286932Y1579997D01*
X286032Y1580531D01*
X284832Y1580797D01*
X284132Y1581331D01*
X283832Y1582264D01*
X284032Y1583197D01*
X284532Y1583864D01*
X285232Y1584264D01*
X285932D01*
X286632Y1583997D01*
X287232Y1583331D01*
G01X292332Y1584264D02*
X294732D01*
G01X293532D02*
Y1576264D01*
G01X292332D02*
X294732D01*
G01X302332Y1580531D02*
X302732Y1580931D01*
X303032Y1581597D01*
X303232Y1582531D01*
X303032Y1583331D01*
X302632Y1583864D01*
X301932Y1584264D01*
X299232D01*
Y1576264D01*
X302532D01*
X303232Y1576797D01*
X303632Y1577597D01*
X303832Y1578531D01*
X303632Y1579464D01*
X303032Y1580264D01*
X302332Y1580531D01*
X299232D01*
G01X307532Y1584264D02*
Y1576264D01*
X311532D01*
G01X319532D02*
X315532D01*
Y1584264D01*
X319532D01*
G01X317932Y1580397D02*
X315532D01*
G01X333532Y1584264D02*
Y1576264D01*
G01X331232Y1584264D02*
X335832D01*
G01X341532Y1576264D02*
X340732Y1576397D01*
X340032Y1576931D01*
X339432Y1577731D01*
X339032Y1578664D01*
X338832Y1579731D01*
Y1580797D01*
X339032Y1581864D01*
X339432Y1582797D01*
X340032Y1583597D01*
X340732Y1584131D01*
X341532Y1584264D01*
X342332Y1584131D01*
X343032Y1583597D01*
X343632Y1582797D01*
X344032Y1581864D01*
X344232Y1580797D01*
Y1579731D01*
X344032Y1578664D01*
X343632Y1577731D01*
X343032Y1576931D01*
X342332Y1576397D01*
X341532Y1576264D01*
G01X355632D02*
Y1584264D01*
X359432D01*
G01X358032Y1580397D02*
X355632D01*
G01X364332Y1584264D02*
X366732D01*
G01X365532D02*
Y1576264D01*
G01X364332D02*
X366732D01*
G01X373532Y1584264D02*
Y1576264D01*
G01X371232Y1584264D02*
X375832D01*
G01X388332D02*
X390732D01*
G01X389532D02*
Y1576264D01*
G01X388332D02*
X390732D01*
G01X395232D02*
Y1584264D01*
X399832Y1576264D01*
Y1584264D01*
G01X413532D02*
Y1576264D01*
G01X411232Y1584264D02*
X415832D01*
G01X419432Y1576264D02*
Y1584264D01*
G01X423632D02*
Y1576264D01*
G01Y1580264D02*
X419432D01*
G01X431532Y1576264D02*
X427532D01*
Y1584264D01*
X431532D01*
G01X429932Y1580397D02*
X427532D01*
G01X443532Y1584264D02*
Y1576264D01*
X447532D01*
G01X453532D02*
X452732Y1576397D01*
X452032Y1576931D01*
X451432Y1577731D01*
X451032Y1578664D01*
X450832Y1579731D01*
Y1580797D01*
X451032Y1581864D01*
X451432Y1582797D01*
X452032Y1583597D01*
X452732Y1584131D01*
X453532Y1584264D01*
X454332Y1584131D01*
X455032Y1583597D01*
X455632Y1582797D01*
X456032Y1581864D01*
X456232Y1580797D01*
Y1579731D01*
X456032Y1578664D01*
X455632Y1577731D01*
X455032Y1576931D01*
X454332Y1576397D01*
X453532Y1576264D01*
G01X463732Y1583597D02*
X463132Y1583997D01*
X462432Y1584264D01*
X461632D01*
X460732Y1583864D01*
X460032Y1583197D01*
X459532Y1582397D01*
X459132Y1581064D01*
X459032Y1579864D01*
X459232Y1578664D01*
X459532Y1577864D01*
X460132Y1577064D01*
X460832Y1576531D01*
X461532Y1576264D01*
X462232D01*
X462932Y1576531D01*
X463532Y1576931D01*
X464032Y1577464D01*
G01X467032Y1576264D02*
X469532Y1584264D01*
X472032Y1576264D01*
G01X471132Y1579064D02*
X467932D01*
G01X477532Y1584264D02*
Y1576264D01*
G01X475232Y1584264D02*
X479832D01*
G01X484332D02*
X486732D01*
G01X485532D02*
Y1576264D01*
G01X484332D02*
X486732D01*
G01X493532D02*
X492732Y1576397D01*
X492032Y1576931D01*
X491432Y1577731D01*
X491032Y1578664D01*
X490832Y1579731D01*
Y1580797D01*
X491032Y1581864D01*
X491432Y1582797D01*
X492032Y1583597D01*
X492732Y1584131D01*
X493532Y1584264D01*
X494332Y1584131D01*
X495032Y1583597D01*
X495632Y1582797D01*
X496032Y1581864D01*
X496232Y1580797D01*
Y1579731D01*
X496032Y1578664D01*
X495632Y1577731D01*
X495032Y1576931D01*
X494332Y1576397D01*
X493532Y1576264D01*
G01X499232D02*
Y1584264D01*
X503832Y1576264D01*
Y1584264D01*
G01X507432Y1577330D02*
X508232Y1576664D01*
X509132Y1576264D01*
X509932D01*
X510732Y1576664D01*
X511332Y1577330D01*
X511632Y1578264D01*
X511432Y1579197D01*
X510932Y1579997D01*
X510032Y1580531D01*
X508832Y1580797D01*
X508132Y1581331D01*
X507832Y1582264D01*
X508032Y1583197D01*
X508532Y1583864D01*
X509232Y1584264D01*
X509932D01*
X510632Y1583997D01*
X511232Y1583331D01*
G01X523632Y1576264D02*
Y1584264D01*
X527432D01*
G01X526032Y1580397D02*
X523632D01*
G01X533532Y1576264D02*
X532732Y1576397D01*
X532032Y1576931D01*
X531432Y1577731D01*
X531032Y1578664D01*
X530832Y1579731D01*
Y1580797D01*
X531032Y1581864D01*
X531432Y1582797D01*
X532032Y1583597D01*
X532732Y1584131D01*
X533532Y1584264D01*
X534332Y1584131D01*
X535032Y1583597D01*
X535632Y1582797D01*
X536032Y1581864D01*
X536232Y1580797D01*
Y1579731D01*
X536032Y1578664D01*
X535632Y1577731D01*
X535032Y1576931D01*
X534332Y1576397D01*
X533532Y1576264D01*
G01X539532D02*
Y1584264D01*
X542032D01*
X542832Y1583864D01*
X543332Y1583331D01*
X543532Y1582264D01*
X543332Y1581197D01*
X542732Y1580531D01*
X542032Y1580131D01*
X539532D01*
G01X542032D02*
X543532Y1576264D01*
G01X558332Y1580531D02*
X558732Y1580931D01*
X559032Y1581597D01*
X559232Y1582531D01*
X559032Y1583331D01*
X558632Y1583864D01*
X557932Y1584264D01*
X555232D01*
Y1576264D01*
X558532D01*
X559232Y1576797D01*
X559632Y1577597D01*
X559832Y1578531D01*
X559632Y1579464D01*
X559032Y1580264D01*
X558332Y1580531D01*
X555232D01*
G01X565532Y1576264D02*
X564732Y1576397D01*
X564032Y1576931D01*
X563432Y1577731D01*
X563032Y1578664D01*
X562832Y1579731D01*
Y1580797D01*
X563032Y1581864D01*
X563432Y1582797D01*
X564032Y1583597D01*
X564732Y1584131D01*
X565532Y1584264D01*
X566332Y1584131D01*
X567032Y1583597D01*
X567632Y1582797D01*
X568032Y1581864D01*
X568232Y1580797D01*
Y1579731D01*
X568032Y1578664D01*
X567632Y1577731D01*
X567032Y1576931D01*
X566332Y1576397D01*
X565532Y1576264D01*
G01X573532Y1584264D02*
Y1576264D01*
G01X571232Y1584264D02*
X575832D01*
G01X579432Y1576264D02*
Y1584264D01*
G01X583632D02*
Y1576264D01*
G01Y1580264D02*
X579432D01*
G01X-12468Y1591264D02*
Y1599264D01*
X-10068D01*
X-9268Y1598864D01*
X-8668Y1597931D01*
X-8468Y1596864D01*
X-8668Y1595797D01*
X-9168Y1594997D01*
X-10068Y1594597D01*
X-12468D01*
G01X-4468Y1599264D02*
Y1591264D01*
X-468D01*
G01X7532D02*
X3532D01*
Y1599264D01*
X7532D01*
G01X5932Y1595397D02*
X3532D01*
G01X11032Y1591264D02*
X13532Y1599264D01*
X16032Y1591264D01*
G01X15132Y1594064D02*
X11932D01*
G01X19432Y1592330D02*
X20232Y1591664D01*
X21132Y1591264D01*
X21932D01*
X22732Y1591664D01*
X23332Y1592330D01*
X23632Y1593264D01*
X23432Y1594197D01*
X22932Y1594997D01*
X22032Y1595531D01*
X20832Y1595797D01*
X20132Y1596331D01*
X19832Y1597264D01*
X20032Y1598197D01*
X20532Y1598864D01*
X21232Y1599264D01*
X21932D01*
X22632Y1598997D01*
X23232Y1598331D01*
G01X31532Y1591264D02*
X27532D01*
Y1599264D01*
X31532D01*
G01X29932Y1595397D02*
X27532D01*
G01X43632Y1591264D02*
Y1599264D01*
X47432D01*
G01X46032Y1595397D02*
X43632D01*
G01X53532Y1591264D02*
X52732Y1591397D01*
X52032Y1591931D01*
X51432Y1592731D01*
X51032Y1593664D01*
X50832Y1594731D01*
Y1595797D01*
X51032Y1596864D01*
X51432Y1597797D01*
X52032Y1598597D01*
X52732Y1599131D01*
X53532Y1599264D01*
X54332Y1599131D01*
X55032Y1598597D01*
X55632Y1597797D01*
X56032Y1596864D01*
X56232Y1595797D01*
Y1594731D01*
X56032Y1593664D01*
X55632Y1592731D01*
X55032Y1591931D01*
X54332Y1591397D01*
X53532Y1591264D01*
G01X59532Y1599264D02*
Y1591264D01*
X63532D01*
G01X67532Y1599264D02*
Y1591264D01*
X71532D01*
G01X77532D02*
X76732Y1591397D01*
X76032Y1591931D01*
X75432Y1592731D01*
X75032Y1593664D01*
X74832Y1594731D01*
Y1595797D01*
X75032Y1596864D01*
X75432Y1597797D01*
X76032Y1598597D01*
X76732Y1599131D01*
X77532Y1599264D01*
X78332Y1599131D01*
X79032Y1598597D01*
X79632Y1597797D01*
X80032Y1596864D01*
X80232Y1595797D01*
Y1594731D01*
X80032Y1593664D01*
X79632Y1592731D01*
X79032Y1591931D01*
X78332Y1591397D01*
X77532Y1591264D01*
G01X82532Y1599264D02*
X83932Y1591264D01*
X85532Y1599264D01*
X87132Y1591264D01*
X88532Y1599264D01*
G01X101532D02*
Y1591264D01*
G01X99232Y1599264D02*
X103832D01*
G01X107432Y1591264D02*
Y1599264D01*
G01X111632D02*
Y1591264D01*
G01Y1595264D02*
X107432D01*
G01X119532Y1591264D02*
X115532D01*
Y1599264D01*
X119532D01*
G01X117932Y1595397D02*
X115532D01*
G01X131432Y1592330D02*
X132232Y1591664D01*
X133132Y1591264D01*
X133932D01*
X134732Y1591664D01*
X135332Y1592330D01*
X135632Y1593264D01*
X135432Y1594197D01*
X134932Y1594997D01*
X134032Y1595531D01*
X132832Y1595797D01*
X132132Y1596331D01*
X131832Y1597264D01*
X132032Y1598197D01*
X132532Y1598864D01*
X133232Y1599264D01*
X133932D01*
X134632Y1598997D01*
X135232Y1598331D01*
G01X139532Y1599264D02*
Y1591264D01*
X143532D01*
G01X148332Y1599264D02*
X150732D01*
G01X149532D02*
Y1591264D01*
G01X148332D02*
X150732D01*
G01X155332D02*
Y1599264D01*
X157332D01*
X158132Y1598864D01*
X158732Y1598331D01*
X159232Y1597531D01*
X159632Y1596597D01*
X159732Y1595264D01*
X159632Y1593931D01*
X159232Y1592997D01*
X158732Y1592197D01*
X158132Y1591664D01*
X157332Y1591264D01*
X155332D01*
G01X167532D02*
X163532D01*
Y1599264D01*
X167532D01*
G01X165932Y1595397D02*
X163532D01*
G01X171432Y1592330D02*
X172232Y1591664D01*
X173132Y1591264D01*
X173932D01*
X174732Y1591664D01*
X175332Y1592330D01*
X175632Y1593264D01*
X175432Y1594197D01*
X174932Y1594997D01*
X174032Y1595531D01*
X172832Y1595797D01*
X172132Y1596331D01*
X171832Y1597264D01*
X172032Y1598197D01*
X172532Y1598864D01*
X173232Y1599264D01*
X173932D01*
X174632Y1598997D01*
X175232Y1598331D01*
G01X189532Y1599264D02*
Y1591264D01*
G01X187232Y1599264D02*
X191832D01*
G01X197532Y1591264D02*
X196732Y1591397D01*
X196032Y1591931D01*
X195432Y1592731D01*
X195032Y1593664D01*
X194832Y1594731D01*
Y1595797D01*
X195032Y1596864D01*
X195432Y1597797D01*
X196032Y1598597D01*
X196732Y1599131D01*
X197532Y1599264D01*
X198332Y1599131D01*
X199032Y1598597D01*
X199632Y1597797D01*
X200032Y1596864D01*
X200232Y1595797D01*
Y1594731D01*
X200032Y1593664D01*
X199632Y1592731D01*
X199032Y1591931D01*
X198332Y1591397D01*
X197532Y1591264D01*
G01X214132Y1595264D02*
X216132D01*
Y1592864D01*
X215532Y1592064D01*
X214832Y1591531D01*
X213832Y1591264D01*
X212832Y1591531D01*
X212132Y1592064D01*
X211532Y1592864D01*
X211132Y1593797D01*
X210932Y1594864D01*
Y1595797D01*
X211132Y1596597D01*
X211532Y1597531D01*
X212132Y1598331D01*
X212732Y1598864D01*
X213532Y1599264D01*
X214232D01*
X215032Y1598997D01*
X215632Y1598464D01*
G01X223532Y1591264D02*
X219532D01*
Y1599264D01*
X223532D01*
G01X221932Y1595397D02*
X219532D01*
G01X227232Y1591264D02*
Y1599264D01*
X231832Y1591264D01*
Y1599264D01*
G01X239532Y1591264D02*
X235532D01*
Y1599264D01*
X239532D01*
G01X237932Y1595397D02*
X235532D01*
G01X243532Y1591264D02*
Y1599264D01*
X246032D01*
X246832Y1598864D01*
X247332Y1598331D01*
X247532Y1597264D01*
X247332Y1596197D01*
X246732Y1595531D01*
X246032Y1595131D01*
X243532D01*
G01X246032D02*
X247532Y1591264D01*
G01X251032D02*
X253532Y1599264D01*
X256032Y1591264D01*
G01X255132Y1594064D02*
X251932D01*
G01X261532Y1599264D02*
Y1591264D01*
G01X259232Y1599264D02*
X263832D01*
G01X271532Y1591264D02*
X267532D01*
Y1599264D01*
X271532D01*
G01X269932Y1595397D02*
X267532D01*
G01X285532Y1599264D02*
Y1591264D01*
G01X283232Y1599264D02*
X287832D01*
G01X291432Y1591264D02*
Y1599264D01*
G01X295632D02*
Y1591264D01*
G01Y1595264D02*
X291432D01*
G01X303532Y1591264D02*
X299532D01*
Y1599264D01*
X303532D01*
G01X301932Y1595397D02*
X299532D01*
G01X315532Y1591264D02*
Y1599264D01*
X317932D01*
X318732Y1598864D01*
X319332Y1597931D01*
X319532Y1596864D01*
X319332Y1595797D01*
X318832Y1594997D01*
X317932Y1594597D01*
X315532D01*
G01X323032Y1591264D02*
X325532Y1599264D01*
X328032Y1591264D01*
G01X327132Y1594064D02*
X323932D01*
G01X331332Y1591264D02*
Y1599264D01*
X333332D01*
X334132Y1598864D01*
X334732Y1598331D01*
X335232Y1597531D01*
X335632Y1596597D01*
X335732Y1595264D01*
X335632Y1593931D01*
X335232Y1592997D01*
X334732Y1592197D01*
X334132Y1591664D01*
X333332Y1591264D01*
X331332D01*
G01X339432Y1592330D02*
X340232Y1591664D01*
X341132Y1591264D01*
X341932D01*
X342732Y1591664D01*
X343332Y1592330D01*
X343632Y1593264D01*
X343432Y1594197D01*
X342932Y1594997D01*
X342032Y1595531D01*
X340832Y1595797D01*
X340132Y1596331D01*
X339832Y1597264D01*
X340032Y1598197D01*
X340532Y1598864D01*
X341232Y1599264D01*
X341932D01*
X342632Y1598997D01*
X343232Y1598331D01*
G01X355032Y1591264D02*
X357532Y1599264D01*
X360032Y1591264D01*
G01X359132Y1594064D02*
X355932D01*
G01X363232Y1591264D02*
Y1599264D01*
X367832Y1591264D01*
Y1599264D01*
G01X371332Y1591264D02*
Y1599264D01*
X373332D01*
X374132Y1598864D01*
X374732Y1598331D01*
X375232Y1597531D01*
X375632Y1596597D01*
X375732Y1595264D01*
X375632Y1593931D01*
X375232Y1592997D01*
X374732Y1592197D01*
X374132Y1591664D01*
X373332Y1591264D01*
X371332D01*
G01X386932D02*
Y1599264D01*
X389532Y1592597D01*
X392132Y1599264D01*
Y1591264D01*
G01X395032D02*
X397532Y1599264D01*
X400032Y1591264D01*
G01X399132Y1594064D02*
X395932D01*
G01X403432Y1592330D02*
X404232Y1591664D01*
X405132Y1591264D01*
X405932D01*
X406732Y1591664D01*
X407332Y1592330D01*
X407632Y1593264D01*
X407432Y1594197D01*
X406932Y1594997D01*
X406032Y1595531D01*
X404832Y1595797D01*
X404132Y1596331D01*
X403832Y1597264D01*
X404032Y1598197D01*
X404532Y1598864D01*
X405232Y1599264D01*
X405932D01*
X406632Y1598997D01*
X407232Y1598331D01*
G01X411332Y1591264D02*
Y1599264D01*
G01X415132D02*
X411332Y1594330D01*
G01X415732Y1591264D02*
X413032Y1596597D01*
G01X427032Y1591264D02*
X429532Y1599264D01*
X432032Y1591264D01*
G01X431132Y1594064D02*
X427932D01*
G01X435232Y1591264D02*
Y1599264D01*
X439832Y1591264D01*
Y1599264D01*
G01X443332Y1591264D02*
Y1599264D01*
X445332D01*
X446132Y1598864D01*
X446732Y1598331D01*
X447232Y1597531D01*
X447632Y1596597D01*
X447732Y1595264D01*
X447632Y1593931D01*
X447232Y1592997D01*
X446732Y1592197D01*
X446132Y1591664D01*
X445332Y1591264D01*
X443332D01*
G01X459032D02*
X461532Y1599264D01*
X464032Y1591264D01*
G01X463132Y1594064D02*
X459932D01*
G01X467332Y1591264D02*
Y1599264D01*
X469332D01*
X470132Y1598864D01*
X470732Y1598331D01*
X471232Y1597531D01*
X471632Y1596597D01*
X471732Y1595264D01*
X471632Y1593931D01*
X471232Y1592997D01*
X470732Y1592197D01*
X470132Y1591664D01*
X469332Y1591264D01*
X467332D01*
G01X475332D02*
Y1599264D01*
X477332D01*
X478132Y1598864D01*
X478732Y1598331D01*
X479232Y1597531D01*
X479632Y1596597D01*
X479732Y1595264D01*
X479632Y1593931D01*
X479232Y1592997D01*
X478732Y1592197D01*
X478132Y1591664D01*
X477332Y1591264D01*
X475332D01*
G01X493532Y1599264D02*
Y1591264D01*
G01X491232Y1599264D02*
X495832D01*
G01X499432Y1591264D02*
Y1599264D01*
G01X503632D02*
Y1591264D01*
G01Y1595264D02*
X499432D01*
G01X511532Y1591264D02*
X507532D01*
Y1599264D01*
X511532D01*
G01X509932Y1595397D02*
X507532D01*
G01X525532Y1599264D02*
Y1591264D01*
G01X523232Y1599264D02*
X527832D01*
G01X535532Y1591264D02*
X531532D01*
Y1599264D01*
X535532D01*
G01X533932Y1595397D02*
X531532D01*
G01X539432Y1592330D02*
X540232Y1591664D01*
X541132Y1591264D01*
X541932D01*
X542732Y1591664D01*
X543332Y1592330D01*
X543632Y1593264D01*
X543432Y1594197D01*
X542932Y1594997D01*
X542032Y1595531D01*
X540832Y1595797D01*
X540132Y1596331D01*
X539832Y1597264D01*
X540032Y1598197D01*
X540532Y1598864D01*
X541232Y1599264D01*
X541932D01*
X542632Y1598997D01*
X543232Y1598331D01*
G01X549532Y1599264D02*
Y1591264D01*
G01X547232Y1599264D02*
X551832D01*
G01X563532Y1591264D02*
Y1599264D01*
X565932D01*
X566732Y1598864D01*
X567332Y1597931D01*
X567532Y1596864D01*
X567332Y1595797D01*
X566832Y1594997D01*
X565932Y1594597D01*
X563532D01*
G01X571032Y1591264D02*
X573532Y1599264D01*
X576032Y1591264D01*
G01X575132Y1594064D02*
X571932D01*
G01X579332Y1591264D02*
Y1599264D01*
X581332D01*
X582132Y1598864D01*
X582732Y1598331D01*
X583232Y1597531D01*
X583632Y1596597D01*
X583732Y1595264D01*
X583632Y1593931D01*
X583232Y1592997D01*
X582732Y1592197D01*
X582132Y1591664D01*
X581332Y1591264D01*
X579332D01*
G01X587432Y1592330D02*
X588232Y1591664D01*
X589132Y1591264D01*
X589932D01*
X590732Y1591664D01*
X591332Y1592330D01*
X591632Y1593264D01*
X591432Y1594197D01*
X590932Y1594997D01*
X590032Y1595531D01*
X588832Y1595797D01*
X588132Y1596331D01*
X587832Y1597264D01*
X588032Y1598197D01*
X588532Y1598864D01*
X589232Y1599264D01*
X589932D01*
X590632Y1598997D01*
X591232Y1598331D01*
G01X-12968Y1621264D02*
X-10468Y1629264D01*
X-7968Y1621264D01*
G01X-8868Y1624064D02*
X-12068D01*
G01X-4768Y1621264D02*
Y1629264D01*
X-168Y1621264D01*
Y1629264D01*
G01X5532Y1621264D02*
Y1624864D01*
X3532Y1629264D01*
G01X7532D02*
X5532Y1624864D01*
G01X19532Y1621264D02*
Y1629264D01*
X21932D01*
X22732Y1628864D01*
X23332Y1627931D01*
X23532Y1626864D01*
X23332Y1625797D01*
X22832Y1624997D01*
X21932Y1624597D01*
X19532D01*
G01X27532Y1621264D02*
Y1629264D01*
X30032D01*
X30832Y1628864D01*
X31332Y1628331D01*
X31532Y1627264D01*
X31332Y1626197D01*
X30732Y1625531D01*
X30032Y1625131D01*
X27532D01*
G01X30032D02*
X31532Y1621264D01*
G01X37532D02*
X36732Y1621397D01*
X36032Y1621931D01*
X35432Y1622731D01*
X35032Y1623664D01*
X34832Y1624731D01*
Y1625797D01*
X35032Y1626864D01*
X35432Y1627797D01*
X36032Y1628597D01*
X36732Y1629131D01*
X37532Y1629264D01*
X38332Y1629131D01*
X39032Y1628597D01*
X39632Y1627797D01*
X40032Y1626864D01*
X40232Y1625797D01*
Y1624731D01*
X40032Y1623664D01*
X39632Y1622731D01*
X39032Y1621931D01*
X38332Y1621397D01*
X37532Y1621264D01*
G01X43532D02*
Y1629264D01*
X45932D01*
X46732Y1628864D01*
X47332Y1627931D01*
X47532Y1626864D01*
X47332Y1625797D01*
X46832Y1624997D01*
X45932Y1624597D01*
X43532D01*
G01X53532Y1621264D02*
X52732Y1621397D01*
X52032Y1621931D01*
X51432Y1622731D01*
X51032Y1623664D01*
X50832Y1624731D01*
Y1625797D01*
X51032Y1626864D01*
X51432Y1627797D01*
X52032Y1628597D01*
X52732Y1629131D01*
X53532Y1629264D01*
X54332Y1629131D01*
X55032Y1628597D01*
X55632Y1627797D01*
X56032Y1626864D01*
X56232Y1625797D01*
Y1624731D01*
X56032Y1623664D01*
X55632Y1622731D01*
X55032Y1621931D01*
X54332Y1621397D01*
X53532Y1621264D01*
G01X59432Y1622330D02*
X60232Y1621664D01*
X61132Y1621264D01*
X61932D01*
X62732Y1621664D01*
X63332Y1622330D01*
X63632Y1623264D01*
X63432Y1624197D01*
X62932Y1624997D01*
X62032Y1625531D01*
X60832Y1625797D01*
X60132Y1626331D01*
X59832Y1627264D01*
X60032Y1628197D01*
X60532Y1628864D01*
X61232Y1629264D01*
X61932D01*
X62632Y1628997D01*
X63232Y1628331D01*
G01X71532Y1621264D02*
X67532D01*
Y1629264D01*
X71532D01*
G01X69932Y1625397D02*
X67532D01*
G01X75332Y1621264D02*
Y1629264D01*
X77332D01*
X78132Y1628864D01*
X78732Y1628331D01*
X79232Y1627531D01*
X79632Y1626597D01*
X79732Y1625264D01*
X79632Y1623931D01*
X79232Y1622997D01*
X78732Y1622197D01*
X78132Y1621664D01*
X77332Y1621264D01*
X75332D01*
G01X95732Y1628597D02*
X95132Y1628997D01*
X94432Y1629264D01*
X93632D01*
X92732Y1628864D01*
X92032Y1628197D01*
X91532Y1627397D01*
X91132Y1626064D01*
X91032Y1624864D01*
X91232Y1623664D01*
X91532Y1622864D01*
X92132Y1622064D01*
X92832Y1621531D01*
X93532Y1621264D01*
X94232D01*
X94932Y1621531D01*
X95532Y1621931D01*
X96032Y1622464D01*
G01X99432Y1621264D02*
Y1629264D01*
G01X103632D02*
Y1621264D01*
G01Y1625264D02*
X99432D01*
G01X107032Y1621264D02*
X109532Y1629264D01*
X112032Y1621264D01*
G01X111132Y1624064D02*
X107932D01*
G01X115232Y1621264D02*
Y1629264D01*
X119832Y1621264D01*
Y1629264D01*
G01X126132Y1625264D02*
X128132D01*
Y1622864D01*
X127532Y1622064D01*
X126832Y1621531D01*
X125832Y1621264D01*
X124832Y1621531D01*
X124132Y1622064D01*
X123532Y1622864D01*
X123132Y1623797D01*
X122932Y1624864D01*
Y1625797D01*
X123132Y1626597D01*
X123532Y1627531D01*
X124132Y1628331D01*
X124732Y1628864D01*
X125532Y1629264D01*
X126232D01*
X127032Y1628997D01*
X127632Y1628464D01*
G01X135532Y1621264D02*
X131532D01*
Y1629264D01*
X135532D01*
G01X133932Y1625397D02*
X131532D01*
G01X147532Y1621264D02*
Y1629264D01*
X150032D01*
X150832Y1628864D01*
X151332Y1628331D01*
X151532Y1627264D01*
X151332Y1626197D01*
X150732Y1625531D01*
X150032Y1625131D01*
X147532D01*
G01X150032D02*
X151532Y1621264D01*
G01X159532D02*
X155532D01*
Y1629264D01*
X159532D01*
G01X157932Y1625397D02*
X155532D01*
G01X165532Y1621264D02*
X164732Y1621397D01*
X164032Y1621931D01*
X163432Y1622731D01*
X163032Y1623664D01*
X162832Y1624731D01*
Y1625797D01*
X163032Y1626864D01*
X163432Y1627797D01*
X164032Y1628597D01*
X164732Y1629131D01*
X165532Y1629264D01*
X166332Y1629131D01*
X167032Y1628597D01*
X167632Y1627797D01*
X168032Y1626864D01*
X168232Y1625797D01*
Y1624731D01*
X168032Y1623664D01*
X167632Y1622731D01*
X167032Y1621931D01*
X166332Y1621397D01*
X165532Y1621264D01*
G01X166332Y1623397D02*
X167532Y1621264D01*
G01X171332Y1629264D02*
Y1623531D01*
X171732Y1622330D01*
X172532Y1621531D01*
X173532Y1621264D01*
X174532Y1621531D01*
X175332Y1622330D01*
X175732Y1623531D01*
Y1629264D01*
G01X183532Y1621264D02*
X179532D01*
Y1629264D01*
X183532D01*
G01X181932Y1625397D02*
X179532D01*
G01X187432Y1622330D02*
X188232Y1621664D01*
X189132Y1621264D01*
X189932D01*
X190732Y1621664D01*
X191332Y1622330D01*
X191632Y1623264D01*
X191432Y1624197D01*
X190932Y1624997D01*
X190032Y1625531D01*
X188832Y1625797D01*
X188132Y1626331D01*
X187832Y1627264D01*
X188032Y1628197D01*
X188532Y1628864D01*
X189232Y1629264D01*
X189932D01*
X190632Y1628997D01*
X191232Y1628331D01*
G01X197532Y1629264D02*
Y1621264D01*
G01X195232Y1629264D02*
X199832D01*
G01X210932Y1621264D02*
Y1629264D01*
X213532Y1622597D01*
X216132Y1629264D01*
Y1621264D01*
G01X219332Y1629264D02*
Y1623531D01*
X219732Y1622330D01*
X220532Y1621531D01*
X221532Y1621264D01*
X222532Y1621531D01*
X223332Y1622330D01*
X223732Y1623531D01*
Y1629264D01*
G01X227432Y1622330D02*
X228232Y1621664D01*
X229132Y1621264D01*
X229932D01*
X230732Y1621664D01*
X231332Y1622330D01*
X231632Y1623264D01*
X231432Y1624197D01*
X230932Y1624997D01*
X230032Y1625531D01*
X228832Y1625797D01*
X228132Y1626331D01*
X227832Y1627264D01*
X228032Y1628197D01*
X228532Y1628864D01*
X229232Y1629264D01*
X229932D01*
X230632Y1628997D01*
X231232Y1628331D01*
G01X237532Y1629264D02*
Y1621264D01*
G01X235232Y1629264D02*
X239832D01*
G01X254332Y1625531D02*
X254732Y1625931D01*
X255032Y1626597D01*
X255232Y1627531D01*
X255032Y1628331D01*
X254632Y1628864D01*
X253932Y1629264D01*
X251232D01*
Y1621264D01*
X254532D01*
X255232Y1621797D01*
X255632Y1622597D01*
X255832Y1623531D01*
X255632Y1624464D01*
X255032Y1625264D01*
X254332Y1625531D01*
X251232D01*
G01X263532Y1621264D02*
X259532D01*
Y1629264D01*
X263532D01*
G01X261932Y1625397D02*
X259532D01*
G01X275032Y1621264D02*
X277532Y1629264D01*
X280032Y1621264D01*
G01X279132Y1624064D02*
X275932D01*
G01X283532Y1621264D02*
Y1629264D01*
X285932D01*
X286732Y1628864D01*
X287332Y1627931D01*
X287532Y1626864D01*
X287332Y1625797D01*
X286832Y1624997D01*
X285932Y1624597D01*
X283532D01*
G01X291532Y1621264D02*
Y1629264D01*
X293932D01*
X294732Y1628864D01*
X295332Y1627931D01*
X295532Y1626864D01*
X295332Y1625797D01*
X294832Y1624997D01*
X293932Y1624597D01*
X291532D01*
G01X299532Y1621264D02*
Y1629264D01*
X302032D01*
X302832Y1628864D01*
X303332Y1628331D01*
X303532Y1627264D01*
X303332Y1626197D01*
X302732Y1625531D01*
X302032Y1625131D01*
X299532D01*
G01X302032D02*
X303532Y1621264D01*
G01X309532D02*
X308732Y1621397D01*
X308032Y1621931D01*
X307432Y1622731D01*
X307032Y1623664D01*
X306832Y1624731D01*
Y1625797D01*
X307032Y1626864D01*
X307432Y1627797D01*
X308032Y1628597D01*
X308732Y1629131D01*
X309532Y1629264D01*
X310332Y1629131D01*
X311032Y1628597D01*
X311632Y1627797D01*
X312032Y1626864D01*
X312232Y1625797D01*
Y1624731D01*
X312032Y1623664D01*
X311632Y1622731D01*
X311032Y1621931D01*
X310332Y1621397D01*
X309532Y1621264D01*
G01X315032Y1629264D02*
X317532Y1621264D01*
X320032Y1629264D01*
G01X327532Y1621264D02*
X323532D01*
Y1629264D01*
X327532D01*
G01X325932Y1625397D02*
X323532D01*
G01X331332Y1621264D02*
Y1629264D01*
X333332D01*
X334132Y1628864D01*
X334732Y1628331D01*
X335232Y1627531D01*
X335632Y1626597D01*
X335732Y1625264D01*
X335632Y1623931D01*
X335232Y1622997D01*
X334732Y1622197D01*
X334132Y1621664D01*
X333332Y1621264D01*
X331332D01*
G01X350332Y1625531D02*
X350732Y1625931D01*
X351032Y1626597D01*
X351232Y1627531D01*
X351032Y1628331D01*
X350632Y1628864D01*
X349932Y1629264D01*
X347232D01*
Y1621264D01*
X350532D01*
X351232Y1621797D01*
X351632Y1622597D01*
X351832Y1623531D01*
X351632Y1624464D01*
X351032Y1625264D01*
X350332Y1625531D01*
X347232D01*
G01X357532Y1621264D02*
Y1624864D01*
X355532Y1629264D01*
G01X359532D02*
X357532Y1624864D01*
G01X373532Y1621264D02*
X372732Y1621397D01*
X372032Y1621931D01*
X371432Y1622731D01*
X371032Y1623664D01*
X370832Y1624731D01*
Y1625797D01*
X371032Y1626864D01*
X371432Y1627797D01*
X372032Y1628597D01*
X372732Y1629131D01*
X373532Y1629264D01*
X374332Y1629131D01*
X375032Y1628597D01*
X375632Y1627797D01*
X376032Y1626864D01*
X376232Y1625797D01*
Y1624731D01*
X376032Y1623664D01*
X375632Y1622731D01*
X375032Y1621931D01*
X374332Y1621397D01*
X373532Y1621264D01*
G01X374332Y1623397D02*
X375532Y1621264D01*
G01X379332Y1629264D02*
Y1623531D01*
X379732Y1622330D01*
X380532Y1621531D01*
X381532Y1621264D01*
X382532Y1621531D01*
X383332Y1622330D01*
X383732Y1623531D01*
Y1629264D01*
G01X387032Y1621264D02*
X389532Y1629264D01*
X392032Y1621264D01*
G01X391132Y1624064D02*
X387932D01*
G01X395232Y1621264D02*
Y1629264D01*
X399832Y1621264D01*
Y1629264D01*
G01X405532D02*
Y1621264D01*
G01X403232Y1629264D02*
X407832D01*
G01X411032Y1621264D02*
X413532Y1629264D01*
X416032Y1621264D01*
G01X415132Y1624064D02*
X411932D01*
G01X427532Y1621264D02*
Y1629264D01*
X429932D01*
X430732Y1628864D01*
X431332Y1627931D01*
X431532Y1626864D01*
X431332Y1625797D01*
X430832Y1624997D01*
X429932Y1624597D01*
X427532D01*
G01X435532Y1621264D02*
Y1629264D01*
X438032D01*
X438832Y1628864D01*
X439332Y1628331D01*
X439532Y1627264D01*
X439332Y1626197D01*
X438732Y1625531D01*
X438032Y1625131D01*
X435532D01*
G01X438032D02*
X439532Y1621264D01*
G01X444332Y1629264D02*
X446732D01*
G01X445532D02*
Y1621264D01*
G01X444332D02*
X446732D01*
G01X453532D02*
X452732Y1621397D01*
X452032Y1621931D01*
X451432Y1622731D01*
X451032Y1623664D01*
X450832Y1624731D01*
Y1625797D01*
X451032Y1626864D01*
X451432Y1627797D01*
X452032Y1628597D01*
X452732Y1629131D01*
X453532Y1629264D01*
X454332Y1629131D01*
X455032Y1628597D01*
X455632Y1627797D01*
X456032Y1626864D01*
X456232Y1625797D01*
Y1624731D01*
X456032Y1623664D01*
X455632Y1622731D01*
X455032Y1621931D01*
X454332Y1621397D01*
X453532Y1621264D01*
G01X459532D02*
Y1629264D01*
X462032D01*
X462832Y1628864D01*
X463332Y1628331D01*
X463532Y1627264D01*
X463332Y1626197D01*
X462732Y1625531D01*
X462032Y1625131D01*
X459532D01*
G01X462032D02*
X463532Y1621264D01*
G01X477532Y1629264D02*
Y1621264D01*
G01X475232Y1629264D02*
X479832D01*
G01X485532Y1621264D02*
X484732Y1621397D01*
X484032Y1621931D01*
X483432Y1622731D01*
X483032Y1623664D01*
X482832Y1624731D01*
Y1625797D01*
X483032Y1626864D01*
X483432Y1627797D01*
X484032Y1628597D01*
X484732Y1629131D01*
X485532Y1629264D01*
X486332Y1629131D01*
X487032Y1628597D01*
X487632Y1627797D01*
X488032Y1626864D01*
X488232Y1625797D01*
Y1624731D01*
X488032Y1623664D01*
X487632Y1622731D01*
X487032Y1621931D01*
X486332Y1621397D01*
X485532Y1621264D01*
G01X500332Y1629264D02*
X502732D01*
G01X501532D02*
Y1621264D01*
G01X500332D02*
X502732D01*
G01X509532Y1629264D02*
Y1621264D01*
G01X507232Y1629264D02*
X511832D01*
G01X515432Y1622330D02*
X516232Y1621664D01*
X517132Y1621264D01*
X517932D01*
X518732Y1621664D01*
X519332Y1622330D01*
X519632Y1623264D01*
X519432Y1624197D01*
X518932Y1624997D01*
X518032Y1625531D01*
X516832Y1625797D01*
X516132Y1626331D01*
X515832Y1627264D01*
X516032Y1628197D01*
X516532Y1628864D01*
X517232Y1629264D01*
X517932D01*
X518632Y1628997D01*
X519232Y1628331D01*
G01X532332Y1629264D02*
X534732D01*
G01X533532D02*
Y1621264D01*
G01X532332D02*
X534732D01*
G01X538932D02*
Y1629264D01*
X541532Y1622597D01*
X544132Y1629264D01*
Y1621264D01*
G01X547532D02*
Y1629264D01*
X549932D01*
X550732Y1628864D01*
X551332Y1627931D01*
X551532Y1626864D01*
X551332Y1625797D01*
X550832Y1624997D01*
X549932Y1624597D01*
X547532D01*
G01X555532Y1629264D02*
Y1621264D01*
X559532D01*
G01X567532D02*
X563532D01*
Y1629264D01*
X567532D01*
G01X565932Y1625397D02*
X563532D01*
G01X570932Y1621264D02*
Y1629264D01*
X573532Y1622597D01*
X576132Y1629264D01*
Y1621264D01*
G01X583532D02*
X579532D01*
Y1629264D01*
X583532D01*
G01X581932Y1625397D02*
X579532D01*
G01X587232Y1621264D02*
Y1629264D01*
X591832Y1621264D01*
Y1629264D01*
G01X597532D02*
Y1621264D01*
G01X595232Y1629264D02*
X599832D01*
G01X603032Y1621264D02*
X605532Y1629264D01*
X608032Y1621264D01*
G01X607132Y1624064D02*
X603932D01*
G01X613532Y1629264D02*
Y1621264D01*
G01X611232Y1629264D02*
X615832D01*
G01X620332D02*
X622732D01*
G01X621532D02*
Y1621264D01*
G01X620332D02*
X622732D01*
G01X629532D02*
X628732Y1621397D01*
X628032Y1621931D01*
X627432Y1622731D01*
X627032Y1623664D01*
X626832Y1624731D01*
Y1625797D01*
X627032Y1626864D01*
X627432Y1627797D01*
X628032Y1628597D01*
X628732Y1629131D01*
X629532Y1629264D01*
X630332Y1629131D01*
X631032Y1628597D01*
X631632Y1627797D01*
X632032Y1626864D01*
X632232Y1625797D01*
Y1624731D01*
X632032Y1623664D01*
X631632Y1622731D01*
X631032Y1621931D01*
X630332Y1621397D01*
X629532Y1621264D01*
G01X635232D02*
Y1629264D01*
X639832Y1621264D01*
Y1629264D01*
G01X645532Y1620997D02*
X645332Y1621131D01*
Y1621397D01*
X645532Y1621531D01*
X645732Y1621397D01*
Y1621131D01*
X645532Y1620997D01*
G01X-12568Y1652330D02*
X-11768Y1651664D01*
X-10868Y1651264D01*
X-10068D01*
X-9268Y1651664D01*
X-8668Y1652330D01*
X-8368Y1653264D01*
X-8568Y1654197D01*
X-9068Y1654997D01*
X-9968Y1655531D01*
X-11168Y1655797D01*
X-11868Y1656331D01*
X-12168Y1657264D01*
X-11968Y1658197D01*
X-11468Y1658864D01*
X-10768Y1659264D01*
X-10068D01*
X-9368Y1658997D01*
X-8768Y1658331D01*
G01X-4468Y1651264D02*
Y1659264D01*
X-2068D01*
X-1268Y1658864D01*
X-668Y1657931D01*
X-468Y1656864D01*
X-668Y1655797D01*
X-1168Y1654997D01*
X-2068Y1654597D01*
X-4468D01*
G01X3032Y1651264D02*
X5532Y1659264D01*
X8032Y1651264D01*
G01X7132Y1654064D02*
X3932D01*
G01X15732Y1658597D02*
X15132Y1658997D01*
X14432Y1659264D01*
X13632D01*
X12732Y1658864D01*
X12032Y1658197D01*
X11532Y1657397D01*
X11132Y1656064D01*
X11032Y1654864D01*
X11232Y1653664D01*
X11532Y1652864D01*
X12132Y1652064D01*
X12832Y1651531D01*
X13532Y1651264D01*
X14232D01*
X14932Y1651531D01*
X15532Y1651931D01*
X16032Y1652464D01*
G01X20332Y1659264D02*
X22732D01*
G01X21532D02*
Y1651264D01*
G01X20332D02*
X22732D01*
G01X27232D02*
Y1659264D01*
X31832Y1651264D01*
Y1659264D01*
G01X38132Y1655264D02*
X40132D01*
Y1652864D01*
X39532Y1652064D01*
X38832Y1651531D01*
X37832Y1651264D01*
X36832Y1651531D01*
X36132Y1652064D01*
X35532Y1652864D01*
X35132Y1653797D01*
X34932Y1654864D01*
Y1655797D01*
X35132Y1656597D01*
X35532Y1657531D01*
X36132Y1658331D01*
X36732Y1658864D01*
X37532Y1659264D01*
X38232D01*
X39032Y1658997D01*
X39632Y1658464D01*
G01X51032Y1651264D02*
X53532Y1659264D01*
X56032Y1651264D01*
G01X55132Y1654064D02*
X51932D01*
G01X59232Y1651264D02*
Y1659264D01*
X63832Y1651264D01*
Y1659264D01*
G01X67332Y1651264D02*
Y1659264D01*
X69332D01*
X70132Y1658864D01*
X70732Y1658331D01*
X71232Y1657531D01*
X71632Y1656597D01*
X71732Y1655264D01*
X71632Y1653931D01*
X71232Y1652997D01*
X70732Y1652197D01*
X70132Y1651664D01*
X69332Y1651264D01*
X67332D01*
G01X82932D02*
Y1659264D01*
X85532Y1652597D01*
X88132Y1659264D01*
Y1651264D01*
G01X91032D02*
X93532Y1659264D01*
X96032Y1651264D01*
G01X95132Y1654064D02*
X91932D01*
G01X101532Y1659264D02*
Y1651264D01*
G01X99232Y1659264D02*
X103832D01*
G01X111532Y1651264D02*
X107532D01*
Y1659264D01*
X111532D01*
G01X109932Y1655397D02*
X107532D01*
G01X115532Y1651264D02*
Y1659264D01*
X118032D01*
X118832Y1658864D01*
X119332Y1658331D01*
X119532Y1657264D01*
X119332Y1656197D01*
X118732Y1655531D01*
X118032Y1655131D01*
X115532D01*
G01X118032D02*
X119532Y1651264D01*
G01X124332Y1659264D02*
X126732D01*
G01X125532D02*
Y1651264D01*
G01X124332D02*
X126732D01*
G01X131032D02*
X133532Y1659264D01*
X136032Y1651264D01*
G01X135132Y1654064D02*
X131932D01*
G01X139532Y1659264D02*
Y1651264D01*
X143532D01*
G01X155332D02*
Y1659264D01*
X157332D01*
X158132Y1658864D01*
X158732Y1658331D01*
X159232Y1657531D01*
X159632Y1656597D01*
X159732Y1655264D01*
X159632Y1653931D01*
X159232Y1652997D01*
X158732Y1652197D01*
X158132Y1651664D01*
X157332Y1651264D01*
X155332D01*
G01X164332Y1659264D02*
X166732D01*
G01X165532D02*
Y1651264D01*
G01X164332D02*
X166732D01*
G01X175532D02*
X171532D01*
Y1659264D01*
X175532D01*
G01X173932Y1655397D02*
X171532D01*
G01X179532Y1659264D02*
Y1651264D01*
X183532D01*
G01X191532D02*
X187532D01*
Y1659264D01*
X191532D01*
G01X189932Y1655397D02*
X187532D01*
G01X199732Y1658597D02*
X199132Y1658997D01*
X198432Y1659264D01*
X197632D01*
X196732Y1658864D01*
X196032Y1658197D01*
X195532Y1657397D01*
X195132Y1656064D01*
X195032Y1654864D01*
X195232Y1653664D01*
X195532Y1652864D01*
X196132Y1652064D01*
X196832Y1651531D01*
X197532Y1651264D01*
X198232D01*
X198932Y1651531D01*
X199532Y1651931D01*
X200032Y1652464D01*
G01X205532Y1659264D02*
Y1651264D01*
G01X203232Y1659264D02*
X207832D01*
G01X211532Y1651264D02*
Y1659264D01*
X214032D01*
X214832Y1658864D01*
X215332Y1658331D01*
X215532Y1657264D01*
X215332Y1656197D01*
X214732Y1655531D01*
X214032Y1655131D01*
X211532D01*
G01X214032D02*
X215532Y1651264D01*
G01X220332Y1659264D02*
X222732D01*
G01X221532D02*
Y1651264D01*
G01X220332D02*
X222732D01*
G01X231732Y1658597D02*
X231132Y1658997D01*
X230432Y1659264D01*
X229632D01*
X228732Y1658864D01*
X228032Y1658197D01*
X227532Y1657397D01*
X227132Y1656064D01*
X227032Y1654864D01*
X227232Y1653664D01*
X227532Y1652864D01*
X228132Y1652064D01*
X228832Y1651531D01*
X229532Y1651264D01*
X230232D01*
X230932Y1651531D01*
X231532Y1651931D01*
X232032Y1652464D01*
G01X247732Y1658597D02*
X247132Y1658997D01*
X246432Y1659264D01*
X245632D01*
X244732Y1658864D01*
X244032Y1658197D01*
X243532Y1657397D01*
X243132Y1656064D01*
X243032Y1654864D01*
X243232Y1653664D01*
X243532Y1652864D01*
X244132Y1652064D01*
X244832Y1651531D01*
X245532Y1651264D01*
X246232D01*
X246932Y1651531D01*
X247532Y1651931D01*
X248032Y1652464D01*
G01X253532Y1651264D02*
X252732Y1651397D01*
X252032Y1651931D01*
X251432Y1652731D01*
X251032Y1653664D01*
X250832Y1654731D01*
Y1655797D01*
X251032Y1656864D01*
X251432Y1657797D01*
X252032Y1658597D01*
X252732Y1659131D01*
X253532Y1659264D01*
X254332Y1659131D01*
X255032Y1658597D01*
X255632Y1657797D01*
X256032Y1656864D01*
X256232Y1655797D01*
Y1654731D01*
X256032Y1653664D01*
X255632Y1652731D01*
X255032Y1651931D01*
X254332Y1651397D01*
X253532Y1651264D01*
G01X259232D02*
Y1659264D01*
X263832Y1651264D01*
Y1659264D01*
G01X267432Y1652330D02*
X268232Y1651664D01*
X269132Y1651264D01*
X269932D01*
X270732Y1651664D01*
X271332Y1652330D01*
X271632Y1653264D01*
X271432Y1654197D01*
X270932Y1654997D01*
X270032Y1655531D01*
X268832Y1655797D01*
X268132Y1656331D01*
X267832Y1657264D01*
X268032Y1658197D01*
X268532Y1658864D01*
X269232Y1659264D01*
X269932D01*
X270632Y1658997D01*
X271232Y1658331D01*
G01X277532Y1659264D02*
Y1651264D01*
G01X275232Y1659264D02*
X279832D01*
G01X283032Y1651264D02*
X285532Y1659264D01*
X288032Y1651264D01*
G01X287132Y1654064D02*
X283932D01*
G01X291232Y1651264D02*
Y1659264D01*
X295832Y1651264D01*
Y1659264D01*
G01X301532D02*
Y1651264D01*
G01X299232Y1659264D02*
X303832D01*
G01X317532D02*
Y1651264D01*
G01X315232Y1659264D02*
X319832D01*
G01X325532Y1651264D02*
X324732Y1651397D01*
X324032Y1651931D01*
X323432Y1652731D01*
X323032Y1653664D01*
X322832Y1654731D01*
Y1655797D01*
X323032Y1656864D01*
X323432Y1657797D01*
X324032Y1658597D01*
X324732Y1659131D01*
X325532Y1659264D01*
X326332Y1659131D01*
X327032Y1658597D01*
X327632Y1657797D01*
X328032Y1656864D01*
X328232Y1655797D01*
Y1654731D01*
X328032Y1653664D01*
X327632Y1652731D01*
X327032Y1651931D01*
X326332Y1651397D01*
X325532Y1651264D01*
G01X339032D02*
X341532Y1659264D01*
X344032Y1651264D01*
G01X343132Y1654064D02*
X339932D01*
G01X351732Y1658597D02*
X351132Y1658997D01*
X350432Y1659264D01*
X349632D01*
X348732Y1658864D01*
X348032Y1658197D01*
X347532Y1657397D01*
X347132Y1656064D01*
X347032Y1654864D01*
X347232Y1653664D01*
X347532Y1652864D01*
X348132Y1652064D01*
X348832Y1651531D01*
X349532Y1651264D01*
X350232D01*
X350932Y1651531D01*
X351532Y1651931D01*
X352032Y1652464D01*
G01X355432Y1651264D02*
Y1659264D01*
G01X359632D02*
Y1651264D01*
G01Y1655264D02*
X355432D01*
G01X364332Y1659264D02*
X366732D01*
G01X365532D02*
Y1651264D01*
G01X364332D02*
X366732D01*
G01X375532D02*
X371532D01*
Y1659264D01*
X375532D01*
G01X373932Y1655397D02*
X371532D01*
G01X379032Y1659264D02*
X381532Y1651264D01*
X384032Y1659264D01*
G01X391532Y1651264D02*
X387532D01*
Y1659264D01*
X391532D01*
G01X389932Y1655397D02*
X387532D01*
G01X403532Y1651264D02*
Y1659264D01*
X406032D01*
X406832Y1658864D01*
X407332Y1658331D01*
X407532Y1657264D01*
X407332Y1656197D01*
X406732Y1655531D01*
X406032Y1655131D01*
X403532D01*
G01X406032D02*
X407532Y1651264D01*
G01X415532D02*
X411532D01*
Y1659264D01*
X415532D01*
G01X413932Y1655397D02*
X411532D01*
G01X421532Y1651264D02*
X420732Y1651397D01*
X420032Y1651931D01*
X419432Y1652731D01*
X419032Y1653664D01*
X418832Y1654731D01*
Y1655797D01*
X419032Y1656864D01*
X419432Y1657797D01*
X420032Y1658597D01*
X420732Y1659131D01*
X421532Y1659264D01*
X422332Y1659131D01*
X423032Y1658597D01*
X423632Y1657797D01*
X424032Y1656864D01*
X424232Y1655797D01*
Y1654731D01*
X424032Y1653664D01*
X423632Y1652731D01*
X423032Y1651931D01*
X422332Y1651397D01*
X421532Y1651264D01*
G01X422332Y1653397D02*
X423532Y1651264D01*
G01X427332Y1659264D02*
Y1653531D01*
X427732Y1652330D01*
X428532Y1651531D01*
X429532Y1651264D01*
X430532Y1651531D01*
X431332Y1652330D01*
X431732Y1653531D01*
Y1659264D01*
G01X436332D02*
X438732D01*
G01X437532D02*
Y1651264D01*
G01X436332D02*
X438732D01*
G01X443532D02*
Y1659264D01*
X446032D01*
X446832Y1658864D01*
X447332Y1658331D01*
X447532Y1657264D01*
X447332Y1656197D01*
X446732Y1655531D01*
X446032Y1655131D01*
X443532D01*
G01X446032D02*
X447532Y1651264D01*
G01X455532D02*
X451532D01*
Y1659264D01*
X455532D01*
G01X453932Y1655397D02*
X451532D01*
G01X459332Y1651264D02*
Y1659264D01*
X461332D01*
X462132Y1658864D01*
X462732Y1658331D01*
X463232Y1657531D01*
X463632Y1656597D01*
X463732Y1655264D01*
X463632Y1653931D01*
X463232Y1652997D01*
X462732Y1652197D01*
X462132Y1651664D01*
X461332Y1651264D01*
X459332D01*
G01X-11668Y1644264D02*
X-9268D01*
G01X-10468D02*
Y1636264D01*
G01X-11668D02*
X-9268D01*
G01X-5068D02*
Y1644264D01*
X-2468Y1637597D01*
X132Y1644264D01*
Y1636264D01*
G01X3532D02*
Y1644264D01*
X5932D01*
X6732Y1643864D01*
X7332Y1642931D01*
X7532Y1641864D01*
X7332Y1640797D01*
X6832Y1639997D01*
X5932Y1639597D01*
X3532D01*
G01X15532Y1636264D02*
X11532D01*
Y1644264D01*
X15532D01*
G01X13932Y1640397D02*
X11532D01*
G01X19332Y1636264D02*
Y1644264D01*
X21332D01*
X22132Y1643864D01*
X22732Y1643331D01*
X23232Y1642531D01*
X23632Y1641597D01*
X23732Y1640264D01*
X23632Y1638931D01*
X23232Y1637997D01*
X22732Y1637197D01*
X22132Y1636664D01*
X21332Y1636264D01*
X19332D01*
G01X27032D02*
X29532Y1644264D01*
X32032Y1636264D01*
G01X31132Y1639064D02*
X27932D01*
G01X35232Y1636264D02*
Y1644264D01*
X39832Y1636264D01*
Y1644264D01*
G01X47732Y1643597D02*
X47132Y1643997D01*
X46432Y1644264D01*
X45632D01*
X44732Y1643864D01*
X44032Y1643197D01*
X43532Y1642397D01*
X43132Y1641064D01*
X43032Y1639864D01*
X43232Y1638664D01*
X43532Y1637864D01*
X44132Y1637064D01*
X44832Y1636531D01*
X45532Y1636264D01*
X46232D01*
X46932Y1636531D01*
X47532Y1636931D01*
X48032Y1637464D01*
G01X55532Y1636264D02*
X51532D01*
Y1644264D01*
X55532D01*
G01X53932Y1640397D02*
X51532D01*
G01X59432Y1637330D02*
X60232Y1636664D01*
X61132Y1636264D01*
X61932D01*
X62732Y1636664D01*
X63332Y1637330D01*
X63632Y1638264D01*
X63432Y1639197D01*
X62932Y1639997D01*
X62032Y1640531D01*
X60832Y1640797D01*
X60132Y1641331D01*
X59832Y1642264D01*
X60032Y1643197D01*
X60532Y1643864D01*
X61232Y1644264D01*
X61932D01*
X62632Y1643997D01*
X63232Y1643331D01*
G01X75032Y1636264D02*
X77532Y1644264D01*
X80032Y1636264D01*
G01X79132Y1639064D02*
X75932D01*
G01X83232Y1636264D02*
Y1644264D01*
X87832Y1636264D01*
Y1644264D01*
G01X91332Y1636264D02*
Y1644264D01*
X93332D01*
X94132Y1643864D01*
X94732Y1643331D01*
X95232Y1642531D01*
X95632Y1641597D01*
X95732Y1640264D01*
X95632Y1638931D01*
X95232Y1637997D01*
X94732Y1637197D01*
X94132Y1636664D01*
X93332Y1636264D01*
X91332D01*
G01X110332Y1640531D02*
X110732Y1640931D01*
X111032Y1641597D01*
X111232Y1642531D01*
X111032Y1643331D01*
X110632Y1643864D01*
X109932Y1644264D01*
X107232D01*
Y1636264D01*
X110532D01*
X111232Y1636797D01*
X111632Y1637597D01*
X111832Y1638531D01*
X111632Y1639464D01*
X111032Y1640264D01*
X110332Y1640531D01*
X107232D01*
G01X117532Y1636264D02*
X116732Y1636397D01*
X116032Y1636931D01*
X115432Y1637731D01*
X115032Y1638664D01*
X114832Y1639731D01*
Y1640797D01*
X115032Y1641864D01*
X115432Y1642797D01*
X116032Y1643597D01*
X116732Y1644131D01*
X117532Y1644264D01*
X118332Y1644131D01*
X119032Y1643597D01*
X119632Y1642797D01*
X120032Y1641864D01*
X120232Y1640797D01*
Y1639731D01*
X120032Y1638664D01*
X119632Y1637731D01*
X119032Y1636931D01*
X118332Y1636397D01*
X117532Y1636264D01*
G01X123032D02*
X125532Y1644264D01*
X128032Y1636264D01*
G01X127132Y1639064D02*
X123932D01*
G01X131532Y1636264D02*
Y1644264D01*
X134032D01*
X134832Y1643864D01*
X135332Y1643331D01*
X135532Y1642264D01*
X135332Y1641197D01*
X134732Y1640531D01*
X134032Y1640131D01*
X131532D01*
G01X134032D02*
X135532Y1636264D01*
G01X139332D02*
Y1644264D01*
X141332D01*
X142132Y1643864D01*
X142732Y1643331D01*
X143232Y1642531D01*
X143632Y1641597D01*
X143732Y1640264D01*
X143632Y1638931D01*
X143232Y1637997D01*
X142732Y1637197D01*
X142132Y1636664D01*
X141332Y1636264D01*
X139332D01*
G01X157532Y1644264D02*
Y1636264D01*
G01X155232Y1644264D02*
X159832D01*
G01X163432Y1636264D02*
Y1644264D01*
G01X167632D02*
Y1636264D01*
G01Y1640264D02*
X163432D01*
G01X172332Y1644264D02*
X174732D01*
G01X173532D02*
Y1636264D01*
G01X172332D02*
X174732D01*
G01X183732Y1643597D02*
X183132Y1643997D01*
X182432Y1644264D01*
X181632D01*
X180732Y1643864D01*
X180032Y1643197D01*
X179532Y1642397D01*
X179132Y1641064D01*
X179032Y1639864D01*
X179232Y1638664D01*
X179532Y1637864D01*
X180132Y1637064D01*
X180832Y1636531D01*
X181532Y1636264D01*
X182232D01*
X182932Y1636531D01*
X183532Y1636931D01*
X184032Y1637464D01*
G01X187332Y1636264D02*
Y1644264D01*
G01X191132D02*
X187332Y1639330D01*
G01X191732Y1636264D02*
X189032Y1641597D01*
G01X195232Y1636264D02*
Y1644264D01*
X199832Y1636264D01*
Y1644264D01*
G01X207532Y1636264D02*
X203532D01*
Y1644264D01*
X207532D01*
G01X205932Y1640397D02*
X203532D01*
G01X211432Y1637330D02*
X212232Y1636664D01*
X213132Y1636264D01*
X213932D01*
X214732Y1636664D01*
X215332Y1637330D01*
X215632Y1638264D01*
X215432Y1639197D01*
X214932Y1639997D01*
X214032Y1640531D01*
X212832Y1640797D01*
X212132Y1641331D01*
X211832Y1642264D01*
X212032Y1643197D01*
X212532Y1643864D01*
X213232Y1644264D01*
X213932D01*
X214632Y1643997D01*
X215232Y1643331D01*
G01X219432Y1637330D02*
X220232Y1636664D01*
X221132Y1636264D01*
X221932D01*
X222732Y1636664D01*
X223332Y1637330D01*
X223632Y1638264D01*
X223432Y1639197D01*
X222932Y1639997D01*
X222032Y1640531D01*
X220832Y1640797D01*
X220132Y1641331D01*
X219832Y1642264D01*
X220032Y1643197D01*
X220532Y1643864D01*
X221232Y1644264D01*
X221932D01*
X222632Y1643997D01*
X223232Y1643331D01*
G01X229532Y1635997D02*
X229332Y1636131D01*
Y1636397D01*
X229532Y1636531D01*
X229732Y1636397D01*
Y1636131D01*
X229532Y1635997D01*
G01X-8268Y1673597D02*
X-8868Y1673997D01*
X-9568Y1674264D01*
X-10368D01*
X-11268Y1673864D01*
X-11968Y1673197D01*
X-12468Y1672397D01*
X-12868Y1671064D01*
X-12968Y1669864D01*
X-12768Y1668664D01*
X-12468Y1667864D01*
X-11868Y1667064D01*
X-11168Y1666531D01*
X-10468Y1666264D01*
X-9768D01*
X-9068Y1666531D01*
X-8468Y1666931D01*
X-7968Y1667464D01*
G01X-4568Y1666264D02*
Y1674264D01*
G01X-368D02*
Y1666264D01*
G01Y1670264D02*
X-4568D01*
G01X3032Y1666264D02*
X5532Y1674264D01*
X8032Y1666264D01*
G01X7132Y1669064D02*
X3932D01*
G01X11532Y1666264D02*
Y1674264D01*
X14032D01*
X14832Y1673864D01*
X15332Y1673331D01*
X15532Y1672264D01*
X15332Y1671197D01*
X14732Y1670531D01*
X14032Y1670131D01*
X11532D01*
G01X14032D02*
X15532Y1666264D01*
G01X21532Y1674264D02*
Y1666264D01*
G01X19232Y1674264D02*
X23832D01*
G01X29532Y1665997D02*
X29332Y1666131D01*
Y1666397D01*
X29532Y1666531D01*
X29732Y1666397D01*
Y1666131D01*
X29532Y1665997D01*
G01X42932Y1666264D02*
Y1674264D01*
X45532Y1667597D01*
X48132Y1674264D01*
Y1666264D01*
G01X51032D02*
X53532Y1674264D01*
X56032Y1666264D01*
G01X55132Y1669064D02*
X51932D01*
G01X59232Y1666264D02*
Y1674264D01*
X63832Y1666264D01*
Y1674264D01*
G01X67332D02*
Y1668531D01*
X67732Y1667330D01*
X68532Y1666531D01*
X69532Y1666264D01*
X70532Y1666531D01*
X71332Y1667330D01*
X71732Y1668531D01*
Y1674264D01*
G01X75632Y1666264D02*
Y1674264D01*
X79432D01*
G01X78032Y1670397D02*
X75632D01*
G01X83032Y1666264D02*
X85532Y1674264D01*
X88032Y1666264D01*
G01X87132Y1669064D02*
X83932D01*
G01X95732Y1673597D02*
X95132Y1673997D01*
X94432Y1674264D01*
X93632D01*
X92732Y1673864D01*
X92032Y1673197D01*
X91532Y1672397D01*
X91132Y1671064D01*
X91032Y1669864D01*
X91232Y1668664D01*
X91532Y1667864D01*
X92132Y1667064D01*
X92832Y1666531D01*
X93532Y1666264D01*
X94232D01*
X94932Y1666531D01*
X95532Y1666931D01*
X96032Y1667464D01*
G01X101532Y1674264D02*
Y1666264D01*
G01X99232Y1674264D02*
X103832D01*
G01X107332D02*
Y1668531D01*
X107732Y1667330D01*
X108532Y1666531D01*
X109532Y1666264D01*
X110532Y1666531D01*
X111332Y1667330D01*
X111732Y1668531D01*
Y1674264D01*
G01X115532Y1666264D02*
Y1674264D01*
X118032D01*
X118832Y1673864D01*
X119332Y1673331D01*
X119532Y1672264D01*
X119332Y1671197D01*
X118732Y1670531D01*
X118032Y1670131D01*
X115532D01*
G01X118032D02*
X119532Y1666264D01*
G01X127532D02*
X123532D01*
Y1674264D01*
X127532D01*
G01X125932Y1670397D02*
X123532D01*
G01X131532Y1666264D02*
Y1674264D01*
X134032D01*
X134832Y1673864D01*
X135332Y1673331D01*
X135532Y1672264D01*
X135332Y1671197D01*
X134732Y1670531D01*
X134032Y1670131D01*
X131532D01*
G01X134032D02*
X135532Y1666264D01*
G01X148332Y1674264D02*
X150732D01*
G01X149532D02*
Y1666264D01*
G01X148332D02*
X150732D01*
G01X155432Y1667330D02*
X156232Y1666664D01*
X157132Y1666264D01*
X157932D01*
X158732Y1666664D01*
X159332Y1667330D01*
X159632Y1668264D01*
X159432Y1669197D01*
X158932Y1669997D01*
X158032Y1670531D01*
X156832Y1670797D01*
X156132Y1671331D01*
X155832Y1672264D01*
X156032Y1673197D01*
X156532Y1673864D01*
X157232Y1674264D01*
X157932D01*
X158632Y1673997D01*
X159232Y1673331D01*
G01X171632Y1666264D02*
Y1674264D01*
X175432D01*
G01X174032Y1670397D02*
X171632D01*
G01X179532Y1666264D02*
Y1674264D01*
X182032D01*
X182832Y1673864D01*
X183332Y1673331D01*
X183532Y1672264D01*
X183332Y1671197D01*
X182732Y1670531D01*
X182032Y1670131D01*
X179532D01*
G01X182032D02*
X183532Y1666264D01*
G01X191532D02*
X187532D01*
Y1674264D01*
X191532D01*
G01X189932Y1670397D02*
X187532D01*
G01X199532Y1666264D02*
X195532D01*
Y1674264D01*
X199532D01*
G01X197932Y1670397D02*
X195532D01*
G01X213532Y1674264D02*
Y1666264D01*
G01X211232Y1674264D02*
X215832D01*
G01X221532Y1666264D02*
X220732Y1666397D01*
X220032Y1666931D01*
X219432Y1667731D01*
X219032Y1668664D01*
X218832Y1669731D01*
Y1670797D01*
X219032Y1671864D01*
X219432Y1672797D01*
X220032Y1673597D01*
X220732Y1674131D01*
X221532Y1674264D01*
X222332Y1674131D01*
X223032Y1673597D01*
X223632Y1672797D01*
X224032Y1671864D01*
X224232Y1670797D01*
Y1669731D01*
X224032Y1668664D01*
X223632Y1667731D01*
X223032Y1666931D01*
X222332Y1666397D01*
X221532Y1666264D01*
G01X235032D02*
X237532Y1674264D01*
X240032Y1666264D01*
G01X239132Y1669064D02*
X235932D01*
G01X243332Y1666264D02*
Y1674264D01*
X245332D01*
X246132Y1673864D01*
X246732Y1673331D01*
X247232Y1672531D01*
X247632Y1671597D01*
X247732Y1670264D01*
X247632Y1668931D01*
X247232Y1667997D01*
X246732Y1667197D01*
X246132Y1666664D01*
X245332Y1666264D01*
X243332D01*
G01X251532Y1667864D02*
X252032Y1667064D01*
X252632Y1666531D01*
X253332Y1666264D01*
X254132Y1666531D01*
X254732Y1667064D01*
X255332Y1667864D01*
X255532Y1668931D01*
Y1674264D01*
G01X259332D02*
Y1668531D01*
X259732Y1667330D01*
X260532Y1666531D01*
X261532Y1666264D01*
X262532Y1666531D01*
X263332Y1667330D01*
X263732Y1668531D01*
Y1674264D01*
G01X267432Y1667330D02*
X268232Y1666664D01*
X269132Y1666264D01*
X269932D01*
X270732Y1666664D01*
X271332Y1667330D01*
X271632Y1668264D01*
X271432Y1669197D01*
X270932Y1669997D01*
X270032Y1670531D01*
X268832Y1670797D01*
X268132Y1671331D01*
X267832Y1672264D01*
X268032Y1673197D01*
X268532Y1673864D01*
X269232Y1674264D01*
X269932D01*
X270632Y1673997D01*
X271232Y1673331D01*
G01X277532Y1674264D02*
Y1666264D01*
G01X275232Y1674264D02*
X279832D01*
G01X293532D02*
Y1666264D01*
G01X291232Y1674264D02*
X295832D01*
G01X299532Y1666264D02*
Y1674264D01*
X302032D01*
X302832Y1673864D01*
X303332Y1673331D01*
X303532Y1672264D01*
X303332Y1671197D01*
X302732Y1670531D01*
X302032Y1670131D01*
X299532D01*
G01X302032D02*
X303532Y1666264D01*
G01X307032D02*
X309532Y1674264D01*
X312032Y1666264D01*
G01X311132Y1669064D02*
X307932D01*
G01X319732Y1673597D02*
X319132Y1673997D01*
X318432Y1674264D01*
X317632D01*
X316732Y1673864D01*
X316032Y1673197D01*
X315532Y1672397D01*
X315132Y1671064D01*
X315032Y1669864D01*
X315232Y1668664D01*
X315532Y1667864D01*
X316132Y1667064D01*
X316832Y1666531D01*
X317532Y1666264D01*
X318232D01*
X318932Y1666531D01*
X319532Y1666931D01*
X320032Y1667464D01*
G01X327532Y1666264D02*
X323532D01*
Y1674264D01*
X327532D01*
G01X325932Y1670397D02*
X323532D01*
G01X338532Y1674264D02*
X339932Y1666264D01*
X341532Y1674264D01*
X343132Y1666264D01*
X344532Y1674264D01*
G01X348332D02*
X350732D01*
G01X349532D02*
Y1666264D01*
G01X348332D02*
X350732D01*
G01X355332D02*
Y1674264D01*
X357332D01*
X358132Y1673864D01*
X358732Y1673331D01*
X359232Y1672531D01*
X359632Y1671597D01*
X359732Y1670264D01*
X359632Y1668931D01*
X359232Y1667997D01*
X358732Y1667197D01*
X358132Y1666664D01*
X357332Y1666264D01*
X355332D01*
G01X365532Y1674264D02*
Y1666264D01*
G01X363232Y1674264D02*
X367832D01*
G01X371432Y1666264D02*
Y1674264D01*
G01X375632D02*
Y1666264D01*
G01Y1670264D02*
X371432D01*
G01X379432Y1667330D02*
X380232Y1666664D01*
X381132Y1666264D01*
X381932D01*
X382732Y1666664D01*
X383332Y1667330D01*
X383632Y1668264D01*
X383432Y1669197D01*
X382932Y1669997D01*
X382032Y1670531D01*
X380832Y1670797D01*
X380132Y1671331D01*
X379832Y1672264D01*
X380032Y1673197D01*
X380532Y1673864D01*
X381232Y1674264D01*
X381932D01*
X382632Y1673997D01*
X383232Y1673331D01*
G01X389332Y1664797D02*
X389732Y1666531D01*
G01X411332Y1666264D02*
Y1674264D01*
X413332D01*
X414132Y1673864D01*
X414732Y1673331D01*
X415232Y1672531D01*
X415632Y1671597D01*
X415732Y1670264D01*
X415632Y1668931D01*
X415232Y1667997D01*
X414732Y1667197D01*
X414132Y1666664D01*
X413332Y1666264D01*
X411332D01*
G01X420332Y1674264D02*
X422732D01*
G01X421532D02*
Y1666264D01*
G01X420332D02*
X422732D01*
G01X431532D02*
X427532D01*
Y1674264D01*
X431532D01*
G01X429932Y1670397D02*
X427532D01*
G01X435532Y1674264D02*
Y1666264D01*
X439532D01*
G01X447532D02*
X443532D01*
Y1674264D01*
X447532D01*
G01X445932Y1670397D02*
X443532D01*
G01X455732Y1673597D02*
X455132Y1673997D01*
X454432Y1674264D01*
X453632D01*
X452732Y1673864D01*
X452032Y1673197D01*
X451532Y1672397D01*
X451132Y1671064D01*
X451032Y1669864D01*
X451232Y1668664D01*
X451532Y1667864D01*
X452132Y1667064D01*
X452832Y1666531D01*
X453532Y1666264D01*
X454232D01*
X454932Y1666531D01*
X455532Y1666931D01*
X456032Y1667464D01*
G01X461532Y1674264D02*
Y1666264D01*
G01X459232Y1674264D02*
X463832D01*
G01X467532Y1666264D02*
Y1674264D01*
X470032D01*
X470832Y1673864D01*
X471332Y1673331D01*
X471532Y1672264D01*
X471332Y1671197D01*
X470732Y1670531D01*
X470032Y1670131D01*
X467532D01*
G01X470032D02*
X471532Y1666264D01*
G01X476332Y1674264D02*
X478732D01*
G01X477532D02*
Y1666264D01*
G01X476332D02*
X478732D01*
G01X487732Y1673597D02*
X487132Y1673997D01*
X486432Y1674264D01*
X485632D01*
X484732Y1673864D01*
X484032Y1673197D01*
X483532Y1672397D01*
X483132Y1671064D01*
X483032Y1669864D01*
X483232Y1668664D01*
X483532Y1667864D01*
X484132Y1667064D01*
X484832Y1666531D01*
X485532Y1666264D01*
X486232D01*
X486932Y1666531D01*
X487532Y1666931D01*
X488032Y1667464D01*
G01X37000Y-995000D02*
Y-1070000D01*
X537000D01*
Y-995000D01*
X37000D01*
G01X32820Y-735508D02*
X35920D01*
Y-736428D01*
X35765Y-736735D01*
X35403Y-736965D01*
X34990Y-737042D01*
X34577Y-736965D01*
X34267Y-736773D01*
X34112Y-736428D01*
Y-735508D01*
G01X35662Y-740218D02*
X35817Y-739988D01*
X35920Y-739720D01*
Y-739413D01*
X35765Y-739068D01*
X35507Y-738800D01*
X35197Y-738608D01*
X34680Y-738455D01*
X34215Y-738417D01*
X33750Y-738493D01*
X33440Y-738608D01*
X33130Y-738838D01*
X32923Y-739107D01*
X32820Y-739375D01*
Y-739643D01*
X32923Y-739912D01*
X33078Y-740142D01*
X33285Y-740333D01*
G01X34473Y-742782D02*
X34628Y-742935D01*
X34887Y-743050D01*
X35248Y-743127D01*
X35558Y-743050D01*
X35765Y-742897D01*
X35920Y-742628D01*
Y-741593D01*
X32820D01*
Y-742858D01*
X33027Y-743127D01*
X33337Y-743280D01*
X33698Y-743357D01*
X34060Y-743280D01*
X34370Y-743050D01*
X34473Y-742782D01*
Y-741593D01*
G01X35920Y-747717D02*
X32820Y-748675D01*
X35920Y-749633D01*
G01X32820Y-752542D02*
Y-751008D01*
X35920D01*
Y-752542D01*
G01X34422Y-751928D02*
Y-751008D01*
G01X32820Y-753993D02*
X35920D01*
X32820Y-755757D01*
X35920D01*
G01X32820Y-757132D02*
X35920D01*
Y-757898D01*
X35765Y-758205D01*
X35558Y-758435D01*
X35248Y-758627D01*
X34887Y-758780D01*
X34370Y-758818D01*
X33853Y-758780D01*
X33492Y-758627D01*
X33182Y-758435D01*
X32975Y-758205D01*
X32820Y-757898D01*
Y-757132D01*
G01Y-761075D02*
X32872Y-760768D01*
X33078Y-760500D01*
X33388Y-760270D01*
X33750Y-760117D01*
X34163Y-760040D01*
X34577D01*
X34990Y-760117D01*
X35352Y-760270D01*
X35662Y-760500D01*
X35868Y-760768D01*
X35920Y-761075D01*
X35868Y-761382D01*
X35662Y-761650D01*
X35352Y-761880D01*
X34990Y-762033D01*
X34577Y-762110D01*
X34163D01*
X33750Y-762033D01*
X33388Y-761880D01*
X33078Y-761650D01*
X32872Y-761382D01*
X32820Y-761075D01*
G01Y-763408D02*
X35920D01*
Y-764367D01*
X35765Y-764673D01*
X35558Y-764865D01*
X35145Y-764942D01*
X34732Y-764865D01*
X34473Y-764635D01*
X34318Y-764367D01*
Y-763408D01*
G01Y-764367D02*
X32820Y-764942D01*
G01X30920Y-742808D02*
X27820D01*
Y-744342D01*
G01Y-746675D02*
X27872Y-746368D01*
X28078Y-746100D01*
X28388Y-745870D01*
X28750Y-745717D01*
X29163Y-745640D01*
X29577D01*
X29990Y-745717D01*
X30352Y-745870D01*
X30662Y-746100D01*
X30868Y-746368D01*
X30920Y-746675D01*
X30868Y-746982D01*
X30662Y-747250D01*
X30352Y-747480D01*
X29990Y-747633D01*
X29577Y-747710D01*
X29163D01*
X28750Y-747633D01*
X28388Y-747480D01*
X28078Y-747250D01*
X27872Y-746982D01*
X27820Y-746675D01*
G01X29370Y-750005D02*
Y-750772D01*
X28440D01*
X28130Y-750542D01*
X27923Y-750273D01*
X27820Y-749890D01*
X27923Y-749507D01*
X28130Y-749238D01*
X28440Y-749008D01*
X28802Y-748855D01*
X29215Y-748778D01*
X29577D01*
X29887Y-748855D01*
X30248Y-749008D01*
X30558Y-749238D01*
X30765Y-749468D01*
X30920Y-749775D01*
Y-750043D01*
X30817Y-750350D01*
X30610Y-750580D01*
G01X27820Y-752875D02*
X27872Y-752568D01*
X28078Y-752300D01*
X28388Y-752070D01*
X28750Y-751917D01*
X29163Y-751840D01*
X29577D01*
X29990Y-751917D01*
X30352Y-752070D01*
X30662Y-752300D01*
X30868Y-752568D01*
X30920Y-752875D01*
X30868Y-753182D01*
X30662Y-753450D01*
X30352Y-753680D01*
X29990Y-753833D01*
X29577Y-753910D01*
X29163D01*
X28750Y-753833D01*
X28388Y-753680D01*
X28078Y-753450D01*
X27872Y-753182D01*
X27820Y-752875D01*
G01X46952Y11818D02*
X41344Y-4284D01*
G01X41339Y17717D02*
Y23763D01*
G03X38916Y32156I-15749J0D01*
G02X55572I8328J5245D01*
G03X53150Y23763I13326J-8392D01*
G01Y17717D01*
G02X41339I-5905J0D01*
G01Y23763D02*
G03X38916Y32156I-15749J0D01*
G02X55572I8328J5245D01*
G03X53150Y23763I13326J-8392D01*
G01Y17717D01*
G02X41339I-5905J0D01*
G01Y23763D01*
G01X41338Y17716D02*
G03X53150I5906J0D01*
G01X41338Y23763D02*
Y17716D01*
G01X38916Y32155D02*
G02X41338Y23763I-13327J-8392D01*
G01X55572Y32155D02*
G03X38916I-8328J5246D01*
G01X41339Y330709D02*
Y336756D01*
G03X38916Y345148I-15747J-1D01*
G02X55572I8328J5245D01*
G03X53150Y336756I13324J-8391D01*
G01Y330709D01*
G02X41339I-5905J0D01*
G01Y336756D02*
G03X38916Y345148I-15747J-1D01*
G02X55572I8328J5245D01*
G03X53150Y336756I13324J-8391D01*
G01Y330709D01*
G02X41339I-5905J0D01*
G01Y336756D01*
G01X46952Y324810D02*
X41344Y308708D01*
G01X41338Y330708D02*
G03X53150I5906J0D01*
G01X41338Y336755D02*
Y330708D01*
G01X38916Y345147D02*
G02X41338Y336755I-13327J-8392D01*
G01X55572Y345147D02*
G03X38916I-8328J5246D01*
G01X19685Y541339D02*
G02X44882I12598J0D01*
G02X19685I-12599J0D01*
G01D02*
G02X44882I12598J0D01*
G02X19685I-12599J0D01*
G01X49000Y-1060000D02*
Y-1065000D01*
G01X47543Y-1060000D02*
X50457D01*
G01X55367Y-1065000D02*
X52833D01*
Y-1060000D01*
X55367D01*
G01X54353Y-1062417D02*
X52833D01*
G01X57933Y-1060000D02*
Y-1065000D01*
X60467D01*
G01X64300Y-1065167D02*
X64173Y-1065083D01*
Y-1064917D01*
X64300Y-1064833D01*
X64427Y-1064917D01*
Y-1065083D01*
X64300Y-1065167D01*
G01Y-1062917D02*
X64173Y-1062833D01*
Y-1062667D01*
X64300Y-1062583D01*
X64427Y-1062667D01*
Y-1062833D01*
X64300Y-1062917D01*
G01X69083Y-1066667D02*
X68450Y-1065833D01*
X68133Y-1065000D01*
Y-1061667D01*
X68450Y-1060833D01*
X69083Y-1060000D01*
G01X74500D02*
X73993Y-1060167D01*
X73613Y-1060583D01*
X73360Y-1061083D01*
X73170Y-1061750D01*
X73107Y-1062500D01*
X73170Y-1063250D01*
X73360Y-1063917D01*
X73613Y-1064417D01*
X73993Y-1064833D01*
X74500Y-1065000D01*
X75007Y-1064833D01*
X75387Y-1064417D01*
X75640Y-1063917D01*
X75830Y-1063250D01*
X75893Y-1062500D01*
X75830Y-1061750D01*
X75640Y-1061083D01*
X75387Y-1060583D01*
X75007Y-1060167D01*
X74500Y-1060000D01*
G01X78207Y-1064000D02*
X78587Y-1064583D01*
X79093Y-1064917D01*
X79663Y-1065000D01*
X80170Y-1064917D01*
X80677Y-1064500D01*
X80993Y-1064000D01*
X81057Y-1063500D01*
X80930Y-1062917D01*
X80487Y-1062500D01*
X80043Y-1062333D01*
X79473D01*
G01X80043D02*
X80423Y-1062083D01*
X80740Y-1061667D01*
X80867Y-1061167D01*
X80740Y-1060667D01*
X80423Y-1060250D01*
X79853Y-1060000D01*
X79283Y-1060083D01*
X78713Y-1060417D01*
G01X85017Y-1066667D02*
X85650Y-1065833D01*
X85967Y-1065000D01*
Y-1061667D01*
X85650Y-1060833D01*
X85017Y-1060000D01*
G01X88407Y-1064000D02*
X88787Y-1064583D01*
X89293Y-1064917D01*
X89863Y-1065000D01*
X90370Y-1064917D01*
X90877Y-1064500D01*
X91193Y-1064000D01*
X91257Y-1063500D01*
X91130Y-1062917D01*
X90687Y-1062500D01*
X90243Y-1062333D01*
X89673D01*
G01X90243D02*
X90623Y-1062083D01*
X90940Y-1061667D01*
X91067Y-1061167D01*
X90940Y-1060667D01*
X90623Y-1060250D01*
X90053Y-1060000D01*
X89483Y-1060083D01*
X88913Y-1060417D01*
G01X93697Y-1060833D02*
X94077Y-1060333D01*
X94520Y-1060083D01*
X95027Y-1060000D01*
X95660Y-1060167D01*
X96103Y-1060583D01*
X96230Y-1061083D01*
X96167Y-1061583D01*
X95913Y-1062000D01*
X94647Y-1062833D01*
X94077Y-1063417D01*
X93697Y-1064250D01*
X93570Y-1065000D01*
X96230D01*
G01X99873D02*
X100000Y-1063917D01*
X100190Y-1063000D01*
X100443Y-1062167D01*
X100760Y-1061250D01*
X101267Y-1060000D01*
X98733D01*
G01X104277Y-1063333D02*
X105923D01*
G01X108997Y-1060833D02*
X109377Y-1060333D01*
X109820Y-1060083D01*
X110327Y-1060000D01*
X110960Y-1060167D01*
X111403Y-1060583D01*
X111530Y-1061083D01*
X111467Y-1061583D01*
X111213Y-1062000D01*
X109947Y-1062833D01*
X109377Y-1063417D01*
X108997Y-1064250D01*
X108870Y-1065000D01*
X111530D01*
G01X113907Y-1064000D02*
X114287Y-1064583D01*
X114793Y-1064917D01*
X115363Y-1065000D01*
X115870Y-1064917D01*
X116377Y-1064500D01*
X116693Y-1064000D01*
X116757Y-1063500D01*
X116630Y-1062917D01*
X116187Y-1062500D01*
X115743Y-1062333D01*
X115173D01*
G01X115743D02*
X116123Y-1062083D01*
X116440Y-1061667D01*
X116567Y-1061167D01*
X116440Y-1060667D01*
X116123Y-1060250D01*
X115553Y-1060000D01*
X114983Y-1060083D01*
X114413Y-1060417D01*
G01X121160Y-1065000D02*
Y-1060000D01*
X118817Y-1063583D01*
X121983D01*
G01X124107Y-1064250D02*
X124487Y-1064667D01*
X124930Y-1064917D01*
X125500Y-1065000D01*
X126070Y-1064833D01*
X126513Y-1064500D01*
X126830Y-1063917D01*
X126893Y-1063250D01*
X126767Y-1062583D01*
X126450Y-1062167D01*
X126007Y-1061833D01*
X125563Y-1061750D01*
X125120Y-1061833D01*
X124550Y-1062167D01*
X124740Y-1060000D01*
X126450D01*
G01X134497Y-1065000D02*
Y-1060000D01*
X136903D01*
G01X136017Y-1062417D02*
X134497D01*
G01X139217Y-1065000D02*
X140800Y-1060000D01*
X142383Y-1065000D01*
G01X141813Y-1063250D02*
X139787D01*
G01X144570Y-1065000D02*
X147230Y-1060000D01*
G01X144570D02*
X147230Y-1065000D01*
G01X151000Y-1065167D02*
X150873Y-1065083D01*
Y-1064917D01*
X151000Y-1064833D01*
X151127Y-1064917D01*
Y-1065083D01*
X151000Y-1065167D01*
G01Y-1062917D02*
X150873Y-1062833D01*
Y-1062667D01*
X151000Y-1062583D01*
X151127Y-1062667D01*
Y-1062833D01*
X151000Y-1062917D01*
G01X155783Y-1066667D02*
X155150Y-1065833D01*
X154833Y-1065000D01*
Y-1061667D01*
X155150Y-1060833D01*
X155783Y-1060000D01*
G01X161200D02*
X160693Y-1060167D01*
X160313Y-1060583D01*
X160060Y-1061083D01*
X159870Y-1061750D01*
X159807Y-1062500D01*
X159870Y-1063250D01*
X160060Y-1063917D01*
X160313Y-1064417D01*
X160693Y-1064833D01*
X161200Y-1065000D01*
X161707Y-1064833D01*
X162087Y-1064417D01*
X162340Y-1063917D01*
X162530Y-1063250D01*
X162593Y-1062500D01*
X162530Y-1061750D01*
X162340Y-1061083D01*
X162087Y-1060583D01*
X161707Y-1060167D01*
X161200Y-1060000D01*
G01X164907Y-1064000D02*
X165287Y-1064583D01*
X165793Y-1064917D01*
X166363Y-1065000D01*
X166870Y-1064917D01*
X167377Y-1064500D01*
X167693Y-1064000D01*
X167757Y-1063500D01*
X167630Y-1062917D01*
X167187Y-1062500D01*
X166743Y-1062333D01*
X166173D01*
G01X166743D02*
X167123Y-1062083D01*
X167440Y-1061667D01*
X167567Y-1061167D01*
X167440Y-1060667D01*
X167123Y-1060250D01*
X166553Y-1060000D01*
X165983Y-1060083D01*
X165413Y-1060417D01*
G01X171717Y-1066667D02*
X172350Y-1065833D01*
X172667Y-1065000D01*
Y-1061667D01*
X172350Y-1060833D01*
X171717Y-1060000D01*
G01X175107Y-1064000D02*
X175487Y-1064583D01*
X175993Y-1064917D01*
X176563Y-1065000D01*
X177070Y-1064917D01*
X177577Y-1064500D01*
X177893Y-1064000D01*
X177957Y-1063500D01*
X177830Y-1062917D01*
X177387Y-1062500D01*
X176943Y-1062333D01*
X176373D01*
G01X176943D02*
X177323Y-1062083D01*
X177640Y-1061667D01*
X177767Y-1061167D01*
X177640Y-1060667D01*
X177323Y-1060250D01*
X176753Y-1060000D01*
X176183Y-1060083D01*
X175613Y-1060417D01*
G01X180523Y-1064417D02*
X180967Y-1064833D01*
X181473Y-1065000D01*
X181980Y-1064833D01*
X182423Y-1064333D01*
X182740Y-1063583D01*
X182867Y-1062833D01*
Y-1061917D01*
X182740Y-1061167D01*
X182423Y-1060500D01*
X182043Y-1060167D01*
X181600Y-1060000D01*
X181093Y-1060167D01*
X180713Y-1060500D01*
X180460Y-1061000D01*
X180333Y-1061667D01*
X180460Y-1062250D01*
X180777Y-1062833D01*
X181157Y-1063167D01*
X181600Y-1063250D01*
X182107Y-1063083D01*
X182487Y-1062667D01*
X182867Y-1061917D01*
G01X186573Y-1065000D02*
X186700Y-1063917D01*
X186890Y-1063000D01*
X187143Y-1062167D01*
X187460Y-1061250D01*
X187967Y-1060000D01*
X185433D01*
G01X190977Y-1063333D02*
X192623D01*
G01X195507Y-1064000D02*
X195887Y-1064583D01*
X196393Y-1064917D01*
X196963Y-1065000D01*
X197470Y-1064917D01*
X197977Y-1064500D01*
X198293Y-1064000D01*
X198357Y-1063500D01*
X198230Y-1062917D01*
X197787Y-1062500D01*
X197343Y-1062333D01*
X196773D01*
G01X197343D02*
X197723Y-1062083D01*
X198040Y-1061667D01*
X198167Y-1061167D01*
X198040Y-1060667D01*
X197723Y-1060250D01*
X197153Y-1060000D01*
X196583Y-1060083D01*
X196013Y-1060417D01*
G01X200797Y-1062917D02*
X201240Y-1062333D01*
X201620Y-1062000D01*
X202127Y-1061833D01*
X202570Y-1062000D01*
X202887Y-1062333D01*
X203140Y-1062833D01*
X203203Y-1063417D01*
X203140Y-1063917D01*
X202887Y-1064417D01*
X202507Y-1064833D01*
X202063Y-1065000D01*
X201557Y-1064833D01*
X201113Y-1064333D01*
X200860Y-1063583D01*
X200797Y-1062750D01*
X200923Y-1061667D01*
X201113Y-1061083D01*
X201430Y-1060500D01*
X201873Y-1060083D01*
X202317Y-1060000D01*
X202760Y-1060167D01*
X203077Y-1060583D01*
G01X207100Y-1065000D02*
Y-1060000D01*
X206340Y-1061000D01*
G01Y-1065000D02*
X207860D01*
G01X212960D02*
Y-1060000D01*
X210617Y-1063583D01*
X213783D01*
G01X65994Y-118350D02*
Y-123000D01*
X53494D01*
Y-118350D01*
G01X65994Y-87350D02*
Y-82700D01*
X53494D01*
Y-87350D01*
G01X47244Y329708D02*
Y-57675D01*
G01X59055Y235614D02*
Y-53000D01*
X86100D01*
Y-57675D01*
G01X46587Y7776D02*
X46952Y11818D01*
X44728Y8424D01*
X46587Y7776D01*
G01X53150Y23763D02*
G02X55572Y32155I15747J1D01*
G01X53150Y17716D02*
Y23763D01*
G01X51181Y236614D02*
G02X66929I7874J0D01*
G02X51181I-7874J0D01*
G01D02*
G02X66929I7874J0D01*
G02X51181I-7874J0D01*
G01X46587Y320768D02*
X46952Y324810D01*
X44728Y321416D01*
X46587Y320768D01*
G01X53150Y336755D02*
G02X55572Y345147I15747J1D01*
G01X53150Y330708D02*
Y336755D01*
G01X51181Y411614D02*
G02X66929I7874J0D01*
G02X51181I-7874J0D01*
G01D02*
G02X66929I7874J0D01*
G02X51181I-7874J0D01*
G01X59055Y412594D02*
Y718000D01*
X84100Y719000D01*
Y737675D01*
G01X46457Y498031D02*
G02X71654I12598J0D01*
G02X46457I-12599J0D01*
G01D02*
G02X71654I12598J0D01*
G02X46457I-12599J0D01*
G01X97366Y1128197D02*
X65870D01*
G01D02*
X107209D01*
G01X77681Y1198079D02*
G03I-2953J0D01*
G01X57996D02*
G03I-2953J0D01*
G01X77681Y1217764D02*
G03I-2953J0D01*
G01X57996D02*
G03I-2953J0D01*
G01X52091Y1260086D02*
X626894D01*
G01X52091Y1275834D02*
Y1260086D01*
G01X626894Y1295520D02*
X52091D01*
G01Y1279771D02*
X626894D01*
G01Y1275834D02*
X52091D01*
G01Y1295520D02*
Y1279771D01*
G01Y1299457D02*
Y1370323D01*
G01Y1362449D02*
X347366D01*
G01X104850Y-118350D02*
Y-123000D01*
X92350D01*
Y-118350D01*
G01X104850Y-87350D02*
Y-82700D01*
X92350D01*
Y-87350D01*
G01X102850Y767650D02*
Y763000D01*
X90350D01*
Y767650D01*
G01X102850Y798650D02*
Y803300D01*
X90350D01*
Y798650D01*
G01X89722Y1109439D02*
X90652Y1108397D01*
X91737Y1107772D01*
X93132Y1107564D01*
X94527Y1107981D01*
X95612Y1108814D01*
X96387Y1110272D01*
X96542Y1111939D01*
X96232Y1113606D01*
X95457Y1114647D01*
X94372Y1115481D01*
X93287Y1115689D01*
X92202Y1115481D01*
X90807Y1114647D01*
X91272Y1120064D01*
X95457D01*
G01X101502Y1107564D02*
Y1120064D01*
X105532Y1109647D01*
X109562Y1120064D01*
Y1107564D01*
G01X113902D02*
Y1120064D01*
X117932Y1109647D01*
X121962Y1120064D01*
Y1107564D01*
G01X97366Y1190577D02*
Y1120323D01*
G01Y1198079D02*
G03I-2952J0D01*
G01Y1217764D02*
G03I-2952J0D01*
G01X132503Y669285D02*
X168003D01*
Y597585D01*
X132503D01*
Y669285D01*
G01X141502Y669364D02*
X139502Y671964D01*
X141602Y672664D01*
X141502Y669364D01*
X115003Y743085D01*
G01X148547Y1100638D02*
X117051D01*
G01D02*
X158390D01*
G01X117051Y1190927D02*
Y1120323D01*
G01Y1128197D02*
X148547D01*
G01D02*
X107209D01*
G01X117051Y1201031D02*
X122957D01*
G01Y1195126D02*
X117051D01*
G01X122957Y1201031D02*
Y1195126D01*
G01X117051D02*
Y1201031D01*
G01Y1220716D02*
X122957D01*
G01Y1214811D02*
X117051D01*
G01X122957Y1220716D02*
Y1214811D01*
G01X117051D02*
Y1220716D01*
G01X137303Y665685D02*
Y723475D01*
G01X156053Y741050D02*
Y736400D01*
X143553D01*
Y741050D01*
G01X156053Y809250D02*
Y813900D01*
X143553D01*
Y809250D01*
G01X142722Y1078039D02*
X143652Y1076997D01*
X144737Y1076372D01*
X146132Y1076164D01*
X147527Y1076581D01*
X148612Y1077414D01*
X149387Y1078872D01*
X149542Y1080539D01*
X149232Y1082206D01*
X148457Y1083247D01*
X147372Y1084081D01*
X146287Y1084289D01*
X145202Y1084081D01*
X143807Y1083247D01*
X144272Y1088664D01*
X148457D01*
G01X154502Y1076164D02*
Y1088664D01*
X158532Y1078247D01*
X162562Y1088664D01*
Y1076164D01*
G01X166902D02*
Y1088664D01*
X170932Y1078247D01*
X174962Y1088664D01*
Y1076164D01*
G01X199728Y1100638D02*
X158390D01*
G01X148547Y1191189D02*
Y1092764D01*
G01X168232Y1152339D02*
X136736D01*
G01D02*
X171185D01*
G01X142642Y1201031D02*
X148547D01*
G01Y1195126D02*
X142642D01*
G01X148547Y1201031D02*
Y1195126D01*
G01X142642D02*
Y1201031D01*
G01Y1220716D02*
X148547D01*
G01Y1214811D02*
X142642D01*
G01X148547Y1220716D02*
Y1214811D01*
G01X142642D02*
Y1220716D01*
G01X178022Y658674D02*
X186295Y625510D01*
X185517Y626854D01*
X186365Y626995D01*
X186295Y625510D01*
G01X189422Y614341D02*
Y667341D01*
G01X226922Y614341D02*
X189422D01*
G01X178022Y658674D02*
Y738647D01*
G01X189422Y667341D02*
X226922D01*
G01X168232Y1191189D02*
Y1092764D01*
G01Y1100638D02*
X199728D01*
G01X174138Y1190504D02*
Y1144465D01*
G01X168232Y1187005D02*
Y1144465D01*
G01X198147Y1155292D02*
Y1167792D01*
X196287Y1165292D01*
G01Y1155292D02*
X200007D01*
G01X210547Y1154875D02*
X210237Y1155084D01*
Y1155500D01*
X210547Y1155709D01*
X210857Y1155500D01*
Y1155084D01*
X210547Y1154875D01*
G01X219537Y1157167D02*
X220467Y1156125D01*
X221552Y1155500D01*
X222947Y1155292D01*
X224342Y1155709D01*
X225427Y1156542D01*
X226202Y1158000D01*
X226357Y1159667D01*
X226047Y1161334D01*
X225272Y1162375D01*
X224187Y1163209D01*
X223102Y1163417D01*
X222017Y1163209D01*
X220622Y1162375D01*
X221087Y1167792D01*
X225272D01*
G01X231317Y1155292D02*
Y1167792D01*
X235347Y1157375D01*
X239377Y1167792D01*
Y1155292D01*
G01X243717D02*
Y1167792D01*
X247747Y1157375D01*
X251777Y1167792D01*
Y1155292D01*
G01X174138Y1152339D02*
X240664D01*
G01D02*
X171185D01*
G01X168232Y1201031D02*
X174138D01*
G01Y1195126D02*
X168232D01*
G01X174138Y1201031D02*
Y1195126D01*
G01X168232D02*
Y1201031D01*
G01Y1220716D02*
X174138D01*
G01Y1214811D02*
X168232D01*
G01X174138Y1220716D02*
Y1214811D01*
G01X168232D02*
Y1220716D01*
G01X178075Y1214811D02*
X297805D01*
G01X178075Y1220716D02*
X297805D01*
G01X223622Y618441D02*
Y729475D01*
G01X224622Y617441D02*
X409775D01*
G01X203691Y639094D02*
G02X212057I4183J0D01*
G02X203691I-4183J0D01*
G01D02*
G02X212057I4183J0D01*
G02X203691I-4183J0D01*
G01X232000Y-995000D02*
Y-1070000D01*
G01Y-1045000D02*
X335000D01*
Y-1020000D01*
G01X232000D02*
X335000D01*
G01X259850Y-144950D02*
Y-149600D01*
X247350D01*
Y-144950D01*
G01X259850Y-76750D02*
Y-72100D01*
X247350D01*
Y-76750D01*
G01X236142Y15512D02*
G02X245591I4724J0D01*
G02X236142I-4724J0D01*
G01D02*
G02X245591I4724J0D01*
G02X236142I-4724J0D01*
G01X293446Y27112D02*
Y4112D01*
X247346D01*
Y27112D01*
X293446D01*
G01X226922Y667341D02*
Y614341D01*
G01X306050Y613691D02*
X244000D01*
Y667791D01*
X306050D01*
Y613691D01*
G01X242372Y753250D02*
Y748600D01*
X229872D01*
Y753250D01*
G01X242372Y809050D02*
Y813700D01*
X229872D01*
Y809050D01*
G01X227432Y1772330D02*
X228232Y1771664D01*
X229132Y1771264D01*
X229932D01*
X230732Y1771664D01*
X231332Y1772330D01*
X231632Y1773264D01*
X231432Y1774197D01*
X230932Y1774997D01*
X230032Y1775531D01*
X228832Y1775797D01*
X228132Y1776331D01*
X227832Y1777264D01*
X228032Y1778197D01*
X228532Y1778864D01*
X229232Y1779264D01*
X229932D01*
X230632Y1778997D01*
X231232Y1778331D01*
G01X237532Y1771264D02*
X236732Y1771397D01*
X236032Y1771931D01*
X235432Y1772731D01*
X235032Y1773664D01*
X234832Y1774731D01*
Y1775797D01*
X235032Y1776864D01*
X235432Y1777797D01*
X236032Y1778597D01*
X236732Y1779131D01*
X237532Y1779264D01*
X238332Y1779131D01*
X239032Y1778597D01*
X239632Y1777797D01*
X240032Y1776864D01*
X240232Y1775797D01*
Y1774731D01*
X240032Y1773664D01*
X239632Y1772731D01*
X239032Y1771931D01*
X238332Y1771397D01*
X237532Y1771264D01*
G01X243532Y1779264D02*
Y1771264D01*
X247532D01*
G01X251332D02*
Y1779264D01*
X253332D01*
X254132Y1778864D01*
X254732Y1778331D01*
X255232Y1777531D01*
X255632Y1776597D01*
X255732Y1775264D01*
X255632Y1773931D01*
X255232Y1772997D01*
X254732Y1772197D01*
X254132Y1771664D01*
X253332Y1771264D01*
X251332D01*
G01X263532D02*
X259532D01*
Y1779264D01*
X263532D01*
G01X261932Y1775397D02*
X259532D01*
G01X267532Y1771264D02*
Y1779264D01*
X270032D01*
X270832Y1778864D01*
X271332Y1778331D01*
X271532Y1777264D01*
X271332Y1776197D01*
X270732Y1775531D01*
X270032Y1775131D01*
X267532D01*
G01X270032D02*
X271532Y1771264D01*
G01X274932D02*
Y1779264D01*
X277532Y1772597D01*
X280132Y1779264D01*
Y1771264D01*
G01X283032D02*
X285532Y1779264D01*
X288032Y1771264D01*
G01X287132Y1774064D02*
X283932D01*
G01X291432Y1772330D02*
X292232Y1771664D01*
X293132Y1771264D01*
X293932D01*
X294732Y1771664D01*
X295332Y1772330D01*
X295632Y1773264D01*
X295432Y1774197D01*
X294932Y1774997D01*
X294032Y1775531D01*
X292832Y1775797D01*
X292132Y1776331D01*
X291832Y1777264D01*
X292032Y1778197D01*
X292532Y1778864D01*
X293232Y1779264D01*
X293932D01*
X294632Y1778997D01*
X295232Y1778331D01*
G01X299332Y1771264D02*
Y1779264D01*
G01X303132D02*
X299332Y1774330D01*
G01X303732Y1771264D02*
X301032Y1776597D01*
G01X317532Y1771264D02*
X316732Y1771397D01*
X316032Y1771931D01*
X315432Y1772731D01*
X315032Y1773664D01*
X314832Y1774731D01*
Y1775797D01*
X315032Y1776864D01*
X315432Y1777797D01*
X316032Y1778597D01*
X316732Y1779131D01*
X317532Y1779264D01*
X318332Y1779131D01*
X319032Y1778597D01*
X319632Y1777797D01*
X320032Y1776864D01*
X320232Y1775797D01*
Y1774731D01*
X320032Y1773664D01*
X319632Y1772731D01*
X319032Y1771931D01*
X318332Y1771397D01*
X317532Y1771264D01*
G01X323532D02*
Y1779264D01*
X325932D01*
X326732Y1778864D01*
X327332Y1777931D01*
X327532Y1776864D01*
X327332Y1775797D01*
X326832Y1774997D01*
X325932Y1774597D01*
X323532D01*
G01X335532Y1771264D02*
X331532D01*
Y1779264D01*
X335532D01*
G01X333932Y1775397D02*
X331532D01*
G01X339232Y1771264D02*
Y1779264D01*
X343832Y1771264D01*
Y1779264D01*
G01X357532Y1771264D02*
X356732Y1771397D01*
X356032Y1771931D01*
X355432Y1772731D01*
X355032Y1773664D01*
X354832Y1774731D01*
Y1775797D01*
X355032Y1776864D01*
X355432Y1777797D01*
X356032Y1778597D01*
X356732Y1779131D01*
X357532Y1779264D01*
X358332Y1779131D01*
X359032Y1778597D01*
X359632Y1777797D01*
X360032Y1776864D01*
X360232Y1775797D01*
Y1774731D01*
X360032Y1773664D01*
X359632Y1772731D01*
X359032Y1771931D01*
X358332Y1771397D01*
X357532Y1771264D01*
G01X363232D02*
Y1779264D01*
X367832Y1771264D01*
Y1779264D01*
G01X382332Y1775531D02*
X382732Y1775931D01*
X383032Y1776597D01*
X383232Y1777531D01*
X383032Y1778331D01*
X382632Y1778864D01*
X381932Y1779264D01*
X379232D01*
Y1771264D01*
X382532D01*
X383232Y1771797D01*
X383632Y1772597D01*
X383832Y1773531D01*
X383632Y1774464D01*
X383032Y1775264D01*
X382332Y1775531D01*
X379232D01*
G01X389532Y1771264D02*
X388732Y1771397D01*
X388032Y1771931D01*
X387432Y1772731D01*
X387032Y1773664D01*
X386832Y1774731D01*
Y1775797D01*
X387032Y1776864D01*
X387432Y1777797D01*
X388032Y1778597D01*
X388732Y1779131D01*
X389532Y1779264D01*
X390332Y1779131D01*
X391032Y1778597D01*
X391632Y1777797D01*
X392032Y1776864D01*
X392232Y1775797D01*
Y1774731D01*
X392032Y1773664D01*
X391632Y1772731D01*
X391032Y1771931D01*
X390332Y1771397D01*
X389532Y1771264D01*
G01X397532Y1779264D02*
Y1771264D01*
G01X395232Y1779264D02*
X399832D01*
G01X403432Y1771264D02*
Y1779264D01*
G01X407632D02*
Y1771264D01*
G01Y1775264D02*
X403432D01*
G01X419432Y1772330D02*
X420232Y1771664D01*
X421132Y1771264D01*
X421932D01*
X422732Y1771664D01*
X423332Y1772330D01*
X423632Y1773264D01*
X423432Y1774197D01*
X422932Y1774997D01*
X422032Y1775531D01*
X420832Y1775797D01*
X420132Y1776331D01*
X419832Y1777264D01*
X420032Y1778197D01*
X420532Y1778864D01*
X421232Y1779264D01*
X421932D01*
X422632Y1778997D01*
X423232Y1778331D01*
G01X428332Y1779264D02*
X430732D01*
G01X429532D02*
Y1771264D01*
G01X428332D02*
X430732D01*
G01X435332D02*
Y1779264D01*
X437332D01*
X438132Y1778864D01*
X438732Y1778331D01*
X439232Y1777531D01*
X439632Y1776597D01*
X439732Y1775264D01*
X439632Y1773931D01*
X439232Y1772997D01*
X438732Y1772197D01*
X438132Y1771664D01*
X437332Y1771264D01*
X435332D01*
G01X447532D02*
X443532D01*
Y1779264D01*
X447532D01*
G01X445932Y1775397D02*
X443532D01*
G01X453532Y1770997D02*
X453332Y1771131D01*
Y1771397D01*
X453532Y1771531D01*
X453732Y1771397D01*
Y1771131D01*
X453532Y1770997D01*
G01X274646Y7012D02*
Y-110000D01*
X269525Y-110153D01*
G01X279528Y52148D02*
Y-108000D01*
G01X275515Y-509D02*
X277515Y-3109D01*
X275415Y-3809D01*
X275515Y-509D01*
X285065Y-31259D01*
G01X273622Y53150D02*
Y59196D01*
G03X271199Y67589I-15749J0D01*
G02X287856I8329J5246D01*
G03X285433Y59196I13326J-8393D01*
G01Y53150D01*
G02X273622I-5905J0D01*
G01Y59196D02*
G03X271199Y67589I-15749J0D01*
G02X287856I8329J5246D01*
G03X285433Y59196I13326J-8393D01*
G01Y53150D01*
G02X273622I-5905J0D01*
G01Y59196D01*
G01X279236Y47250D02*
X273628Y31148D01*
G01X278871Y43208D02*
X279236Y47250D01*
X277012Y43856D01*
X278871Y43208D01*
G01X285434Y53148D02*
Y59195D01*
G01X273622Y53148D02*
G03X285434I5906J0D01*
G01X273622Y59195D02*
Y53148D01*
G01X285434Y59195D02*
G02X287856Y67587I15747J1D01*
G01X271200D02*
G02X273622Y59195I-13327J-8392D01*
G01X287856Y67587D02*
G03X271200I-8328J5246D01*
G01X283268Y628465D02*
G02X291535I4134J0D01*
G02X283268I-4134J0D01*
G01D02*
G02X291535I4134J0D01*
G02X283268I-4134J0D01*
G01X259646Y659961D02*
G02X267913I4134J0D01*
G02X259646I-4134J0D01*
G01D02*
G02X267913I4134J0D01*
G02X259646I-4134J0D01*
G01X303150Y618441D02*
Y710000D01*
X280100Y711000D01*
X280331Y726475D01*
G01X281073Y1106003D02*
X268573D01*
X271073Y1104143D01*
G01X281073D02*
Y1107863D01*
G01X281490Y1118403D02*
X281281Y1118093D01*
X280865D01*
X280656Y1118403D01*
X280865Y1118713D01*
X281281D01*
X281490Y1118403D01*
G01X279198Y1127393D02*
X280240Y1128323D01*
X280865Y1129408D01*
X281073Y1130803D01*
X280656Y1132198D01*
X279823Y1133283D01*
X278365Y1134058D01*
X276698Y1134213D01*
X275031Y1133903D01*
X273990Y1133128D01*
X273156Y1132043D01*
X272948Y1130958D01*
X273156Y1129873D01*
X273990Y1128478D01*
X268573Y1128943D01*
Y1133128D01*
G01X281073Y1139173D02*
X268573D01*
X278990Y1143203D01*
X268573Y1147233D01*
X281073D01*
G01Y1151573D02*
X268573D01*
X278990Y1155603D01*
X268573Y1159633D01*
X281073D01*
G01X324850Y-124350D02*
Y-129000D01*
X312350D01*
Y-124350D01*
G01X324850Y-93350D02*
Y-88700D01*
X312350D01*
Y-93350D01*
G01X296142Y10197D02*
G02X305591I4725J0D01*
G02X296142I-4724J0D01*
G01D02*
G02X305591I4725J0D01*
G02X296142I-4724J0D01*
G01X314669Y555125D02*
X309061Y539023D01*
G01X320866Y561024D02*
G02X309055I-5905J0D01*
G01Y567070D01*
G03X306632Y575463I-15749J0D01*
G02X323289I8329J5246D01*
G03X320866Y567070I13326J-8393D01*
G01Y561024D01*
G01X309055D02*
Y567070D01*
G03X306632Y575463I-15749J0D01*
G02X323289I8329J5246D01*
G03X320866Y567070I13326J-8393D01*
G01Y561024D01*
G02X309055I-5905J0D01*
G01X314304Y551083D02*
X314669Y555125D01*
X312445Y551731D01*
X314304Y551083D01*
G01X309055Y561023D02*
G03X320867I5906J0D01*
G01X309055Y567070D02*
Y561023D01*
G01X306633Y575462D02*
G02X309055Y567070I-13327J-8392D01*
G01X315961Y561023D02*
X415975D01*
G01X314961Y562023D02*
Y719000D01*
X347100D01*
Y732475D01*
G01X323289Y575462D02*
G03X306633I-8328J5246D01*
G01X310149Y638405D02*
X324099Y648505D01*
G01X312761Y641511D02*
X310149Y638405D01*
X313915Y639917D01*
X312761Y641511D01*
G01X299850Y762650D02*
Y758000D01*
X287350D01*
Y762650D01*
G01X299850Y793650D02*
Y798300D01*
X287350D01*
Y793650D01*
G01X289931Y1214811D02*
Y1118992D01*
G01D02*
Y1217764D01*
G01Y1220716D02*
Y1252212D01*
G01D02*
Y1217764D01*
G01X297766Y1365401D02*
Y1377901D01*
X295906Y1375401D01*
G01Y1365401D02*
X299626D01*
G01X310166Y1377901D02*
X308926Y1377484D01*
X307996Y1376443D01*
X307376Y1375193D01*
X306911Y1373526D01*
X306756Y1371651D01*
X306911Y1369776D01*
X307376Y1368109D01*
X307996Y1366859D01*
X308926Y1365818D01*
X310166Y1365401D01*
X311406Y1365818D01*
X312336Y1366859D01*
X312956Y1368109D01*
X313421Y1369776D01*
X313576Y1371651D01*
X313421Y1373526D01*
X312956Y1375193D01*
X312336Y1376443D01*
X311406Y1377484D01*
X310166Y1377901D01*
G01X322566D02*
X321326Y1377484D01*
X320396Y1376443D01*
X319776Y1375193D01*
X319311Y1373526D01*
X319156Y1371651D01*
X319311Y1369776D01*
X319776Y1368109D01*
X320396Y1366859D01*
X321326Y1365818D01*
X322566Y1365401D01*
X323806Y1365818D01*
X324736Y1366859D01*
X325356Y1368109D01*
X325821Y1369776D01*
X325976Y1371651D01*
X325821Y1373526D01*
X325356Y1375193D01*
X324736Y1376443D01*
X323806Y1377484D01*
X322566Y1377901D01*
G01X332951Y1369568D02*
X336981D01*
G01X347366Y1365401D02*
Y1377901D01*
X345506Y1375401D01*
G01Y1365401D02*
X349226D01*
G01X356356Y1367276D02*
X357286Y1366234D01*
X358371Y1365609D01*
X359766Y1365401D01*
X361161Y1365818D01*
X362246Y1366651D01*
X363021Y1368109D01*
X363176Y1369776D01*
X362866Y1371443D01*
X362091Y1372484D01*
X361006Y1373318D01*
X359921Y1373526D01*
X358836Y1373318D01*
X357441Y1372484D01*
X357906Y1377901D01*
X362091D01*
G01X372166D02*
X370926Y1377484D01*
X369996Y1376443D01*
X369376Y1375193D01*
X368911Y1373526D01*
X368756Y1371651D01*
X368911Y1369776D01*
X369376Y1368109D01*
X369996Y1366859D01*
X370926Y1365818D01*
X372166Y1365401D01*
X373406Y1365818D01*
X374336Y1366859D01*
X374956Y1368109D01*
X375421Y1369776D01*
X375576Y1371651D01*
X375421Y1373526D01*
X374956Y1375193D01*
X374336Y1376443D01*
X373406Y1377484D01*
X372166Y1377901D01*
G01X380536Y1365401D02*
Y1377901D01*
X384566Y1367484D01*
X388596Y1377901D01*
Y1365401D01*
G01X392936D02*
Y1377901D01*
X396966Y1367484D01*
X400996Y1377901D01*
Y1365401D01*
G01X337000Y-995000D02*
Y-1070000D01*
G01X335000Y-995000D02*
Y-1070000D01*
G01X342507Y-1055000D02*
Y-1050000D01*
X343773D01*
X344280Y-1050250D01*
X344660Y-1050583D01*
X344977Y-1051083D01*
X345230Y-1051667D01*
X345293Y-1052500D01*
X345230Y-1053333D01*
X344977Y-1053917D01*
X344660Y-1054417D01*
X344280Y-1054750D01*
X343773Y-1055000D01*
X342507D01*
G01X347417D02*
X349000Y-1050000D01*
X350583Y-1055000D01*
G01X350013Y-1053250D02*
X347987D01*
G01X354100Y-1050000D02*
Y-1055000D01*
G01X352643Y-1050000D02*
X355557D01*
G01X360467Y-1055000D02*
X357933D01*
Y-1050000D01*
X360467D01*
G01X359453Y-1052417D02*
X357933D01*
G01X364300Y-1055167D02*
X364173Y-1055083D01*
Y-1054917D01*
X364300Y-1054833D01*
X364427Y-1054917D01*
Y-1055083D01*
X364300Y-1055167D01*
G01Y-1052917D02*
X364173Y-1052833D01*
Y-1052667D01*
X364300Y-1052583D01*
X364427Y-1052667D01*
Y-1052833D01*
X364300Y-1052917D01*
G01X337000Y-1045000D02*
X537000D01*
G01X342633Y-1030000D02*
Y-1025000D01*
X344153D01*
X344660Y-1025250D01*
X345040Y-1025833D01*
X345167Y-1026500D01*
X345040Y-1027167D01*
X344723Y-1027667D01*
X344153Y-1027917D01*
X342633D01*
G01X347860Y-1030167D02*
X350140Y-1025000D01*
G01X352643Y-1030000D02*
Y-1025000D01*
X355557Y-1030000D01*
Y-1025000D01*
G01X359200Y-1030167D02*
X359073Y-1030083D01*
Y-1029917D01*
X359200Y-1029833D01*
X359327Y-1029917D01*
Y-1030083D01*
X359200Y-1030167D01*
G01Y-1027917D02*
X359073Y-1027833D01*
Y-1027667D01*
X359200Y-1027583D01*
X359327Y-1027667D01*
Y-1027833D01*
X359200Y-1027917D01*
G01X342633Y-1005000D02*
Y-1000000D01*
X344153D01*
X344660Y-1000250D01*
X345040Y-1000833D01*
X345167Y-1001500D01*
X345040Y-1002167D01*
X344723Y-1002667D01*
X344153Y-1002917D01*
X342633D01*
G01X347733Y-1005000D02*
Y-1000000D01*
X349317D01*
X349823Y-1000250D01*
X350140Y-1000583D01*
X350267Y-1001250D01*
X350140Y-1001917D01*
X349760Y-1002333D01*
X349317Y-1002583D01*
X347733D01*
G01X349317D02*
X350267Y-1005000D01*
G01X354100D02*
X353593Y-1004917D01*
X353150Y-1004583D01*
X352770Y-1004083D01*
X352517Y-1003500D01*
X352390Y-1002833D01*
Y-1002167D01*
X352517Y-1001500D01*
X352770Y-1000917D01*
X353150Y-1000417D01*
X353593Y-1000083D01*
X354100Y-1000000D01*
X354607Y-1000083D01*
X355050Y-1000417D01*
X355430Y-1000917D01*
X355683Y-1001500D01*
X355810Y-1002167D01*
Y-1002833D01*
X355683Y-1003500D01*
X355430Y-1004083D01*
X355050Y-1004583D01*
X354607Y-1004917D01*
X354100Y-1005000D01*
G01X357933Y-1004000D02*
X358250Y-1004500D01*
X358630Y-1004833D01*
X359073Y-1005000D01*
X359580Y-1004833D01*
X359960Y-1004500D01*
X360340Y-1004000D01*
X360467Y-1003333D01*
Y-1000000D01*
G01X365567Y-1005000D02*
X363033D01*
Y-1000000D01*
X365567D01*
G01X364553Y-1002417D02*
X363033D01*
G01X370793Y-1000417D02*
X370413Y-1000167D01*
X369970Y-1000000D01*
X369463D01*
X368893Y-1000250D01*
X368450Y-1000667D01*
X368133Y-1001167D01*
X367880Y-1002000D01*
X367817Y-1002750D01*
X367943Y-1003500D01*
X368133Y-1004000D01*
X368513Y-1004500D01*
X368957Y-1004833D01*
X369400Y-1005000D01*
X369843D01*
X370287Y-1004833D01*
X370667Y-1004583D01*
X370983Y-1004250D01*
G01X374500Y-1000000D02*
Y-1005000D01*
G01X373043Y-1000000D02*
X375957D01*
G01X379600Y-1005167D02*
X379473Y-1005083D01*
Y-1004917D01*
X379600Y-1004833D01*
X379727Y-1004917D01*
Y-1005083D01*
X379600Y-1005167D01*
G01Y-1002917D02*
X379473Y-1002833D01*
Y-1002667D01*
X379600Y-1002583D01*
X379727Y-1002667D01*
Y-1002833D01*
X379600Y-1002917D01*
G01X337000Y-1020000D02*
X537000D01*
G01X320867Y567070D02*
G02X323289Y575462I15747J1D01*
G01X320867Y561023D02*
Y567070D01*
G01X350532Y1208064D02*
X352532D01*
Y1205664D01*
X351932Y1204864D01*
X351232Y1204331D01*
X350232Y1204064D01*
X349232Y1204331D01*
X348532Y1204864D01*
X347932Y1205664D01*
X347532Y1206597D01*
X347332Y1207664D01*
Y1208597D01*
X347532Y1209397D01*
X347932Y1210331D01*
X348532Y1211131D01*
X349132Y1211664D01*
X349932Y1212064D01*
X350632D01*
X351432Y1211797D01*
X352032Y1211264D01*
G01X355932Y1204064D02*
Y1212064D01*
X358432D01*
X359232Y1211664D01*
X359732Y1211131D01*
X359932Y1210064D01*
X359732Y1208997D01*
X359132Y1208331D01*
X358432Y1207931D01*
X355932D01*
G01X358432D02*
X359932Y1204064D01*
G01X365932D02*
X365132Y1204197D01*
X364432Y1204731D01*
X363832Y1205531D01*
X363432Y1206464D01*
X363232Y1207531D01*
Y1208597D01*
X363432Y1209664D01*
X363832Y1210597D01*
X364432Y1211397D01*
X365132Y1211931D01*
X365932Y1212064D01*
X366732Y1211931D01*
X367432Y1211397D01*
X368032Y1210597D01*
X368432Y1209664D01*
X368632Y1208597D01*
Y1207531D01*
X368432Y1206464D01*
X368032Y1205531D01*
X367432Y1204731D01*
X366732Y1204197D01*
X365932Y1204064D01*
G01X371732Y1212064D02*
Y1206331D01*
X372132Y1205130D01*
X372932Y1204331D01*
X373932Y1204064D01*
X374932Y1204331D01*
X375732Y1205130D01*
X376132Y1206331D01*
Y1212064D01*
G01X379932Y1204064D02*
Y1212064D01*
X382332D01*
X383132Y1211664D01*
X383732Y1210731D01*
X383932Y1209664D01*
X383732Y1208597D01*
X383232Y1207797D01*
X382332Y1207397D01*
X379932D01*
G01X387832Y1205130D02*
X388632Y1204464D01*
X389532Y1204064D01*
X390332D01*
X391132Y1204464D01*
X391732Y1205130D01*
X392032Y1206064D01*
X391832Y1206997D01*
X391332Y1207797D01*
X390432Y1208331D01*
X389232Y1208597D01*
X388532Y1209131D01*
X388232Y1210064D01*
X388432Y1210997D01*
X388932Y1211664D01*
X389632Y1212064D01*
X390332D01*
X391032Y1211797D01*
X391632Y1211131D01*
G01X406732Y1208331D02*
X407132Y1208731D01*
X407432Y1209397D01*
X407632Y1210331D01*
X407432Y1211131D01*
X407032Y1211664D01*
X406332Y1212064D01*
X403632D01*
Y1204064D01*
X406932D01*
X407632Y1204597D01*
X408032Y1205397D01*
X408232Y1206331D01*
X408032Y1207264D01*
X407432Y1208064D01*
X406732Y1208331D01*
X403632D01*
G01X372600Y166996D02*
X431655D01*
Y135500D01*
X372600D01*
Y166996D01*
G01X365850Y768650D02*
Y764000D01*
X353350D01*
Y768650D01*
G01X365850Y799650D02*
Y804300D01*
X353350D01*
Y799650D01*
G01X642642Y1362449D02*
X347366D01*
G01X393410Y338590D02*
X387802Y322488D01*
G01X387795Y344488D02*
Y350535D01*
G03X385373Y358928I-15748J1D01*
G02X402029I8328J5245D01*
G03X399606Y350535I13326J-8393D01*
G01Y344488D01*
G02X387795I-5905J0D01*
G01Y350535D02*
G03X385373Y358928I-15748J1D01*
G02X402029I8328J5245D01*
G03X399606Y350535I13326J-8393D01*
G01Y344488D01*
G02X387795I-5905J0D01*
G01Y350535D01*
G01X393045Y334548D02*
X393410Y338590D01*
X391186Y335196D01*
X393045Y334548D01*
G01X399608Y350535D02*
G02X402030Y358927I15747J1D01*
G01X399608Y344488D02*
Y350535D01*
G01X387796Y344488D02*
G03X399608I5906J0D01*
G01X387796Y350535D02*
Y344488D01*
G01X385374Y358927D02*
G02X387796Y350535I-13327J-8392D01*
G01X402030Y358927D02*
G03X385374I-8328J5246D01*
G01X393702Y345488D02*
Y454975D01*
G01X412452Y484950D02*
Y480300D01*
X399952D01*
Y484950D01*
G01X412452Y528350D02*
Y533000D01*
X399952D01*
Y528350D01*
G01X433550Y542273D02*
X428900D01*
Y554773D01*
X433550D01*
G01X423800Y598691D02*
X419150D01*
Y611191D01*
X423800D01*
G01X452000Y-1045000D02*
Y-1070000D01*
G01X454633Y-1047500D02*
Y-1052500D01*
X457167D01*
G01X460240Y-1047500D02*
X461760D01*
G01X461000D02*
Y-1052500D01*
G01X460240D02*
X461760D01*
G01X466607Y-1049833D02*
X466860Y-1049583D01*
X467050Y-1049167D01*
X467177Y-1048583D01*
X467050Y-1048083D01*
X466797Y-1047750D01*
X466353Y-1047500D01*
X464643D01*
Y-1052500D01*
X466733D01*
X467177Y-1052167D01*
X467430Y-1051667D01*
X467557Y-1051083D01*
X467430Y-1050500D01*
X467050Y-1050000D01*
X466607Y-1049833D01*
X464643D01*
G01X471200Y-1052667D02*
X471073Y-1052583D01*
Y-1052417D01*
X471200Y-1052333D01*
X471327Y-1052417D01*
Y-1052583D01*
X471200Y-1052667D01*
G01Y-1050417D02*
X471073Y-1050333D01*
Y-1050167D01*
X471200Y-1050083D01*
X471327Y-1050167D01*
Y-1050333D01*
X471200Y-1050417D01*
G01X495000Y-1045000D02*
Y-1070000D01*
G01X498900Y-1047500D02*
Y-1052500D01*
G01X497443Y-1047500D02*
X500357D01*
G01X504000Y-1052500D02*
X503620Y-1052417D01*
X503240Y-1052083D01*
X502987Y-1051500D01*
X502860Y-1050833D01*
X502987Y-1050167D01*
X503240Y-1049583D01*
X503620Y-1049250D01*
X504000Y-1049167D01*
X504380Y-1049250D01*
X504760Y-1049583D01*
X505013Y-1050167D01*
X505077Y-1050833D01*
X505013Y-1051500D01*
X504760Y-1052083D01*
X504380Y-1052417D01*
X504000Y-1052500D01*
G01X509100D02*
X508720Y-1052417D01*
X508340Y-1052083D01*
X508087Y-1051500D01*
X507960Y-1050833D01*
X508087Y-1050167D01*
X508340Y-1049583D01*
X508720Y-1049250D01*
X509100Y-1049167D01*
X509480Y-1049250D01*
X509860Y-1049583D01*
X510113Y-1050167D01*
X510177Y-1050833D01*
X510113Y-1051500D01*
X509860Y-1052083D01*
X509480Y-1052417D01*
X509100Y-1052500D01*
G01X514200D02*
Y-1047500D01*
G01X519300Y-1052667D02*
X519173Y-1052583D01*
Y-1052417D01*
X519300Y-1052333D01*
X519427Y-1052417D01*
Y-1052583D01*
X519300Y-1052667D01*
G01Y-1050417D02*
X519173Y-1050333D01*
Y-1050167D01*
X519300Y-1050083D01*
X519427Y-1050167D01*
Y-1050333D01*
X519300Y-1050417D01*
G01X495000Y-1020000D02*
Y-1045000D01*
G01X497633Y-1027500D02*
Y-1022500D01*
X499217D01*
X499723Y-1022750D01*
X500040Y-1023083D01*
X500167Y-1023750D01*
X500040Y-1024417D01*
X499660Y-1024833D01*
X499217Y-1025083D01*
X497633D01*
G01X499217D02*
X500167Y-1027500D01*
G01X505267D02*
X502733D01*
Y-1022500D01*
X505267D01*
G01X504253Y-1024917D02*
X502733D01*
G01X507517Y-1022500D02*
X509100Y-1027500D01*
X510683Y-1022500D01*
G01X514200Y-1027667D02*
X514073Y-1027583D01*
Y-1027417D01*
X514200Y-1027333D01*
X514327Y-1027417D01*
Y-1027583D01*
X514200Y-1027667D01*
G01Y-1025417D02*
X514073Y-1025333D01*
Y-1025167D01*
X514200Y-1025083D01*
X514327Y-1025167D01*
Y-1025333D01*
X514200Y-1025417D01*
G01X503013Y-1073167D02*
X503120Y-1073042D01*
X503200Y-1072833D01*
X503253Y-1072542D01*
X503200Y-1072292D01*
X503093Y-1072125D01*
X502907Y-1072000D01*
X502187D01*
Y-1074500D01*
X503067D01*
X503253Y-1074333D01*
X503360Y-1074083D01*
X503413Y-1073792D01*
X503360Y-1073500D01*
X503200Y-1073250D01*
X503013Y-1073167D01*
X502187D01*
G01X505480Y-1074500D02*
Y-1072833D01*
G01Y-1073125D02*
X505373Y-1072958D01*
X505213Y-1072875D01*
X505027Y-1072833D01*
X504840Y-1072917D01*
X504680Y-1073083D01*
X504573Y-1073333D01*
X504520Y-1073667D01*
X504573Y-1074000D01*
X504680Y-1074250D01*
X504840Y-1074417D01*
X505027Y-1074500D01*
X505213Y-1074458D01*
X505373Y-1074333D01*
X505480Y-1074167D01*
G01X506800Y-1074208D02*
X506933Y-1074375D01*
X507120Y-1074500D01*
X507280D01*
X507440Y-1074417D01*
X507547Y-1074292D01*
X507600Y-1074125D01*
X507573Y-1073875D01*
X507467Y-1073750D01*
X506987Y-1073500D01*
X506880Y-1073208D01*
X506933Y-1073000D01*
X507040Y-1072875D01*
X507200Y-1072833D01*
X507360Y-1072875D01*
X507520Y-1073000D01*
G01X509000Y-1073375D02*
X509853D01*
X509773Y-1073083D01*
X509640Y-1072917D01*
X509453Y-1072833D01*
X509267Y-1072875D01*
X509107Y-1073000D01*
X509000Y-1073292D01*
X508947Y-1073542D01*
Y-1073792D01*
X509000Y-1074042D01*
X509133Y-1074292D01*
X509293Y-1074458D01*
X509480Y-1074500D01*
X509667Y-1074417D01*
X509853Y-1074167D01*
G01X511120Y-1074500D02*
Y-1072000D01*
G01Y-1073250D02*
X511253Y-1073000D01*
X511413Y-1072875D01*
X511573Y-1072833D01*
X511813Y-1072917D01*
X511973Y-1073083D01*
X512080Y-1073375D01*
Y-1073708D01*
X512027Y-1074042D01*
X511920Y-1074292D01*
X511733Y-1074458D01*
X511573Y-1074500D01*
X511413Y-1074458D01*
X511253Y-1074333D01*
X511120Y-1074125D01*
G01X513800Y-1074500D02*
X513640Y-1074458D01*
X513480Y-1074292D01*
X513373Y-1074000D01*
X513320Y-1073667D01*
X513373Y-1073333D01*
X513480Y-1073042D01*
X513640Y-1072875D01*
X513800Y-1072833D01*
X513960Y-1072875D01*
X514120Y-1073042D01*
X514227Y-1073333D01*
X514253Y-1073667D01*
X514227Y-1074000D01*
X514120Y-1074292D01*
X513960Y-1074458D01*
X513800Y-1074500D01*
G01X516480D02*
Y-1072833D01*
G01Y-1073125D02*
X516373Y-1072958D01*
X516213Y-1072875D01*
X516027Y-1072833D01*
X515840Y-1072917D01*
X515680Y-1073083D01*
X515573Y-1073333D01*
X515520Y-1073667D01*
X515573Y-1074000D01*
X515680Y-1074250D01*
X515840Y-1074417D01*
X516027Y-1074500D01*
X516213Y-1074458D01*
X516373Y-1074333D01*
X516480Y-1074167D01*
G01X517827Y-1074500D02*
Y-1072833D01*
G01Y-1073167D02*
X517960Y-1073000D01*
X518093Y-1072875D01*
X518280Y-1072833D01*
X518413Y-1072875D01*
X518573Y-1073000D01*
G01X520880Y-1072000D02*
Y-1074500D01*
G01Y-1074125D02*
X520773Y-1074333D01*
X520613Y-1074458D01*
X520427Y-1074500D01*
X520213Y-1074417D01*
X520053Y-1074208D01*
X519947Y-1073958D01*
X519920Y-1073667D01*
X519947Y-1073375D01*
X520053Y-1073125D01*
X520213Y-1072917D01*
X520427Y-1072833D01*
X520613Y-1072875D01*
X520747Y-1072958D01*
X520880Y-1073125D01*
G01X524267Y-1074500D02*
Y-1072000D01*
X524933D01*
X525147Y-1072125D01*
X525280Y-1072292D01*
X525333Y-1072625D01*
X525280Y-1072958D01*
X525120Y-1073167D01*
X524933Y-1073292D01*
X524267D01*
G01X524933D02*
X525333Y-1074500D01*
G01X526600Y-1073375D02*
X527453D01*
X527373Y-1073083D01*
X527240Y-1072917D01*
X527053Y-1072833D01*
X526867Y-1072875D01*
X526707Y-1073000D01*
X526600Y-1073292D01*
X526547Y-1073542D01*
Y-1073792D01*
X526600Y-1074042D01*
X526733Y-1074292D01*
X526893Y-1074458D01*
X527080Y-1074500D01*
X527267Y-1074417D01*
X527453Y-1074167D01*
G01X528720Y-1072833D02*
X529200Y-1074500D01*
X529680Y-1072833D01*
G01X531400Y-1074583D02*
X531347Y-1074542D01*
Y-1074458D01*
X531400Y-1074417D01*
X531453Y-1074458D01*
Y-1074542D01*
X531400Y-1074583D01*
G01X533600Y-1074500D02*
X533787Y-1074458D01*
X534000Y-1074333D01*
X534133Y-1074125D01*
X534187Y-1073833D01*
X534133Y-1073542D01*
X533973Y-1073292D01*
X533733Y-1073167D01*
X533467D01*
X533307Y-1073083D01*
X533173Y-1072875D01*
X533120Y-1072583D01*
X533200Y-1072292D01*
X533387Y-1072083D01*
X533600Y-1072000D01*
X533813Y-1072083D01*
X534000Y-1072292D01*
X534080Y-1072583D01*
X534027Y-1072875D01*
X533893Y-1073083D01*
X533733Y-1073167D01*
X533467D01*
X533227Y-1073292D01*
X533067Y-1073542D01*
X533013Y-1073833D01*
X533067Y-1074125D01*
X533200Y-1074333D01*
X533413Y-1074458D01*
X533600Y-1074500D01*
G01X536013Y-1073167D02*
X536120Y-1073042D01*
X536200Y-1072833D01*
X536253Y-1072542D01*
X536200Y-1072292D01*
X536093Y-1072125D01*
X535907Y-1072000D01*
X535187D01*
Y-1074500D01*
X536067D01*
X536253Y-1074333D01*
X536360Y-1074083D01*
X536413Y-1073792D01*
X536360Y-1073500D01*
X536200Y-1073250D01*
X536013Y-1073167D01*
X535187D01*
G01X501750Y542273D02*
X506400D01*
Y554773D01*
X501750D01*
G01X504400Y598691D02*
X509050D01*
Y611191D01*
X504400D01*
G01X601142Y413386D02*
X546890D01*
Y483386D01*
X601142D01*
Y413386D01*
G01X546890Y451890D02*
Y483386D01*
G01Y451890D02*
Y483386D01*
G01X589992Y1341264D02*
Y1353764D01*
X584257Y1344806D01*
X592007D01*
G01X596502Y1341264D02*
Y1353764D01*
X600532Y1343347D01*
X604562Y1353764D01*
Y1341264D01*
G01X608902D02*
Y1353764D01*
X612932Y1343347D01*
X616962Y1353764D01*
Y1341264D01*
G01X626894Y1334890D02*
X595398D01*
G01D02*
X634768D01*
G01X626894Y1260086D02*
X642642Y1267960D01*
G01X678075Y1279771D02*
X634768D01*
G01X678075Y1275834D02*
X634768D01*
G01X642642Y1291582D02*
Y1342764D01*
G01Y1291582D02*
Y1370323D01*
G01Y1287646D02*
X626894Y1295520D01*
G01X642642Y1267960D02*
X626894Y1275834D01*
G01Y1279771D02*
X642642Y1287646D01*
G01X626894Y1299457D02*
Y1342764D01*
G01X642642Y1334890D02*
X674138D01*
G01D02*
X634768D01*
G01X682632Y1242064D02*
X670132D01*
X672632Y1240204D01*
G01X682632D02*
Y1243924D01*
G01Y1250434D02*
X670132D01*
X680549Y1254464D01*
X670132Y1258494D01*
X682632D01*
G01Y1262834D02*
X670132D01*
X680549Y1266864D01*
X670132Y1270894D01*
X682632D01*
G01X658694Y1236657D02*
Y1279964D01*
G01X702632Y1277864D02*
X704632D01*
Y1275464D01*
X704032Y1274664D01*
X703332Y1274131D01*
X702332Y1273864D01*
X701332Y1274131D01*
X700632Y1274664D01*
X700032Y1275464D01*
X699632Y1276397D01*
X699432Y1277464D01*
Y1278397D01*
X699632Y1279197D01*
X700032Y1280131D01*
X700632Y1280931D01*
X701232Y1281464D01*
X702032Y1281864D01*
X702732D01*
X703532Y1281597D01*
X704132Y1281064D01*
G01X708032Y1273864D02*
Y1281864D01*
X710532D01*
X711332Y1281464D01*
X711832Y1280931D01*
X712032Y1279864D01*
X711832Y1278797D01*
X711232Y1278131D01*
X710532Y1277731D01*
X708032D01*
G01X710532D02*
X712032Y1273864D01*
G01X718032D02*
X717232Y1273997D01*
X716532Y1274531D01*
X715932Y1275331D01*
X715532Y1276264D01*
X715332Y1277331D01*
Y1278397D01*
X715532Y1279464D01*
X715932Y1280397D01*
X716532Y1281197D01*
X717232Y1281731D01*
X718032Y1281864D01*
X718832Y1281731D01*
X719532Y1281197D01*
X720132Y1280397D01*
X720532Y1279464D01*
X720732Y1278397D01*
Y1277331D01*
X720532Y1276264D01*
X720132Y1275331D01*
X719532Y1274531D01*
X718832Y1273997D01*
X718032Y1273864D01*
G01X723832Y1281864D02*
Y1276131D01*
X724232Y1274930D01*
X725032Y1274131D01*
X726032Y1273864D01*
X727032Y1274131D01*
X727832Y1274930D01*
X728232Y1276131D01*
Y1281864D01*
G01X732032Y1273864D02*
Y1281864D01*
X734432D01*
X735232Y1281464D01*
X735832Y1280531D01*
X736032Y1279464D01*
X735832Y1278397D01*
X735332Y1277597D01*
X734432Y1277197D01*
X732032D01*
G01X739932Y1274930D02*
X740732Y1274264D01*
X741632Y1273864D01*
X742432D01*
X743232Y1274264D01*
X743832Y1274930D01*
X744132Y1275864D01*
X743932Y1276797D01*
X743432Y1277597D01*
X742532Y1278131D01*
X741332Y1278397D01*
X740632Y1278931D01*
X740332Y1279864D01*
X740532Y1280797D01*
X741032Y1281464D01*
X741732Y1281864D01*
X742432D01*
X743132Y1281597D01*
X743732Y1280931D01*
G01X755532Y1273864D02*
X758032Y1281864D01*
X760532Y1273864D01*
G01X759632Y1276664D02*
X756432D01*
G01X742126Y64961D02*
Y71007D01*
G03X739703Y79400I-15749J0D01*
G02X756360I8329J5246D01*
G03X753937Y71007I13326J-8393D01*
G01Y64961D01*
G02X742126I-5905J0D01*
G01Y71007D02*
G03X739703Y79400I-15749J0D01*
G02X756360I8329J5246D01*
G03X753937Y71007I13326J-8393D01*
G01Y64961D01*
G02X742126I-5905J0D01*
G01Y71007D01*
G01X739704Y79400D02*
G02X742126Y71008I-13327J-8392D01*
G01X756360Y79400D02*
G03X739704I-8328J5246D01*
G01X753937Y344488D02*
G02X742126I-5905J0D01*
G01Y350535D01*
G03X739703Y358928I-15749J0D01*
G02X756360I8329J5246D01*
G03X753937Y350535I13326J-8393D01*
G01Y344488D01*
G01X742126D02*
Y350535D01*
G03X739703Y358928I-15749J0D01*
G02X756360I8329J5246D01*
G03X753937Y350535I13326J-8393D01*
G01Y344488D01*
G02X742126I-5905J0D01*
G01X739704Y358927D02*
G02X742126Y350535I-13327J-8392D01*
G01X756360Y358927D02*
G03X739704I-8328J5246D01*
G01X747740Y59063D02*
X742132Y42961D01*
G01X747375Y55021D02*
X747740Y59063D01*
X745516Y55669D01*
X747375Y55021D01*
G01X753938Y71008D02*
G02X756360Y79400I15747J1D01*
G01X753938Y64961D02*
Y71008D01*
G01X742126Y64961D02*
G03X753938I5906J0D01*
G01X742126Y71008D02*
Y64961D01*
G01X747740Y338590D02*
X742132Y322488D01*
G01X747375Y334548D02*
X747740Y338590D01*
X745516Y335196D01*
X747375Y334548D01*
G01X753938Y350535D02*
G02X756360Y358927I15747J1D01*
G01X753938Y344488D02*
Y350535D01*
G01X742126Y344488D02*
G03X753938I5906J0D01*
G01X742126Y350535D02*
Y344488D01*
G01X748032Y345488D02*
Y450975D01*
G01X766782Y480950D02*
Y476300D01*
X754282D01*
Y480950D01*
G01X766782Y524350D02*
Y529000D01*
X754282D01*
Y524350D01*
G01X826787Y131984D02*
X787987D01*
Y270384D01*
X826787D01*
Y131984D01*
G01X813780Y88465D02*
G02X830394I8307J0D01*
G02X813780I-8307J0D01*
G01D02*
G02X830394I8307J0D01*
G02X813780I-8307J0D01*
G01X823720Y129532D02*
X824220Y127232D01*
X825520Y127932D01*
X823720Y129532D01*
X859770Y59232D01*
G01X813780Y313504D02*
G02X830394I8307J0D01*
G02X813780I-8307J0D01*
G01D02*
G02X830394I8307J0D01*
G02X813780I-8307J0D01*
G01X859770Y59232D02*
Y29634D01*
G01X890797Y61584D02*
Y30864D01*
G01X926847Y131884D02*
X926347Y129584D01*
X925047Y130284D01*
X926847Y131884D01*
X890797Y61584D01*
G01X944897Y131984D02*
X906097D01*
Y270384D01*
X944897D01*
Y131984D01*
G01X931890Y88465D02*
G02X948504I8307J0D01*
G02X931890I-8307J0D01*
G01D02*
G02X948504I8307J0D01*
G02X931890I-8307J0D01*
G01Y313504D02*
G02X948504I8307J0D01*
G02X931890I-8307J0D01*
G01D02*
G02X948504I8307J0D01*
G02X931890I-8307J0D01*
G01X932550Y1007250D02*
X927900D01*
Y1019750D01*
X932550D01*
G01X983960Y59063D02*
X978352Y42961D01*
G01X983595Y55021D02*
X983960Y59063D01*
X981736Y55669D01*
X983595Y55021D01*
G01X978346Y64961D02*
Y71007D01*
G03X975924Y79400I-15748J1D01*
G02X992580I8328J5245D01*
G03X990157Y71007I13326J-8393D01*
G01Y64961D01*
G02X978346I-5906J0D01*
G01Y71007D02*
G03X975924Y79400I-15748J1D01*
G02X992580I8328J5245D01*
G03X990157Y71007I13326J-8393D01*
G01Y64961D01*
G02X978346I-5906J0D01*
G01Y71007D01*
G01Y64961D02*
G03X990158I5906J0D01*
G01X978346Y71008D02*
Y64961D01*
G01X975924Y79400D02*
G02X978346Y71008I-13327J-8392D01*
G01X992580Y79400D02*
G03X975924I-8328J5246D01*
G01X983960Y338590D02*
X978352Y322488D01*
G01X978346Y344488D02*
Y350535D01*
G03X975924Y358928I-15748J1D01*
G02X992580I8328J5245D01*
G03X990157Y350535I13326J-8393D01*
G01Y344488D01*
G02X978346I-5906J0D01*
G01Y350535D02*
G03X975924Y358928I-15748J1D01*
G02X992580I8328J5245D01*
G03X990157Y350535I13326J-8393D01*
G01Y344488D01*
G02X978346I-5906J0D01*
G01Y350535D01*
G01X983595Y334548D02*
X983960Y338590D01*
X981736Y335196D01*
X983595Y334548D01*
G01X978346Y344488D02*
G03X990158I5906J0D01*
G01X978346Y350535D02*
Y344488D01*
G01X975924Y358927D02*
G02X978346Y350535I-13327J-8392D01*
G01X992580Y358927D02*
G03X975924I-8328J5246D01*
G01X975950Y1007250D02*
X980600D01*
Y1019750D01*
X975950D01*
G01X990158Y71008D02*
G02X992580Y79400I15747J1D01*
G01X990158Y64961D02*
Y71008D01*
G01Y350535D02*
G02X992580Y358927I15747J1D01*
G01X990158Y344488D02*
Y350535D01*
G01X984252Y345488D02*
Y454975D01*
G01X1003002Y484950D02*
Y480300D01*
X990502D01*
Y484950D01*
G01X1003002Y528350D02*
Y533000D01*
X990502D01*
Y528350D01*
G01X1011825Y1026000D02*
X1874016D01*
G01X1200550Y542273D02*
X1195900D01*
Y554773D01*
X1200550D01*
G01X1268750Y542273D02*
X1273400D01*
Y554773D01*
X1268750D01*
G01X1416324Y561023D02*
X1286025D01*
G01X1338292Y338590D02*
X1332684Y322488D01*
G01X1344488Y344488D02*
G02X1332677I-5905J0D01*
G01Y350535D01*
G03X1330254Y358928I-15749J0D01*
G02X1346911I8329J5246D01*
G03X1344488Y350535I13326J-8393D01*
G01Y344488D01*
G01X1332677D02*
Y350535D01*
G03X1330254Y358928I-15749J0D01*
G02X1346911I8329J5246D01*
G03X1344488Y350535I13326J-8393D01*
G01Y344488D01*
G02X1332677I-5905J0D01*
G01X1337927Y334548D02*
X1338292Y338590D01*
X1336068Y335196D01*
X1337927Y334548D01*
G01X1344490Y350535D02*
G02X1346912Y358927I15747J1D01*
G01X1344490Y344488D02*
Y350535D01*
G01X1332678Y344488D02*
G03X1344490I5906J0D01*
G01X1332678Y350535D02*
Y344488D01*
G01X1330256Y358927D02*
G02X1332678Y350535I-13327J-8392D01*
G01X1346912Y358927D02*
G03X1330256I-8328J5246D01*
G01X1338584Y345488D02*
Y440775D01*
G01X1357334Y476950D02*
Y472300D01*
X1344834D01*
Y476950D01*
G01X1357334Y520350D02*
Y525000D01*
X1344834D01*
Y520350D01*
G01X1418224Y634135D02*
X1401218Y636857D01*
G01X1426693Y15512D02*
G02X1436142I4724J0D01*
G02X1426693I-4725J0D01*
G01D02*
G02X1436142I4724J0D01*
G02X1426693I-4725J0D01*
G01X1417032Y555125D02*
X1411424Y539023D01*
G01X1423228Y561024D02*
G02X1411417I-5906J0D01*
G01Y567070D01*
G03X1408995Y575463I-15748J1D01*
G02X1425651I8328J5245D01*
G03X1423228Y567070I13326J-8393D01*
G01Y561024D01*
G01X1411417D02*
Y567070D01*
G03X1408995Y575463I-15748J1D01*
G02X1425651I8328J5245D01*
G03X1423228Y567070I13326J-8393D01*
G01Y561024D01*
G02X1411417I-5906J0D01*
G01X1416667Y551083D02*
X1417032Y555125D01*
X1414808Y551731D01*
X1416667Y551083D01*
G01X1423230Y567070D02*
G02X1425652Y575462I15747J1D01*
G01X1423230Y561023D02*
Y567070D01*
G01X1411418Y561023D02*
G03X1423230I5906J0D01*
G01X1411418Y567070D02*
Y561023D01*
G01X1408996Y575462D02*
G02X1411418Y567070I-13327J-8392D01*
G01X1417324Y562023D02*
Y694775D01*
G01X1425652Y575462D02*
G03X1408996I-8328J5246D01*
G01X1487152Y613691D02*
X1425102D01*
Y667791D01*
X1487152D01*
Y613691D01*
G01X1414181Y633786D02*
X1418224Y634135D01*
X1414492Y635729D01*
X1414181Y633786D01*
G01X1436074Y730950D02*
Y726300D01*
X1423574D01*
Y730950D01*
G01X1436074Y774350D02*
Y779000D01*
X1423574D01*
Y774350D01*
G01X1471506Y-149550D02*
Y-154200D01*
X1459006D01*
Y-149550D01*
G01X1471506Y-106150D02*
Y-101500D01*
X1459006D01*
Y-106150D01*
G01X1452756Y52149D02*
Y-70275D01*
G01X1454212Y-3050D02*
X1456212Y-5650D01*
X1454112Y-6350D01*
X1454212Y-3050D01*
X1463762Y-33800D01*
G01X1483997Y27112D02*
Y4112D01*
X1437897D01*
Y27112D01*
X1483997D01*
G01X1446850Y53150D02*
Y59196D01*
G03X1444428Y67589I-15748J1D01*
G02X1461084I8328J5245D01*
G03X1458661Y59196I13326J-8393D01*
G01Y53150D01*
G02X1446850I-5905J0D01*
G01Y59196D02*
G03X1444428Y67589I-15748J1D01*
G02X1461084I8328J5245D01*
G03X1458661Y59196I13326J-8393D01*
G01Y53150D01*
G02X1446850I-5905J0D01*
G01Y59196D01*
G01X1452464Y47251D02*
X1446856Y31149D01*
G01X1452099Y43209D02*
X1452464Y47251D01*
X1450240Y43857D01*
X1452099Y43209D01*
G01X1458662Y53149D02*
Y59196D01*
G01X1446850Y53149D02*
G03X1458662I5906J0D01*
G01X1446850Y59196D02*
Y53149D01*
G01X1458662Y59196D02*
G02X1461084Y67588I15747J1D01*
G01X1444428D02*
G02X1446850Y59196I-13327J-8392D01*
G01X1461084Y67588D02*
G03X1444428I-8328J5246D01*
G01X1464370Y628465D02*
G02X1472638I4134J0D01*
G02X1464370I-4134J0D01*
G01D02*
G02X1472638I4134J0D01*
G02X1464370I-4134J0D01*
G01X1440748Y659961D02*
G02X1449016I4134J0D01*
G02X1440748I-4134J0D01*
G01D02*
G02X1449016I4134J0D01*
G02X1440748I-4134J0D01*
G01X1486693Y10197D02*
G02X1496142I4725J0D01*
G02X1486693I-4725J0D01*
G01D02*
G02X1496142I4725J0D01*
G02X1486693I-4725J0D01*
G01X1505957Y614341D02*
Y667341D01*
G01X1543457Y614341D02*
X1505957D01*
G01X1520226Y639094D02*
G02X1528593I4183J0D01*
G02X1520226I-4184J0D01*
G01D02*
G02X1528593I4183J0D01*
G02X1520226I-4184J0D01*
G01X1505957Y667341D02*
X1543457D01*
G01D02*
Y614341D01*
G01X1554247Y642544D02*
X1544816Y626844D01*
X1545216Y628344D01*
X1545916Y627844D01*
X1544816Y626844D01*
G01X1554247Y642544D02*
Y740887D01*
G01X1537375Y675787D02*
X2071100D01*
G01X1563606Y669285D02*
X1599106D01*
Y597585D01*
X1563606D01*
Y669285D01*
G01X1576239Y670703D02*
X1578239Y673303D01*
X1576139Y674003D01*
X1576239Y670703D01*
X1602738Y744424D01*
G01X1679134Y17717D02*
Y23763D01*
G03X1676711Y32156I-15749J0D01*
G02X1693368I8329J5246D01*
G03X1690945Y23763I13326J-8393D01*
G01Y17717D01*
G02X1679134I-5905J0D01*
G01Y23763D02*
G03X1676711Y32156I-15749J0D01*
G02X1693368I8329J5246D01*
G03X1690945Y23763I13326J-8393D01*
G01Y17717D01*
G02X1679134I-5905J0D01*
G01Y23763D01*
G01X1676712Y32155D02*
G02X1679134Y23763I-13327J-8392D01*
G01X1693368Y32155D02*
G03X1676712I-8328J5246D01*
G01X1665354Y236614D02*
G02X1681102I7874J0D01*
G02X1665354I-7874J0D01*
G01D02*
G02X1681102I7874J0D01*
G02X1665354I-7874J0D01*
G01X1679134Y330709D02*
Y336756D01*
G03X1676711Y345148I-15747J-1D01*
G02X1693368I8329J5246D01*
G03X1690945Y336756I13324J-8393D01*
G01Y330709D01*
G02X1679134I-5905J0D01*
G01Y336756D02*
G03X1676711Y345148I-15747J-1D01*
G02X1693368I8329J5246D01*
G03X1690945Y336756I13324J-8393D01*
G01Y330709D01*
G02X1679134I-5905J0D01*
G01Y336756D01*
G01X1676712Y345147D02*
G02X1679134Y336755I-13327J-8392D01*
G01X1693368Y345147D02*
G03X1676712I-8328J5246D01*
G01X1665354Y411614D02*
G02X1681102I7874J0D01*
G02X1665354I-7874J0D01*
G01D02*
G02X1681102I7874J0D01*
G02X1665354I-7874J0D01*
G01X1660630Y498031D02*
G02X1685827I12599J0D01*
G02X1660630I-12599J0D01*
G01D02*
G02X1685827I12599J0D01*
G02X1660630I-12599J0D01*
G01X1684748Y11818D02*
X1679140Y-4284D01*
G01X1696075Y0D02*
X2071100D01*
G01X1684383Y7776D02*
X1684748Y11818D01*
X1682524Y8424D01*
X1684383Y7776D01*
G01X1690946Y23763D02*
G02X1693368Y32155I15747J1D01*
G01X1690946Y17716D02*
Y23763D01*
G01X1679134Y17716D02*
G03X1690946I5906J0D01*
G01X1679134Y23763D02*
Y17716D01*
G01X1684748Y324810D02*
X1679140Y308708D01*
G01X1684383Y320768D02*
X1684748Y324810D01*
X1682524Y321416D01*
X1684383Y320768D01*
G01X1679134Y330708D02*
G03X1690946I5906J0D01*
G01Y336755D02*
G02X1693368Y345147I15747J1D01*
G01X1690946Y330708D02*
Y336755D01*
G01X1679134D02*
Y330708D01*
G01X1685040Y331708D02*
Y365500D01*
X1723000Y448000D01*
X1722500Y678500D01*
X1777000Y734500D01*
G01X1686040Y330708D02*
X1800500D01*
X1824000Y302500D01*
X1872475Y302258D01*
G01X1687402Y541339D02*
G02X1712598I12598J0D01*
G02X1687402I-12598J0D01*
G01D02*
G02X1712598I12598J0D01*
G02X1687402I-12598J0D01*
G01X1798920Y90559D02*
X1793312Y74457D01*
G01X1798555Y86517D02*
X1798920Y90559D01*
X1796696Y87165D01*
X1798555Y86517D01*
G01X1805118Y96457D02*
G02X1793307I-5906J0D01*
G01Y102504D01*
G03X1790884Y110896I-15747J-1D01*
G02X1807541I8329J5246D01*
G03X1805118Y102504I13324J-8393D01*
G01Y96457D01*
G01X1793307D02*
Y102504D01*
G03X1790884Y110896I-15747J-1D01*
G02X1807541I8329J5246D01*
G03X1805118Y102504I13324J-8393D01*
G01Y96457D01*
G02X1793307I-5906J0D01*
G01X1793306D02*
G03X1805118I5906J0D01*
G01X1793306Y102504D02*
Y96457D01*
G01X1790884Y110896D02*
G02X1793306Y102504I-13327J-8392D01*
G01X1807540Y110896D02*
G03X1790884I-8328J5246D01*
G01X1805118Y478346D02*
G02X1793307I-5906J0D01*
G01Y484393D01*
G03X1790884Y492786I-15749J0D01*
G02X1807541I8329J5246D01*
G03X1805118Y484393I13326J-8393D01*
G01Y478346D01*
G01X1793307D02*
Y484393D01*
G03X1790884Y492786I-15749J0D01*
G02X1807541I8329J5246D01*
G03X1805118Y484393I13326J-8393D01*
G01Y478346D01*
G02X1793307I-5906J0D01*
G01X1798920Y472448D02*
X1793312Y456346D01*
G01X1798555Y468406D02*
X1798920Y472448D01*
X1796696Y469054D01*
X1798555Y468406D01*
G01X1793306Y478346D02*
G03X1805118I5906J0D01*
G01X1793306Y484393D02*
Y478346D01*
G01X1790884Y492785D02*
G02X1793306Y484393I-13327J-8392D01*
G01X1807540Y492785D02*
G03X1790884I-8328J5246D01*
G01X1795250Y763950D02*
Y759300D01*
X1782750D01*
Y763950D01*
G01X1795250Y807350D02*
Y812000D01*
X1782750D01*
Y807350D01*
G01X1805118Y102504D02*
G02X1807540Y110896I15747J1D01*
G01X1805118Y96457D02*
Y102504D01*
G01X1821983Y117762D02*
X1834383Y102862D01*
X1831283Y103762D01*
X1833483Y105962D01*
X1834383Y102862D01*
G01X1800212Y96457D02*
X1882175D01*
G01X1805118Y478346D02*
Y484393D01*
G01X1799212Y479346D02*
Y669000D01*
X1833500Y709500D01*
Y719775D01*
G01X1800212Y478346D02*
X1893475D01*
G01X1805118Y484393D02*
G02X1807540Y492785I15747J1D01*
G01X1821982Y500243D02*
X1834382Y485343D01*
X1831282Y486243D01*
X1833482Y488443D01*
X1834382Y485343D01*
G01X1839865Y94037D02*
G03X1836480Y95965I-3386J-2009D01*
G01X1833031D01*
G02X1830079Y98917I0J2952D01*
G01Y99508D01*
G02X1833031Y102461I2952J1D01*
G01X1836480D01*
G03X1839865Y104388I0J3937D01*
G02Y94037I8718J-5176D01*
G01D02*
G03X1836480Y95965I-3386J-2009D01*
G01X1833031D01*
G02X1830079Y98917I0J2952D01*
G01Y99508D01*
G02X1833031Y102461I2952J1D01*
G01X1836480D01*
G03X1839865Y104388I0J3937D01*
G02Y94037I8718J-5176D01*
G01X1849583Y99212D02*
X1870000D01*
X1891000Y143000D01*
G01X1839865Y476518D02*
G03X1836480Y478445I-3385J-2010D01*
G01X1833031D01*
G02X1830079Y481398I0J2953D01*
G01Y481988D01*
G02X1833031Y484941I2952J0D01*
G01X1836480D01*
G03X1839865Y486868I0J3937D01*
G02Y476518I8717J-5175D01*
G01D02*
G03X1836480Y478445I-3385J-2010D01*
G01X1833031D01*
G02X1830079Y481398I0J2953D01*
G01Y481988D01*
G02X1833031Y484941I2953J0D01*
G01X1836480D01*
G03X1839865Y486868I0J3937D01*
G02Y476518I8717J-5175D01*
G01X1848582Y482693D02*
Y663000D01*
X1897000Y715500D01*
X1896802Y753275D01*
G01X1849582Y481693D02*
X1874500D01*
X1907500Y527000D01*
G01X1852250Y755950D02*
Y751300D01*
X1839750D01*
Y755950D01*
G01X1842696Y727734D02*
X1839596D01*
Y728654D01*
X1839751Y728961D01*
X1840113Y729191D01*
X1840526Y729268D01*
X1840939Y729191D01*
X1841249Y728999D01*
X1841404Y728654D01*
Y727734D01*
G01X1839854Y732444D02*
X1839699Y732214D01*
X1839596Y731946D01*
Y731639D01*
X1839751Y731294D01*
X1840009Y731026D01*
X1840319Y730834D01*
X1840836Y730681D01*
X1841301Y730643D01*
X1841766Y730719D01*
X1842076Y730834D01*
X1842386Y731064D01*
X1842593Y731333D01*
X1842696Y731601D01*
Y731869D01*
X1842593Y732138D01*
X1842438Y732368D01*
X1842231Y732559D01*
G01X1841043Y735008D02*
X1840888Y735161D01*
X1840629Y735276D01*
X1840268Y735353D01*
X1839958Y735276D01*
X1839751Y735123D01*
X1839596Y734854D01*
Y733819D01*
X1842696D01*
Y735084D01*
X1842489Y735353D01*
X1842179Y735506D01*
X1841818Y735583D01*
X1841456Y735506D01*
X1841146Y735276D01*
X1841043Y735008D01*
Y733819D01*
G01X1839596Y739943D02*
X1842696Y740901D01*
X1839596Y741859D01*
G01X1842696Y744768D02*
Y743234D01*
X1839596D01*
Y744768D01*
G01X1841094Y744154D02*
Y743234D01*
G01X1842696Y746219D02*
X1839596D01*
X1842696Y747983D01*
X1839596D01*
G01X1842696Y749358D02*
X1839596D01*
Y750124D01*
X1839751Y750431D01*
X1839958Y750661D01*
X1840268Y750853D01*
X1840629Y751006D01*
X1841146Y751044D01*
X1841663Y751006D01*
X1842024Y750853D01*
X1842334Y750661D01*
X1842541Y750431D01*
X1842696Y750124D01*
Y749358D01*
G01Y753301D02*
X1842644Y752994D01*
X1842438Y752726D01*
X1842128Y752496D01*
X1841766Y752343D01*
X1841353Y752266D01*
X1840939D01*
X1840526Y752343D01*
X1840164Y752496D01*
X1839854Y752726D01*
X1839648Y752994D01*
X1839596Y753301D01*
X1839648Y753608D01*
X1839854Y753876D01*
X1840164Y754106D01*
X1840526Y754259D01*
X1840939Y754336D01*
X1841353D01*
X1841766Y754259D01*
X1842128Y754106D01*
X1842438Y753876D01*
X1842644Y753608D01*
X1842696Y753301D01*
G01Y755634D02*
X1839596D01*
Y756593D01*
X1839751Y756899D01*
X1839958Y757091D01*
X1840371Y757168D01*
X1840784Y757091D01*
X1841043Y756861D01*
X1841198Y756593D01*
Y755634D01*
G01Y756593D02*
X1842696Y757168D01*
G01X1844996Y736134D02*
X1848096D01*
Y737668D01*
G01Y740001D02*
X1848044Y739694D01*
X1847838Y739426D01*
X1847528Y739196D01*
X1847166Y739043D01*
X1846753Y738966D01*
X1846339D01*
X1845926Y739043D01*
X1845564Y739196D01*
X1845254Y739426D01*
X1845048Y739694D01*
X1844996Y740001D01*
X1845048Y740308D01*
X1845254Y740576D01*
X1845564Y740806D01*
X1845926Y740959D01*
X1846339Y741036D01*
X1846753D01*
X1847166Y740959D01*
X1847528Y740806D01*
X1847838Y740576D01*
X1848044Y740308D01*
X1848096Y740001D01*
G01X1846546Y743331D02*
Y744098D01*
X1847476D01*
X1847786Y743868D01*
X1847993Y743599D01*
X1848096Y743216D01*
X1847993Y742833D01*
X1847786Y742564D01*
X1847476Y742334D01*
X1847114Y742181D01*
X1846701Y742104D01*
X1846339D01*
X1846029Y742181D01*
X1845668Y742334D01*
X1845358Y742564D01*
X1845151Y742794D01*
X1844996Y743101D01*
Y743369D01*
X1845099Y743676D01*
X1845306Y743906D01*
G01X1848096Y746201D02*
X1848044Y745894D01*
X1847838Y745626D01*
X1847528Y745396D01*
X1847166Y745243D01*
X1846753Y745166D01*
X1846339D01*
X1845926Y745243D01*
X1845564Y745396D01*
X1845254Y745626D01*
X1845048Y745894D01*
X1844996Y746201D01*
X1845048Y746508D01*
X1845254Y746776D01*
X1845564Y747006D01*
X1845926Y747159D01*
X1846339Y747236D01*
X1846753D01*
X1847166Y747159D01*
X1847528Y747006D01*
X1847838Y746776D01*
X1848044Y746508D01*
X1848096Y746201D01*
G01X1834646Y726796D02*
Y785851D01*
X1874016D01*
Y726796D01*
X1834646D01*
G01X1852250Y799350D02*
Y804000D01*
X1839750D01*
Y799350D01*
G01X1874016Y446819D02*
Y1027000D01*
G01X1869016Y1025000D02*
X1874016Y1026000D01*
X1869016Y1027000D01*
Y1025000D01*
G01X1899750Y77707D02*
X1895100D01*
Y90207D01*
X1899750D01*
G01X1900250Y124750D02*
X1895600D01*
Y137250D01*
X1900250D01*
G01X1908650Y283250D02*
X1904000D01*
Y295750D01*
X1908650D01*
G01X1910791Y330838D02*
X1993338D01*
G01X1911050Y459596D02*
X1906400D01*
Y472096D01*
X1911050D01*
G01X1901700Y507750D02*
X1897050D01*
Y520250D01*
X1901700D01*
G01X1915250Y770850D02*
Y766200D01*
X1902750D01*
Y770850D01*
G01X1915250Y851450D02*
Y856100D01*
X1902750D01*
Y851450D01*
G01X1939650Y283250D02*
X1944300D01*
Y295750D01*
X1939650D01*
G01X1955550Y77707D02*
X1960200D01*
Y90207D01*
X1955550D01*
G01X1956050Y124750D02*
X1960700D01*
Y137250D01*
X1956050D01*
G01X1979250Y459596D02*
X1983900D01*
Y472096D01*
X1979250D01*
G01X1982300Y507750D02*
X1986950D01*
Y520250D01*
X1982300D01*
G01X2070100Y329675D02*
Y0D01*
G01X2069100Y5000D02*
X2070100Y0D01*
X2071100Y5000D01*
X2069100D01*
G01X2070100Y438325D02*
Y675787D01*
G01X2071100Y670787D02*
X2070100Y675787D01*
X2069100Y670787D01*
X2071100D01*
G01X2088850Y343700D02*
Y339050D01*
X2076350D01*
Y343700D01*
G01X2088850Y424300D02*
Y428950D01*
X2076350D01*
Y424300D01*
G01X2418434Y-58838D02*
Y809962D01*
X3317434D01*
Y-58838D01*
X2418434D01*
G01Y-21038D02*
X3317434D01*
G01X2418434Y16762D02*
X3317434D01*
G01X2418434Y54562D02*
X3317434D01*
G01X2418434Y92362D02*
X3317434D01*
G01X2418434Y130162D02*
X3317434D01*
G01X2418434Y167962D02*
X3317434D01*
G01X2418434Y205762D02*
X3317434D01*
G01X2418434Y243562D02*
X3317434D01*
G01X2418434Y281362D02*
X3317434D01*
G01X2418434Y319162D02*
X3317434D01*
G01X2418434Y356962D02*
X3317434D01*
G01X2418434Y394762D02*
X3317434D01*
G01X2418434Y432562D02*
X3317434D01*
G01X2418434Y470362D02*
X3317434D01*
G01X2418434Y508162D02*
X3317434D01*
G01X2414000Y550349D02*
Y582349D01*
X3858000D01*
Y550349D01*
X2414000D01*
G01X2418434Y545962D02*
X3317434D01*
G01X2414500Y585849D02*
Y619849D01*
X4084000D01*
Y585849D01*
X2414500D01*
G01X2418434Y583762D02*
X3317434D01*
G01X2418434Y621562D02*
X3317434D01*
G01X2418434Y659362D02*
X3317434D01*
G01X2418434Y697162D02*
X3317434D01*
G01X2418434Y734962D02*
X3317434D01*
G01X2418434Y759962D02*
X3317434D01*
G01X2418434Y784962D02*
X3317434D01*
G01X2508334Y759962D02*
Y-58838D01*
G01X2709834Y759962D02*
Y-58838D01*
G01X2911334Y759962D02*
Y-58838D01*
G01X3112834Y759962D02*
Y-58838D01*
G01X3239934Y759962D02*
Y-58838D01*
G01X-457143Y-1211429D02*
Y2242857D01*
X4308572D01*
Y-1211429D01*
X-457143D01*
G01X-256950Y344750D02*
X-255865Y344958D01*
X-254625Y345583D01*
X-253850Y346625D01*
X-253540Y348083D01*
X-253850Y349541D01*
X-254780Y350792D01*
X-256175Y351417D01*
X-257725D01*
X-258655Y351833D01*
X-259430Y352875D01*
X-259740Y354333D01*
X-259275Y355792D01*
X-258190Y356833D01*
X-256950Y357250D01*
X-255710Y356833D01*
X-254625Y355792D01*
X-254160Y354333D01*
X-254470Y352875D01*
X-255245Y351833D01*
X-256175Y351417D01*
X-257725D01*
X-259120Y350792D01*
X-260050Y349541D01*
X-260360Y348083D01*
X-260050Y346625D01*
X-259275Y345583D01*
X-258035Y344958D01*
X-256950Y344750D01*
G01X-244860D02*
X-244550Y347458D01*
X-244085Y349750D01*
X-243465Y351833D01*
X-242690Y354125D01*
X-241450Y357250D01*
X-247650D01*
G01X-232150Y344333D02*
X-232460Y344542D01*
Y344958D01*
X-232150Y345167D01*
X-231840Y344958D01*
Y344542D01*
X-232150Y344333D01*
G01X-223160Y346625D02*
X-222230Y345583D01*
X-221145Y344958D01*
X-219750Y344750D01*
X-218355Y345167D01*
X-217270Y346000D01*
X-216495Y347458D01*
X-216340Y349125D01*
X-216650Y350792D01*
X-217425Y351833D01*
X-218510Y352667D01*
X-219595Y352875D01*
X-220680Y352667D01*
X-222075Y351833D01*
X-221610Y357250D01*
X-217425D01*
G01X-279110Y372250D02*
X-278180Y370791D01*
X-276940Y369958D01*
X-275545Y369750D01*
X-274305Y369958D01*
X-273065Y371000D01*
X-272290Y372250D01*
X-272135Y373500D01*
X-272445Y374958D01*
X-273530Y376000D01*
X-274615Y376417D01*
X-276010D01*
G01X-274615D02*
X-273685Y377042D01*
X-272910Y378083D01*
X-272600Y379333D01*
X-272910Y380583D01*
X-273685Y381625D01*
X-275080Y382250D01*
X-276475Y382042D01*
X-277870Y381208D01*
G01X-261440Y369750D02*
Y382250D01*
X-267175Y373292D01*
X-259425D01*
G01X-249040Y369750D02*
Y382250D01*
X-254775Y373292D01*
X-247025D01*
G01X-236640Y369750D02*
Y382250D01*
X-242375Y373292D01*
X-234625D01*
G01X-226100Y369333D02*
X-226410Y369542D01*
Y369958D01*
X-226100Y370167D01*
X-225790Y369958D01*
Y369542D01*
X-226100Y369333D01*
G01X-213700Y369750D02*
X-212615Y369958D01*
X-211375Y370583D01*
X-210600Y371625D01*
X-210290Y373083D01*
X-210600Y374541D01*
X-211530Y375792D01*
X-212925Y376417D01*
X-214475D01*
X-215405Y376833D01*
X-216180Y377875D01*
X-216490Y379333D01*
X-216025Y380792D01*
X-214940Y381833D01*
X-213700Y382250D01*
X-212460Y381833D01*
X-211375Y380792D01*
X-210910Y379333D01*
X-211220Y377875D01*
X-211995Y376833D01*
X-212925Y376417D01*
X-214475D01*
X-215870Y375792D01*
X-216800Y374541D01*
X-217110Y373083D01*
X-216800Y371625D01*
X-216025Y370583D01*
X-214785Y369958D01*
X-213700Y369750D01*
G01X-201300D02*
X-200215Y369958D01*
X-198975Y370583D01*
X-198200Y371625D01*
X-197890Y373083D01*
X-198200Y374541D01*
X-199130Y375792D01*
X-200525Y376417D01*
X-202075D01*
X-203005Y376833D01*
X-203780Y377875D01*
X-204090Y379333D01*
X-203625Y380792D01*
X-202540Y381833D01*
X-201300Y382250D01*
X-200060Y381833D01*
X-198975Y380792D01*
X-198510Y379333D01*
X-198820Y377875D01*
X-199595Y376833D01*
X-200525Y376417D01*
X-202075D01*
X-203470Y375792D01*
X-204400Y374541D01*
X-204710Y373083D01*
X-204400Y371625D01*
X-203625Y370583D01*
X-202385Y369958D01*
X-201300Y369750D01*
G01X-166178Y23966D02*
Y36466D01*
X-168038Y33966D01*
G01Y23966D02*
X-164318D01*
G01X-154088D02*
X-153778Y26674D01*
X-153313Y28966D01*
X-152693Y31049D01*
X-151918Y33341D01*
X-150678Y36466D01*
X-156878D01*
G01X-141688Y23966D02*
X-141378Y26674D01*
X-140913Y28966D01*
X-140293Y31049D01*
X-139518Y33341D01*
X-138278Y36466D01*
X-144478D01*
G01X-128978Y23549D02*
X-129288Y23758D01*
Y24174D01*
X-128978Y24383D01*
X-128668Y24174D01*
Y23758D01*
X-128978Y23549D01*
G01X-116578Y23966D02*
Y36466D01*
X-118438Y33966D01*
G01Y23966D02*
X-114718D01*
G01X-107123Y29174D02*
X-106038Y30633D01*
X-105108Y31466D01*
X-103868Y31883D01*
X-102783Y31466D01*
X-102008Y30633D01*
X-101388Y29383D01*
X-101233Y27924D01*
X-101388Y26674D01*
X-102008Y25424D01*
X-102938Y24383D01*
X-104023Y23966D01*
X-105263Y24383D01*
X-106348Y25632D01*
X-106968Y27508D01*
X-107123Y29591D01*
X-106813Y32299D01*
X-106348Y33758D01*
X-105573Y35216D01*
X-104488Y36258D01*
X-103403Y36466D01*
X-102318Y36049D01*
X-101543Y35008D01*
G01X-168410Y80625D02*
X-167480Y79583D01*
X-166395Y78958D01*
X-165000Y78750D01*
X-163605Y79167D01*
X-162520Y80000D01*
X-161745Y81458D01*
X-161590Y83125D01*
X-161900Y84792D01*
X-162675Y85833D01*
X-163760Y86667D01*
X-164845Y86875D01*
X-165930Y86667D01*
X-167325Y85833D01*
X-166860Y91250D01*
X-162675D01*
G01X-156010Y81250D02*
X-155080Y79791D01*
X-153840Y78958D01*
X-152445Y78750D01*
X-151205Y78958D01*
X-149965Y80000D01*
X-149190Y81250D01*
X-149035Y82500D01*
X-149345Y83958D01*
X-150430Y85000D01*
X-151515Y85417D01*
X-152910D01*
G01X-151515D02*
X-150585Y86042D01*
X-149810Y87083D01*
X-149500Y88333D01*
X-149810Y89583D01*
X-150585Y90625D01*
X-151980Y91250D01*
X-153375Y91042D01*
X-154770Y90208D01*
G01X-140200Y78750D02*
Y91250D01*
X-142060Y88750D01*
G01Y78750D02*
X-138340D01*
G01X-127800Y78333D02*
X-128110Y78542D01*
Y78958D01*
X-127800Y79167D01*
X-127490Y78958D01*
Y78542D01*
X-127800Y78333D01*
G01X-113540Y78750D02*
Y91250D01*
X-119275Y82292D01*
X-111525D01*
G01X-103000Y78750D02*
X-101915Y78958D01*
X-100675Y79583D01*
X-99900Y80625D01*
X-99590Y82083D01*
X-99900Y83541D01*
X-100830Y84792D01*
X-102225Y85417D01*
X-103775D01*
X-104705Y85833D01*
X-105480Y86875D01*
X-105790Y88333D01*
X-105325Y89792D01*
X-104240Y90833D01*
X-103000Y91250D01*
X-101760Y90833D01*
X-100675Y89792D01*
X-100210Y88333D01*
X-100520Y86875D01*
X-101295Y85833D01*
X-102225Y85417D01*
X-103775D01*
X-105170Y84792D01*
X-106100Y83541D01*
X-106410Y82083D01*
X-106100Y80625D01*
X-105325Y79583D01*
X-104085Y78958D01*
X-103000Y78750D01*
G01X-167945Y167958D02*
X-166860Y169417D01*
X-165930Y170250D01*
X-164690Y170667D01*
X-163605Y170250D01*
X-162830Y169417D01*
X-162210Y168167D01*
X-162055Y166708D01*
X-162210Y165458D01*
X-162830Y164208D01*
X-163760Y163167D01*
X-164845Y162750D01*
X-166085Y163167D01*
X-167170Y164416D01*
X-167790Y166292D01*
X-167945Y168375D01*
X-167635Y171083D01*
X-167170Y172542D01*
X-166395Y174000D01*
X-165310Y175042D01*
X-164225Y175250D01*
X-163140Y174833D01*
X-162365Y173792D01*
G01X-150740Y162750D02*
Y175250D01*
X-156475Y166292D01*
X-148725D01*
G01X-142835Y164208D02*
X-141750Y163167D01*
X-140510Y162750D01*
X-139270Y163167D01*
X-138185Y164416D01*
X-137410Y166292D01*
X-137100Y168167D01*
Y170458D01*
X-137410Y172333D01*
X-138185Y174000D01*
X-139115Y174833D01*
X-140200Y175250D01*
X-141440Y174833D01*
X-142370Y174000D01*
X-142990Y172750D01*
X-143300Y171083D01*
X-142990Y169625D01*
X-142215Y168167D01*
X-141285Y167333D01*
X-140200Y167125D01*
X-138960Y167541D01*
X-138030Y168583D01*
X-137100Y170458D01*
G01X-127800Y162333D02*
X-128110Y162542D01*
Y162958D01*
X-127800Y163167D01*
X-127490Y162958D01*
Y162542D01*
X-127800Y162333D01*
G01X-118345Y167958D02*
X-117260Y169417D01*
X-116330Y170250D01*
X-115090Y170667D01*
X-114005Y170250D01*
X-113230Y169417D01*
X-112610Y168167D01*
X-112455Y166708D01*
X-112610Y165458D01*
X-113230Y164208D01*
X-114160Y163167D01*
X-115245Y162750D01*
X-116485Y163167D01*
X-117570Y164416D01*
X-118190Y166292D01*
X-118345Y168375D01*
X-118035Y171083D01*
X-117570Y172542D01*
X-116795Y174000D01*
X-115710Y175042D01*
X-114625Y175250D01*
X-113540Y174833D01*
X-112765Y173792D01*
G01X-103000Y162750D02*
Y175250D01*
X-104860Y172750D01*
G01Y162750D02*
X-101140D01*
G01X-175859Y253281D02*
X-174929Y254530D01*
X-173844Y255156D01*
X-172604Y255364D01*
X-171054Y254947D01*
X-169969Y253906D01*
X-169659Y252656D01*
X-169814Y251405D01*
X-170434Y250364D01*
X-173534Y248281D01*
X-174929Y246822D01*
X-175859Y244739D01*
X-176169Y242864D01*
X-169659D01*
G01X-163924Y245364D02*
X-162994Y243905D01*
X-161754Y243072D01*
X-160359Y242864D01*
X-159119Y243072D01*
X-157879Y244114D01*
X-157104Y245364D01*
X-156949Y246614D01*
X-157259Y248072D01*
X-158344Y249114D01*
X-159429Y249531D01*
X-160824D01*
G01X-159429D02*
X-158499Y250156D01*
X-157724Y251197D01*
X-157414Y252447D01*
X-157724Y253697D01*
X-158499Y254739D01*
X-159894Y255364D01*
X-161289Y255156D01*
X-162684Y254322D01*
G01X-151059Y248072D02*
X-149974Y249531D01*
X-149044Y250364D01*
X-147804Y250781D01*
X-146719Y250364D01*
X-145944Y249531D01*
X-145324Y248281D01*
X-145169Y246822D01*
X-145324Y245572D01*
X-145944Y244322D01*
X-146874Y243281D01*
X-147959Y242864D01*
X-149199Y243281D01*
X-150284Y244530D01*
X-150904Y246406D01*
X-151059Y248489D01*
X-150749Y251197D01*
X-150284Y252656D01*
X-149509Y254114D01*
X-148424Y255156D01*
X-147339Y255364D01*
X-146254Y254947D01*
X-145479Y253906D01*
G01X-138659Y248072D02*
X-137574Y249531D01*
X-136644Y250364D01*
X-135404Y250781D01*
X-134319Y250364D01*
X-133544Y249531D01*
X-132924Y248281D01*
X-132769Y246822D01*
X-132924Y245572D01*
X-133544Y244322D01*
X-134474Y243281D01*
X-135559Y242864D01*
X-136799Y243281D01*
X-137884Y244530D01*
X-138504Y246406D01*
X-138659Y248489D01*
X-138349Y251197D01*
X-137884Y252656D01*
X-137109Y254114D01*
X-136024Y255156D01*
X-134939Y255364D01*
X-133854Y254947D01*
X-133079Y253906D01*
G01X-123314Y242447D02*
X-123624Y242656D01*
Y243072D01*
X-123314Y243281D01*
X-123004Y243072D01*
Y242656D01*
X-123314Y242447D01*
G01X-110914Y242864D02*
Y255364D01*
X-112774Y252864D01*
G01Y242864D02*
X-109054D01*
G01X-96654D02*
Y255364D01*
X-102389Y246406D01*
X-94639D01*
G01X-175610Y339458D02*
X-174680Y337999D01*
X-173440Y337166D01*
X-172045Y336958D01*
X-170805Y337166D01*
X-169565Y338208D01*
X-168790Y339458D01*
X-168635Y340708D01*
X-168945Y342166D01*
X-170030Y343208D01*
X-171115Y343625D01*
X-172510D01*
G01X-171115D02*
X-170185Y344250D01*
X-169410Y345291D01*
X-169100Y346541D01*
X-169410Y347791D01*
X-170185Y348833D01*
X-171580Y349458D01*
X-172975Y349250D01*
X-174370Y348416D01*
G01X-163210Y339458D02*
X-162280Y337999D01*
X-161040Y337166D01*
X-159645Y336958D01*
X-158405Y337166D01*
X-157165Y338208D01*
X-156390Y339458D01*
X-156235Y340708D01*
X-156545Y342166D01*
X-157630Y343208D01*
X-158715Y343625D01*
X-160110D01*
G01X-158715D02*
X-157785Y344250D01*
X-157010Y345291D01*
X-156700Y346541D01*
X-157010Y347791D01*
X-157785Y348833D01*
X-159180Y349458D01*
X-160575Y349250D01*
X-161970Y348416D01*
G01X-147400Y349458D02*
X-148640Y349041D01*
X-149570Y348000D01*
X-150190Y346750D01*
X-150655Y345083D01*
X-150810Y343208D01*
X-150655Y341333D01*
X-150190Y339666D01*
X-149570Y338416D01*
X-148640Y337375D01*
X-147400Y336958D01*
X-146160Y337375D01*
X-145230Y338416D01*
X-144610Y339666D01*
X-144145Y341333D01*
X-143990Y343208D01*
X-144145Y345083D01*
X-144610Y346750D01*
X-145230Y348000D01*
X-146160Y349041D01*
X-147400Y349458D01*
G01X-135310Y336958D02*
X-135000Y339666D01*
X-134535Y341958D01*
X-133915Y344041D01*
X-133140Y346333D01*
X-131900Y349458D01*
X-138100D01*
G01X-122600Y336541D02*
X-122910Y336750D01*
Y337166D01*
X-122600Y337375D01*
X-122290Y337166D01*
Y336750D01*
X-122600Y336541D01*
G01X-110200Y349458D02*
X-111440Y349041D01*
X-112370Y348000D01*
X-112990Y346750D01*
X-113455Y345083D01*
X-113610Y343208D01*
X-113455Y341333D01*
X-112990Y339666D01*
X-112370Y338416D01*
X-111440Y337375D01*
X-110200Y336958D01*
X-108960Y337375D01*
X-108030Y338416D01*
X-107410Y339666D01*
X-106945Y341333D01*
X-106790Y343208D01*
X-106945Y345083D01*
X-107410Y346750D01*
X-108030Y348000D01*
X-108960Y349041D01*
X-110200Y349458D01*
G01X-97800Y336958D02*
X-96715Y337166D01*
X-95475Y337791D01*
X-94700Y338833D01*
X-94390Y340291D01*
X-94700Y341749D01*
X-95630Y343000D01*
X-97025Y343625D01*
X-98575D01*
X-99505Y344041D01*
X-100280Y345083D01*
X-100590Y346541D01*
X-100125Y348000D01*
X-99040Y349041D01*
X-97800Y349458D01*
X-96560Y349041D01*
X-95475Y348000D01*
X-95010Y346541D01*
X-95320Y345083D01*
X-96095Y344041D01*
X-97025Y343625D01*
X-98575D01*
X-99970Y343000D01*
X-100900Y341749D01*
X-101210Y340291D01*
X-100900Y338833D01*
X-100125Y337791D01*
X-98885Y337166D01*
X-97800Y336958D01*
G01X-165643Y392844D02*
Y405344D01*
X-167503Y402844D01*
G01Y392844D02*
X-163783D01*
G01X-153243Y405344D02*
X-154483Y404927D01*
X-155413Y403886D01*
X-156033Y402636D01*
X-156498Y400969D01*
X-156653Y399094D01*
X-156498Y397219D01*
X-156033Y395552D01*
X-155413Y394302D01*
X-154483Y393261D01*
X-153243Y392844D01*
X-152003Y393261D01*
X-151073Y394302D01*
X-150453Y395552D01*
X-149988Y397219D01*
X-149833Y399094D01*
X-149988Y400969D01*
X-150453Y402636D01*
X-151073Y403886D01*
X-152003Y404927D01*
X-153243Y405344D01*
G01X-138983Y392844D02*
Y405344D01*
X-144718Y396386D01*
X-136968D01*
G01X-128443Y392427D02*
X-128753Y392636D01*
Y393052D01*
X-128443Y393261D01*
X-128133Y393052D01*
Y392636D01*
X-128443Y392427D01*
G01X-119453Y394719D02*
X-118523Y393677D01*
X-117438Y393052D01*
X-116043Y392844D01*
X-114648Y393261D01*
X-113563Y394094D01*
X-112788Y395552D01*
X-112633Y397219D01*
X-112943Y398886D01*
X-113718Y399927D01*
X-114803Y400761D01*
X-115888Y400969D01*
X-116973Y400761D01*
X-118368Y399927D01*
X-117903Y405344D01*
X-113718D01*
G01X-101783Y392844D02*
Y405344D01*
X-107518Y396386D01*
X-99768D01*
G01X-170133Y417844D02*
Y430344D01*
X-175868Y421386D01*
X-168118D01*
G01X-159593Y417844D02*
Y430344D01*
X-161453Y427844D01*
G01Y417844D02*
X-157733D01*
G01X-147193D02*
Y430344D01*
X-149053Y427844D01*
G01Y417844D02*
X-145333D01*
G01X-138203Y419719D02*
X-137273Y418677D01*
X-136188Y418052D01*
X-134793Y417844D01*
X-133398Y418261D01*
X-132313Y419094D01*
X-131538Y420552D01*
X-131383Y422219D01*
X-131693Y423886D01*
X-132468Y424927D01*
X-133553Y425761D01*
X-134638Y425969D01*
X-135723Y425761D01*
X-137118Y424927D01*
X-136653Y430344D01*
X-132468D01*
G01X-122393Y417427D02*
X-122703Y417636D01*
Y418052D01*
X-122393Y418261D01*
X-122083Y418052D01*
Y417636D01*
X-122393Y417427D01*
G01X-112628Y419302D02*
X-111543Y418261D01*
X-110303Y417844D01*
X-109063Y418261D01*
X-107978Y419510D01*
X-107203Y421386D01*
X-106893Y423261D01*
Y425552D01*
X-107203Y427427D01*
X-107978Y429094D01*
X-108908Y429927D01*
X-109993Y430344D01*
X-111233Y429927D01*
X-112163Y429094D01*
X-112783Y427844D01*
X-113093Y426177D01*
X-112783Y424719D01*
X-112008Y423261D01*
X-111078Y422427D01*
X-109993Y422219D01*
X-108753Y422635D01*
X-107823Y423677D01*
X-106893Y425552D01*
G01X-95733Y417844D02*
Y430344D01*
X-101468Y421386D01*
X-93718D01*
G01X-162900Y645935D02*
Y658435D01*
X-164760Y655935D01*
G01Y645935D02*
X-161040D01*
G01X-153445Y651143D02*
X-152360Y652602D01*
X-151430Y653435D01*
X-150190Y653852D01*
X-149105Y653435D01*
X-148330Y652602D01*
X-147710Y651352D01*
X-147555Y649893D01*
X-147710Y648643D01*
X-148330Y647393D01*
X-149260Y646352D01*
X-150345Y645935D01*
X-151585Y646352D01*
X-152670Y647601D01*
X-153290Y649477D01*
X-153445Y651560D01*
X-153135Y654268D01*
X-152670Y655727D01*
X-151895Y657185D01*
X-150810Y658227D01*
X-149725Y658435D01*
X-148640Y658018D01*
X-147865Y656977D01*
G01X-138100Y645935D02*
X-137015Y646143D01*
X-135775Y646768D01*
X-135000Y647810D01*
X-134690Y649268D01*
X-135000Y650726D01*
X-135930Y651977D01*
X-137325Y652602D01*
X-138875D01*
X-139805Y653018D01*
X-140580Y654060D01*
X-140890Y655518D01*
X-140425Y656977D01*
X-139340Y658018D01*
X-138100Y658435D01*
X-136860Y658018D01*
X-135775Y656977D01*
X-135310Y655518D01*
X-135620Y654060D01*
X-136395Y653018D01*
X-137325Y652602D01*
X-138875D01*
X-140270Y651977D01*
X-141200Y650726D01*
X-141510Y649268D01*
X-141200Y647810D01*
X-140425Y646768D01*
X-139185Y646143D01*
X-138100Y645935D01*
G01X-125700Y645518D02*
X-126010Y645727D01*
Y646143D01*
X-125700Y646352D01*
X-125390Y646143D01*
Y645727D01*
X-125700Y645518D01*
G01X-113300Y645935D02*
X-112215Y646143D01*
X-110975Y646768D01*
X-110200Y647810D01*
X-109890Y649268D01*
X-110200Y650726D01*
X-111130Y651977D01*
X-112525Y652602D01*
X-114075D01*
X-115005Y653018D01*
X-115780Y654060D01*
X-116090Y655518D01*
X-115625Y656977D01*
X-114540Y658018D01*
X-113300Y658435D01*
X-112060Y658018D01*
X-110975Y656977D01*
X-110510Y655518D01*
X-110820Y654060D01*
X-111595Y653018D01*
X-112525Y652602D01*
X-114075D01*
X-115470Y651977D01*
X-116400Y650726D01*
X-116710Y649268D01*
X-116400Y647810D01*
X-115625Y646768D01*
X-114385Y646143D01*
X-113300Y645935D01*
G01X-104310Y648435D02*
X-103380Y646976D01*
X-102140Y646143D01*
X-100745Y645935D01*
X-99505Y646143D01*
X-98265Y647185D01*
X-97490Y648435D01*
X-97335Y649685D01*
X-97645Y651143D01*
X-98730Y652185D01*
X-99815Y652602D01*
X-101210D01*
G01X-99815D02*
X-98885Y653227D01*
X-98110Y654268D01*
X-97800Y655518D01*
X-98110Y656768D01*
X-98885Y657810D01*
X-100280Y658435D01*
X-101675Y658227D01*
X-103070Y657393D01*
G01X-172195Y676143D02*
X-171110Y677602D01*
X-170180Y678435D01*
X-168940Y678852D01*
X-167855Y678435D01*
X-167080Y677602D01*
X-166460Y676352D01*
X-166305Y674893D01*
X-166460Y673643D01*
X-167080Y672393D01*
X-168010Y671352D01*
X-169095Y670935D01*
X-170335Y671352D01*
X-171420Y672601D01*
X-172040Y674477D01*
X-172195Y676560D01*
X-171885Y679268D01*
X-171420Y680727D01*
X-170645Y682185D01*
X-169560Y683227D01*
X-168475Y683435D01*
X-167390Y683018D01*
X-166615Y681977D01*
G01X-159795Y676143D02*
X-158710Y677602D01*
X-157780Y678435D01*
X-156540Y678852D01*
X-155455Y678435D01*
X-154680Y677602D01*
X-154060Y676352D01*
X-153905Y674893D01*
X-154060Y673643D01*
X-154680Y672393D01*
X-155610Y671352D01*
X-156695Y670935D01*
X-157935Y671352D01*
X-159020Y672601D01*
X-159640Y674477D01*
X-159795Y676560D01*
X-159485Y679268D01*
X-159020Y680727D01*
X-158245Y682185D01*
X-157160Y683227D01*
X-156075Y683435D01*
X-154990Y683018D01*
X-154215Y681977D01*
G01X-142590Y670935D02*
Y683435D01*
X-148325Y674477D01*
X-140575D01*
G01X-134995Y676143D02*
X-133910Y677602D01*
X-132980Y678435D01*
X-131740Y678852D01*
X-130655Y678435D01*
X-129880Y677602D01*
X-129260Y676352D01*
X-129105Y674893D01*
X-129260Y673643D01*
X-129880Y672393D01*
X-130810Y671352D01*
X-131895Y670935D01*
X-133135Y671352D01*
X-134220Y672601D01*
X-134840Y674477D01*
X-134995Y676560D01*
X-134685Y679268D01*
X-134220Y680727D01*
X-133445Y682185D01*
X-132360Y683227D01*
X-131275Y683435D01*
X-130190Y683018D01*
X-129415Y681977D01*
G01X-119650Y670518D02*
X-119960Y670727D01*
Y671143D01*
X-119650Y671352D01*
X-119340Y671143D01*
Y670727D01*
X-119650Y670518D01*
G01X-107250Y670935D02*
X-106165Y671143D01*
X-104925Y671768D01*
X-104150Y672810D01*
X-103840Y674268D01*
X-104150Y675726D01*
X-105080Y676977D01*
X-106475Y677602D01*
X-108025D01*
X-108955Y678018D01*
X-109730Y679060D01*
X-110040Y680518D01*
X-109575Y681977D01*
X-108490Y683018D01*
X-107250Y683435D01*
X-106010Y683018D01*
X-104925Y681977D01*
X-104460Y680518D01*
X-104770Y679060D01*
X-105545Y678018D01*
X-106475Y677602D01*
X-108025D01*
X-109420Y676977D01*
X-110350Y675726D01*
X-110660Y674268D01*
X-110350Y672810D01*
X-109575Y671768D01*
X-108335Y671143D01*
X-107250Y670935D01*
G01X-98260Y672810D02*
X-97330Y671768D01*
X-96245Y671143D01*
X-94850Y670935D01*
X-93455Y671352D01*
X-92370Y672185D01*
X-91595Y673643D01*
X-91440Y675310D01*
X-91750Y676977D01*
X-92525Y678018D01*
X-93610Y678852D01*
X-94695Y679060D01*
X-95780Y678852D01*
X-97175Y678018D01*
X-96710Y683435D01*
X-92525D01*
G01X-155445Y-39333D02*
X-154515Y-38084D01*
X-153430Y-37458D01*
X-152190Y-37250D01*
X-150640Y-37667D01*
X-149555Y-38708D01*
X-149245Y-39958D01*
X-149400Y-41209D01*
X-150020Y-42250D01*
X-153120Y-44333D01*
X-154515Y-45792D01*
X-155445Y-47875D01*
X-155755Y-49750D01*
X-149245D01*
G01X-140100Y-50167D02*
X-140410Y-49958D01*
Y-49542D01*
X-140100Y-49333D01*
X-139790Y-49542D01*
Y-49958D01*
X-140100Y-50167D01*
G01X-127700Y-37250D02*
X-128940Y-37667D01*
X-129870Y-38708D01*
X-130490Y-39958D01*
X-130955Y-41625D01*
X-131110Y-43500D01*
X-130955Y-45375D01*
X-130490Y-47042D01*
X-129870Y-48292D01*
X-128940Y-49333D01*
X-127700Y-49750D01*
X-126460Y-49333D01*
X-125530Y-48292D01*
X-124910Y-47042D01*
X-124445Y-45375D01*
X-124290Y-43500D01*
X-124445Y-41625D01*
X-124910Y-39958D01*
X-125530Y-38708D01*
X-126460Y-37667D01*
X-127700Y-37250D01*
G01X-113440Y-49750D02*
Y-37250D01*
X-119175Y-46208D01*
X-111425D01*
G01X-145568Y-1034D02*
Y11466D01*
X-151303Y2508D01*
X-143553D01*
G01X-135028Y-1451D02*
X-135338Y-1242D01*
Y-826D01*
X-135028Y-617D01*
X-134718Y-826D01*
Y-1242D01*
X-135028Y-1451D01*
G01X-126038Y841D02*
X-125108Y-201D01*
X-124023Y-826D01*
X-122628Y-1034D01*
X-121233Y-617D01*
X-120148Y216D01*
X-119373Y1674D01*
X-119218Y3341D01*
X-119528Y5008D01*
X-120303Y6049D01*
X-121388Y6883D01*
X-122473Y7091D01*
X-123558Y6883D01*
X-124953Y6049D01*
X-124488Y11466D01*
X-120303D01*
G01X-158850Y-24750D02*
X-157765Y-24542D01*
X-156525Y-23917D01*
X-155750Y-22875D01*
X-155440Y-21417D01*
X-155750Y-19959D01*
X-156680Y-18708D01*
X-158075Y-18083D01*
X-159625D01*
X-160555Y-17667D01*
X-161330Y-16625D01*
X-161640Y-15167D01*
X-161175Y-13708D01*
X-160090Y-12667D01*
X-158850Y-12250D01*
X-157610Y-12667D01*
X-156525Y-13708D01*
X-156060Y-15167D01*
X-156370Y-16625D01*
X-157145Y-17667D01*
X-158075Y-18083D01*
X-159625D01*
X-161020Y-18708D01*
X-161950Y-19959D01*
X-162260Y-21417D01*
X-161950Y-22875D01*
X-161175Y-23917D01*
X-159935Y-24542D01*
X-158850Y-24750D01*
G01X-146450Y-12250D02*
X-147690Y-12667D01*
X-148620Y-13708D01*
X-149240Y-14958D01*
X-149705Y-16625D01*
X-149860Y-18500D01*
X-149705Y-20375D01*
X-149240Y-22042D01*
X-148620Y-23292D01*
X-147690Y-24333D01*
X-146450Y-24750D01*
X-145210Y-24333D01*
X-144280Y-23292D01*
X-143660Y-22042D01*
X-143195Y-20375D01*
X-143040Y-18500D01*
X-143195Y-16625D01*
X-143660Y-14958D01*
X-144280Y-13708D01*
X-145210Y-12667D01*
X-146450Y-12250D01*
G01X-134050Y-25167D02*
X-134360Y-24958D01*
Y-24542D01*
X-134050Y-24333D01*
X-133740Y-24542D01*
Y-24958D01*
X-134050Y-25167D01*
G01X-121650Y-24750D02*
Y-12250D01*
X-123510Y-14750D01*
G01Y-24750D02*
X-119790D01*
G01X-112195Y-14333D02*
X-111265Y-13084D01*
X-110180Y-12458D01*
X-108940Y-12250D01*
X-107390Y-12667D01*
X-106305Y-13708D01*
X-105995Y-14958D01*
X-106150Y-16209D01*
X-106770Y-17250D01*
X-109870Y-19333D01*
X-111265Y-20792D01*
X-112195Y-22875D01*
X-112505Y-24750D01*
X-105995D01*
G01X-152450Y53750D02*
Y66250D01*
X-154310Y63750D01*
G01Y53750D02*
X-150590D01*
G01X-143460Y56250D02*
X-142530Y54791D01*
X-141290Y53958D01*
X-139895Y53750D01*
X-138655Y53958D01*
X-137415Y55000D01*
X-136640Y56250D01*
X-136485Y57500D01*
X-136795Y58958D01*
X-137880Y60000D01*
X-138965Y60417D01*
X-140360D01*
G01X-138965D02*
X-138035Y61042D01*
X-137260Y62083D01*
X-136950Y63333D01*
X-137260Y64583D01*
X-138035Y65625D01*
X-139430Y66250D01*
X-140825Y66042D01*
X-142220Y65208D01*
G01X-127650Y53333D02*
X-127960Y53542D01*
Y53958D01*
X-127650Y54167D01*
X-127340Y53958D01*
Y53542D01*
X-127650Y53333D01*
G01X-118660Y55625D02*
X-117730Y54583D01*
X-116645Y53958D01*
X-115250Y53750D01*
X-113855Y54167D01*
X-112770Y55000D01*
X-111995Y56458D01*
X-111840Y58125D01*
X-112150Y59792D01*
X-112925Y60833D01*
X-114010Y61667D01*
X-115095Y61875D01*
X-116180Y61667D01*
X-117575Y60833D01*
X-117110Y66250D01*
X-112925D01*
G01X-152450Y137750D02*
Y150250D01*
X-154310Y147750D01*
G01Y137750D02*
X-150590D01*
G01X-142995Y142958D02*
X-141910Y144417D01*
X-140980Y145250D01*
X-139740Y145667D01*
X-138655Y145250D01*
X-137880Y144417D01*
X-137260Y143167D01*
X-137105Y141708D01*
X-137260Y140458D01*
X-137880Y139208D01*
X-138810Y138167D01*
X-139895Y137750D01*
X-141135Y138167D01*
X-142220Y139416D01*
X-142840Y141292D01*
X-142995Y143375D01*
X-142685Y146083D01*
X-142220Y147542D01*
X-141445Y149000D01*
X-140360Y150042D01*
X-139275Y150250D01*
X-138190Y149833D01*
X-137415Y148792D01*
G01X-127650Y137333D02*
X-127960Y137542D01*
Y137958D01*
X-127650Y138167D01*
X-127340Y137958D01*
Y137542D01*
X-127650Y137333D01*
G01X-118660Y139625D02*
X-117730Y138583D01*
X-116645Y137958D01*
X-115250Y137750D01*
X-113855Y138167D01*
X-112770Y139000D01*
X-111995Y140458D01*
X-111840Y142125D01*
X-112150Y143792D01*
X-112925Y144833D01*
X-114010Y145667D01*
X-115095Y145875D01*
X-116180Y145667D01*
X-117575Y144833D01*
X-117110Y150250D01*
X-112925D01*
G01X-157109Y223072D02*
X-156024Y224531D01*
X-155094Y225364D01*
X-153854Y225781D01*
X-152769Y225364D01*
X-151994Y224531D01*
X-151374Y223281D01*
X-151219Y221822D01*
X-151374Y220572D01*
X-151994Y219322D01*
X-152924Y218281D01*
X-154009Y217864D01*
X-155249Y218281D01*
X-156334Y219530D01*
X-156954Y221406D01*
X-157109Y223489D01*
X-156799Y226197D01*
X-156334Y227656D01*
X-155559Y229114D01*
X-154474Y230156D01*
X-153389Y230364D01*
X-152304Y229947D01*
X-151529Y228906D01*
G01X-141764Y230364D02*
X-143004Y229947D01*
X-143934Y228906D01*
X-144554Y227656D01*
X-145019Y225989D01*
X-145174Y224114D01*
X-145019Y222239D01*
X-144554Y220572D01*
X-143934Y219322D01*
X-143004Y218281D01*
X-141764Y217864D01*
X-140524Y218281D01*
X-139594Y219322D01*
X-138974Y220572D01*
X-138509Y222239D01*
X-138354Y224114D01*
X-138509Y225989D01*
X-138974Y227656D01*
X-139594Y228906D01*
X-140524Y229947D01*
X-141764Y230364D01*
G01X-129364Y217447D02*
X-129674Y217656D01*
Y218072D01*
X-129364Y218281D01*
X-129054Y218072D01*
Y217656D01*
X-129364Y217447D01*
G01X-116964Y217864D02*
Y230364D01*
X-118824Y227864D01*
G01Y217864D02*
X-115104D01*
G01X-141050Y311958D02*
X-139965Y312166D01*
X-138725Y312791D01*
X-137950Y313833D01*
X-137640Y315291D01*
X-137950Y316749D01*
X-138880Y318000D01*
X-140275Y318625D01*
X-141825D01*
X-142755Y319041D01*
X-143530Y320083D01*
X-143840Y321541D01*
X-143375Y323000D01*
X-142290Y324041D01*
X-141050Y324458D01*
X-139810Y324041D01*
X-138725Y323000D01*
X-138260Y321541D01*
X-138570Y320083D01*
X-139345Y319041D01*
X-140275Y318625D01*
X-141825D01*
X-143220Y318000D01*
X-144150Y316749D01*
X-144460Y315291D01*
X-144150Y313833D01*
X-143375Y312791D01*
X-142135Y312166D01*
X-141050Y311958D01*
G01X-126790D02*
Y324458D01*
X-132525Y315500D01*
X-124775D01*
G01X-18750Y-42911D02*
X-18333Y-44151D01*
X-17292Y-45081D01*
X-16042Y-45701D01*
X-14375Y-46166D01*
X-12500Y-46321D01*
X-10625Y-46166D01*
X-8958Y-45701D01*
X-7708Y-45081D01*
X-6667Y-44151D01*
X-6250Y-42911D01*
X-6667Y-41671D01*
X-7708Y-40741D01*
X-8958Y-40121D01*
X-10625Y-39656D01*
X-12500Y-39501D01*
X-14375Y-39656D01*
X-16042Y-40121D01*
X-17292Y-40741D01*
X-18333Y-41671D01*
X-18750Y-42911D01*
G01X-27766Y-6250D02*
X-29006Y-6667D01*
X-29936Y-7708D01*
X-30556Y-8958D01*
X-31021Y-10625D01*
X-31176Y-12500D01*
X-31021Y-14375D01*
X-30556Y-16042D01*
X-29936Y-17292D01*
X-29006Y-18333D01*
X-27766Y-18750D01*
X-26526Y-18333D01*
X-25596Y-17292D01*
X-24976Y-16042D01*
X-24511Y-14375D01*
X-24356Y-12500D01*
X-24511Y-10625D01*
X-24976Y-8958D01*
X-25596Y-7708D01*
X-26526Y-6667D01*
X-27766Y-6250D01*
G01X-27916Y18750D02*
X-29156Y18333D01*
X-30086Y17292D01*
X-30706Y16042D01*
X-31171Y14375D01*
X-31326Y12500D01*
X-31171Y10625D01*
X-30706Y8958D01*
X-30086Y7708D01*
X-29156Y6667D01*
X-27916Y6250D01*
X-26676Y6667D01*
X-25746Y7708D01*
X-25126Y8958D01*
X-24661Y10625D01*
X-24506Y12500D01*
X-24661Y14375D01*
X-25126Y16042D01*
X-25746Y17292D01*
X-26676Y18333D01*
X-27916Y18750D01*
G01X6250Y-42761D02*
X6667Y-44001D01*
X7708Y-44931D01*
X8958Y-45551D01*
X10625Y-46016D01*
X12500Y-46171D01*
X14375Y-46016D01*
X16042Y-45551D01*
X17292Y-44931D01*
X18333Y-44001D01*
X18750Y-42761D01*
X18333Y-41521D01*
X17292Y-40591D01*
X16042Y-39971D01*
X14375Y-39506D01*
X12500Y-39351D01*
X10625Y-39506D01*
X8958Y-39971D01*
X7708Y-40591D01*
X6667Y-41521D01*
X6250Y-42761D01*
G01X40994Y-132140D02*
X28494D01*
X37452Y-137875D01*
Y-130125D01*
G01X40994Y-121910D02*
X38286Y-121600D01*
X35994Y-121135D01*
X33911Y-120515D01*
X31619Y-119740D01*
X28494Y-118500D01*
Y-124700D01*
G01X30577Y-112145D02*
X29328Y-111215D01*
X28702Y-110130D01*
X28494Y-108890D01*
X28911Y-107340D01*
X29952Y-106255D01*
X31202Y-105945D01*
X32453Y-106100D01*
X33494Y-106720D01*
X35577Y-109820D01*
X37036Y-111215D01*
X39119Y-112145D01*
X40994Y-112455D01*
Y-105945D01*
G01X41411Y-96800D02*
X41202Y-97110D01*
X40786D01*
X40577Y-96800D01*
X40786Y-96490D01*
X41202D01*
X41411Y-96800D01*
G01X40994Y-82540D02*
X28494D01*
X37452Y-88275D01*
Y-80525D01*
G01X40994Y-70140D02*
X28494D01*
X37452Y-75875D01*
Y-68125D01*
G01X36501Y-17956D02*
Y-10456D01*
X38741D01*
X39488Y-10831D01*
X40048Y-11706D01*
X40235Y-12706D01*
X40048Y-13706D01*
X39581Y-14456D01*
X38741Y-14831D01*
X36501D01*
G01X45868Y-10456D02*
Y-17956D01*
G01X43721Y-10456D02*
X48015D01*
G01X51408Y-17956D02*
Y-10456D01*
G01X55328D02*
Y-17956D01*
G01Y-14206D02*
X51408D01*
G01X32739Y295920D02*
Y303420D01*
X34979D01*
X35726Y303045D01*
X36286Y302170D01*
X36473Y301170D01*
X36286Y300170D01*
X35819Y299420D01*
X34979Y299045D01*
X32739D01*
G01X42106Y303420D02*
Y295920D01*
G01X39959Y303420D02*
X44253D01*
G01X47646Y295920D02*
Y303420D01*
G01X51566D02*
Y295920D01*
G01Y299670D02*
X47646D01*
G01X71650Y-1024800D02*
X69130Y-1024383D01*
X66925Y-1022717D01*
X65035Y-1020217D01*
X63775Y-1017300D01*
X63145Y-1013967D01*
Y-1010633D01*
X63775Y-1007300D01*
X65035Y-1004383D01*
X66925Y-1001884D01*
X69130Y-1000217D01*
X71650Y-999800D01*
X74170Y-1000217D01*
X76375Y-1001884D01*
X78265Y-1004383D01*
X79525Y-1007300D01*
X80155Y-1010633D01*
Y-1013967D01*
X79525Y-1017300D01*
X78265Y-1020217D01*
X76375Y-1022717D01*
X74170Y-1024383D01*
X71650Y-1024800D01*
G01X74170Y-1018133D02*
X77950Y-1024800D01*
G01X91495Y-1008134D02*
Y-1019800D01*
X92755Y-1022717D01*
X94645Y-1024383D01*
X96850Y-1024800D01*
X99055Y-1024383D01*
X100945Y-1022717D01*
X102205Y-1019800D01*
G01Y-1024800D02*
Y-1008134D01*
G01X127720Y-1024800D02*
Y-1008134D01*
G01Y-1011050D02*
X126460Y-1009384D01*
X124570Y-1008550D01*
X122365Y-1008134D01*
X120160Y-1008967D01*
X118270Y-1010633D01*
X117010Y-1013134D01*
X116380Y-1016467D01*
X117010Y-1019800D01*
X118270Y-1022301D01*
X120160Y-1023967D01*
X122365Y-1024800D01*
X124570Y-1024383D01*
X126460Y-1023134D01*
X127720Y-1021467D01*
G01X141895Y-1024800D02*
Y-1008134D01*
G01Y-1012300D02*
X143155Y-1010217D01*
X145045Y-1008550D01*
X147565Y-1008134D01*
X149770Y-1008550D01*
X151660Y-1010217D01*
X152605Y-1013134D01*
Y-1024800D01*
G01X172450Y-999800D02*
Y-1024800D01*
G01X168040Y-1008134D02*
X176860D01*
G01X203320Y-1024800D02*
Y-1008134D01*
G01Y-1011050D02*
X202060Y-1009384D01*
X200170Y-1008550D01*
X197965Y-1008134D01*
X195760Y-1008967D01*
X193870Y-1010633D01*
X192610Y-1013134D01*
X191980Y-1016467D01*
X192610Y-1019800D01*
X193870Y-1022301D01*
X195760Y-1023967D01*
X197965Y-1024800D01*
X200170Y-1024383D01*
X202060Y-1023134D01*
X203320Y-1021467D01*
G01X49820Y-1042350D02*
X51387D01*
Y-1044240D01*
X50917Y-1044870D01*
X50368Y-1045290D01*
X49585Y-1045500D01*
X48802Y-1045290D01*
X48253Y-1044870D01*
X47783Y-1044240D01*
X47470Y-1043505D01*
X47313Y-1042665D01*
Y-1041930D01*
X47470Y-1041300D01*
X47783Y-1040565D01*
X48253Y-1039935D01*
X48723Y-1039515D01*
X49350Y-1039200D01*
X49898D01*
X50525Y-1039410D01*
X50995Y-1039830D01*
G01X53927Y-1039200D02*
Y-1043715D01*
X54240Y-1044660D01*
X54867Y-1045290D01*
X55650Y-1045500D01*
X56433Y-1045290D01*
X57060Y-1044660D01*
X57373Y-1043715D01*
Y-1039200D01*
G01X61010D02*
X62890D01*
G01X61950D02*
Y-1045500D01*
G01X61010D02*
X62890D01*
G01X66605Y-1044660D02*
X67232Y-1045185D01*
X67937Y-1045500D01*
X68563D01*
X69190Y-1045185D01*
X69660Y-1044660D01*
X69895Y-1043925D01*
X69738Y-1043190D01*
X69347Y-1042560D01*
X68642Y-1042140D01*
X67702Y-1041930D01*
X67153Y-1041510D01*
X66918Y-1040775D01*
X67075Y-1040040D01*
X67467Y-1039515D01*
X68015Y-1039200D01*
X68563D01*
X69112Y-1039410D01*
X69582Y-1039935D01*
G01X72905Y-1045500D02*
Y-1039200D01*
G01X76195D02*
Y-1045500D01*
G01Y-1042350D02*
X72905D01*
G01X78892Y-1045500D02*
X80850Y-1039200D01*
X82808Y-1045500D01*
G01X82103Y-1043295D02*
X79597D01*
G01X85348Y-1045500D02*
Y-1039200D01*
X88952Y-1045500D01*
Y-1039200D01*
G01X98027Y-1045500D02*
Y-1039200D01*
X99593D01*
X100220Y-1039515D01*
X100690Y-1039935D01*
X101082Y-1040565D01*
X101395Y-1041300D01*
X101473Y-1042350D01*
X101395Y-1043400D01*
X101082Y-1044135D01*
X100690Y-1044765D01*
X100220Y-1045185D01*
X99593Y-1045500D01*
X98027D01*
G01X105110Y-1039200D02*
X106990D01*
G01X106050D02*
Y-1045500D01*
G01X105110D02*
X106990D01*
G01X110705Y-1044660D02*
X111332Y-1045185D01*
X112037Y-1045500D01*
X112663D01*
X113290Y-1045185D01*
X113760Y-1044660D01*
X113995Y-1043925D01*
X113838Y-1043190D01*
X113447Y-1042560D01*
X112742Y-1042140D01*
X111802Y-1041930D01*
X111253Y-1041510D01*
X111018Y-1040775D01*
X111175Y-1040040D01*
X111567Y-1039515D01*
X112115Y-1039200D01*
X112663D01*
X113212Y-1039410D01*
X113682Y-1039935D01*
G01X118650Y-1039200D02*
Y-1045500D01*
G01X116848Y-1039200D02*
X120452D01*
G01X124950Y-1045710D02*
X124793Y-1045605D01*
Y-1045395D01*
X124950Y-1045290D01*
X125107Y-1045395D01*
Y-1045605D01*
X124950Y-1045710D01*
G01X131093Y-1046655D02*
X131407Y-1045290D01*
G01X137550Y-1039200D02*
Y-1045500D01*
G01X135748Y-1039200D02*
X139352D01*
G01X141892Y-1045500D02*
X143850Y-1039200D01*
X145808Y-1045500D01*
G01X145103Y-1043295D02*
X142597D01*
G01X150150Y-1045500D02*
X149523Y-1045395D01*
X148975Y-1044975D01*
X148505Y-1044345D01*
X148192Y-1043610D01*
X148035Y-1042770D01*
Y-1041930D01*
X148192Y-1041090D01*
X148505Y-1040355D01*
X148975Y-1039725D01*
X149523Y-1039305D01*
X150150Y-1039200D01*
X150777Y-1039305D01*
X151325Y-1039725D01*
X151795Y-1040355D01*
X152108Y-1041090D01*
X152265Y-1041930D01*
Y-1042770D01*
X152108Y-1043610D01*
X151795Y-1044345D01*
X151325Y-1044975D01*
X150777Y-1045395D01*
X150150Y-1045500D01*
G01X156450D02*
Y-1042665D01*
X154883Y-1039200D01*
G01X158017D02*
X156450Y-1042665D01*
G01X161027Y-1039200D02*
Y-1043715D01*
X161340Y-1044660D01*
X161967Y-1045290D01*
X162750Y-1045500D01*
X163533Y-1045290D01*
X164160Y-1044660D01*
X164473Y-1043715D01*
Y-1039200D01*
G01X167092Y-1045500D02*
X169050Y-1039200D01*
X171008Y-1045500D01*
G01X170303Y-1043295D02*
X167797D01*
G01X173548Y-1045500D02*
Y-1039200D01*
X177152Y-1045500D01*
Y-1039200D01*
G01X51073Y-1049725D02*
X50603Y-1049410D01*
X50055Y-1049200D01*
X49428D01*
X48723Y-1049515D01*
X48175Y-1050040D01*
X47783Y-1050670D01*
X47470Y-1051720D01*
X47392Y-1052665D01*
X47548Y-1053610D01*
X47783Y-1054240D01*
X48253Y-1054870D01*
X48802Y-1055290D01*
X49350Y-1055500D01*
X49898D01*
X50447Y-1055290D01*
X50917Y-1054975D01*
X51308Y-1054555D01*
G01X54710Y-1049200D02*
X56590D01*
G01X55650D02*
Y-1055500D01*
G01X54710D02*
X56590D01*
G01X61950Y-1049200D02*
Y-1055500D01*
G01X60148Y-1049200D02*
X63752D01*
G01X68250Y-1055500D02*
Y-1052665D01*
X66683Y-1049200D01*
G01X69817D02*
X68250Y-1052665D01*
G01X79127Y-1054240D02*
X79597Y-1054975D01*
X80223Y-1055395D01*
X80928Y-1055500D01*
X81555Y-1055395D01*
X82182Y-1054870D01*
X82573Y-1054240D01*
X82652Y-1053610D01*
X82495Y-1052875D01*
X81947Y-1052350D01*
X81398Y-1052140D01*
X80693D01*
G01X81398D02*
X81868Y-1051825D01*
X82260Y-1051300D01*
X82417Y-1050670D01*
X82260Y-1050040D01*
X81868Y-1049515D01*
X81163Y-1049200D01*
X80458Y-1049305D01*
X79753Y-1049725D01*
G01X85427Y-1054240D02*
X85897Y-1054975D01*
X86523Y-1055395D01*
X87228Y-1055500D01*
X87855Y-1055395D01*
X88482Y-1054870D01*
X88873Y-1054240D01*
X88952Y-1053610D01*
X88795Y-1052875D01*
X88247Y-1052350D01*
X87698Y-1052140D01*
X86993D01*
G01X87698D02*
X88168Y-1051825D01*
X88560Y-1051300D01*
X88717Y-1050670D01*
X88560Y-1050040D01*
X88168Y-1049515D01*
X87463Y-1049200D01*
X86758Y-1049305D01*
X86053Y-1049725D01*
G01X91727Y-1054240D02*
X92197Y-1054975D01*
X92823Y-1055395D01*
X93528Y-1055500D01*
X94155Y-1055395D01*
X94782Y-1054870D01*
X95173Y-1054240D01*
X95252Y-1053610D01*
X95095Y-1052875D01*
X94547Y-1052350D01*
X93998Y-1052140D01*
X93293D01*
G01X93998D02*
X94468Y-1051825D01*
X94860Y-1051300D01*
X95017Y-1050670D01*
X94860Y-1050040D01*
X94468Y-1049515D01*
X93763Y-1049200D01*
X93058Y-1049305D01*
X92353Y-1049725D01*
G01X99593Y-1055500D02*
X99750Y-1054135D01*
X99985Y-1052980D01*
X100298Y-1051930D01*
X100690Y-1050775D01*
X101317Y-1049200D01*
X98183D01*
G01X105893Y-1055500D02*
X106050Y-1054135D01*
X106285Y-1052980D01*
X106598Y-1051930D01*
X106990Y-1050775D01*
X107617Y-1049200D01*
X104483D01*
G01X112193Y-1056655D02*
X112507Y-1055290D01*
G01X118650Y-1049200D02*
Y-1055500D01*
G01X116848Y-1049200D02*
X120452D01*
G01X122992Y-1055500D02*
X124950Y-1049200D01*
X126908Y-1055500D01*
G01X126203Y-1053295D02*
X123697D01*
G01X130310Y-1049200D02*
X132190D01*
G01X131250D02*
Y-1055500D01*
G01X130310D02*
X132190D01*
G01X135200Y-1049200D02*
X136297Y-1055500D01*
X137550Y-1049200D01*
X138803Y-1055500D01*
X139900Y-1049200D01*
G01X141892Y-1055500D02*
X143850Y-1049200D01*
X145808Y-1055500D01*
G01X145103Y-1053295D02*
X142597D01*
G01X148348Y-1055500D02*
Y-1049200D01*
X151952Y-1055500D01*
Y-1049200D01*
G01X162358Y-1057600D02*
X161575Y-1056550D01*
X161183Y-1055500D01*
Y-1051300D01*
X161575Y-1050250D01*
X162358Y-1049200D01*
G01X173783Y-1055500D02*
Y-1049200D01*
X175742D01*
X176368Y-1049515D01*
X176760Y-1049935D01*
X176917Y-1050775D01*
X176760Y-1051615D01*
X176290Y-1052140D01*
X175742Y-1052455D01*
X173783D01*
G01X175742D02*
X176917Y-1055500D01*
G01X181650Y-1055710D02*
X181493Y-1055605D01*
Y-1055395D01*
X181650Y-1055290D01*
X181807Y-1055395D01*
Y-1055605D01*
X181650Y-1055710D01*
G01X187950Y-1055500D02*
X187323Y-1055395D01*
X186775Y-1054975D01*
X186305Y-1054345D01*
X185992Y-1053610D01*
X185835Y-1052770D01*
Y-1051930D01*
X185992Y-1051090D01*
X186305Y-1050355D01*
X186775Y-1049725D01*
X187323Y-1049305D01*
X187950Y-1049200D01*
X188577Y-1049305D01*
X189125Y-1049725D01*
X189595Y-1050355D01*
X189908Y-1051090D01*
X190065Y-1051930D01*
Y-1052770D01*
X189908Y-1053610D01*
X189595Y-1054345D01*
X189125Y-1054975D01*
X188577Y-1055395D01*
X187950Y-1055500D01*
G01X194250Y-1055710D02*
X194093Y-1055605D01*
Y-1055395D01*
X194250Y-1055290D01*
X194407Y-1055395D01*
Y-1055605D01*
X194250Y-1055710D01*
G01X202273Y-1049725D02*
X201803Y-1049410D01*
X201255Y-1049200D01*
X200628D01*
X199923Y-1049515D01*
X199375Y-1050040D01*
X198983Y-1050670D01*
X198670Y-1051720D01*
X198592Y-1052665D01*
X198748Y-1053610D01*
X198983Y-1054240D01*
X199453Y-1054870D01*
X200002Y-1055290D01*
X200550Y-1055500D01*
X201098D01*
X201647Y-1055290D01*
X202117Y-1054975D01*
X202508Y-1054555D01*
G01X206850Y-1055710D02*
X206693Y-1055605D01*
Y-1055395D01*
X206850Y-1055290D01*
X207007Y-1055395D01*
Y-1055605D01*
X206850Y-1055710D01*
G01X213542Y-1057600D02*
X214325Y-1056550D01*
X214717Y-1055500D01*
Y-1051300D01*
X214325Y-1050250D01*
X213542Y-1049200D01*
G01X47548Y-1035500D02*
Y-1029200D01*
X51152Y-1035500D01*
Y-1029200D01*
G01X55650Y-1035500D02*
X55023Y-1035395D01*
X54475Y-1034975D01*
X54005Y-1034345D01*
X53692Y-1033610D01*
X53535Y-1032770D01*
Y-1031930D01*
X53692Y-1031090D01*
X54005Y-1030355D01*
X54475Y-1029725D01*
X55023Y-1029305D01*
X55650Y-1029200D01*
X56277Y-1029305D01*
X56825Y-1029725D01*
X57295Y-1030355D01*
X57608Y-1031090D01*
X57765Y-1031930D01*
Y-1032770D01*
X57608Y-1033610D01*
X57295Y-1034345D01*
X56825Y-1034975D01*
X56277Y-1035395D01*
X55650Y-1035500D01*
G01X61950Y-1035710D02*
X61793Y-1035605D01*
Y-1035395D01*
X61950Y-1035290D01*
X62107Y-1035395D01*
Y-1035605D01*
X61950Y-1035710D01*
G01X66762Y-1030250D02*
X67232Y-1029620D01*
X67780Y-1029305D01*
X68407Y-1029200D01*
X69190Y-1029410D01*
X69738Y-1029935D01*
X69895Y-1030565D01*
X69817Y-1031195D01*
X69503Y-1031720D01*
X67937Y-1032770D01*
X67232Y-1033505D01*
X66762Y-1034555D01*
X66605Y-1035500D01*
X69895D01*
G01X74550D02*
Y-1029200D01*
X73610Y-1030460D01*
G01Y-1035500D02*
X75490D01*
G01X80850D02*
Y-1029200D01*
X79910Y-1030460D01*
G01Y-1035500D02*
X81790D01*
G01X86993Y-1036655D02*
X87307Y-1035290D01*
G01X91100Y-1029200D02*
X92197Y-1035500D01*
X93450Y-1029200D01*
X94703Y-1035500D01*
X95800Y-1029200D01*
G01X101317Y-1035500D02*
X98183D01*
Y-1029200D01*
X101317D01*
G01X100063Y-1032245D02*
X98183D01*
G01X104248Y-1035500D02*
Y-1029200D01*
X107852Y-1035500D01*
Y-1029200D01*
G01X110705Y-1035500D02*
Y-1029200D01*
G01X113995D02*
Y-1035500D01*
G01Y-1032350D02*
X110705D01*
G01X116927Y-1029200D02*
Y-1033715D01*
X117240Y-1034660D01*
X117867Y-1035290D01*
X118650Y-1035500D01*
X119433Y-1035290D01*
X120060Y-1034660D01*
X120373Y-1033715D01*
Y-1029200D01*
G01X122992Y-1035500D02*
X124950Y-1029200D01*
X126908Y-1035500D01*
G01X126203Y-1033295D02*
X123697D01*
G01X136062Y-1030250D02*
X136532Y-1029620D01*
X137080Y-1029305D01*
X137707Y-1029200D01*
X138490Y-1029410D01*
X139038Y-1029935D01*
X139195Y-1030565D01*
X139117Y-1031195D01*
X138803Y-1031720D01*
X137237Y-1032770D01*
X136532Y-1033505D01*
X136062Y-1034555D01*
X135905Y-1035500D01*
X139195D01*
G01X142048D02*
Y-1029200D01*
X145652Y-1035500D01*
Y-1029200D01*
G01X148427Y-1035500D02*
Y-1029200D01*
X149993D01*
X150620Y-1029515D01*
X151090Y-1029935D01*
X151482Y-1030565D01*
X151795Y-1031300D01*
X151873Y-1032350D01*
X151795Y-1033400D01*
X151482Y-1034135D01*
X151090Y-1034765D01*
X150620Y-1035185D01*
X149993Y-1035500D01*
X148427D01*
G01X161183D02*
Y-1029200D01*
X163142D01*
X163768Y-1029515D01*
X164160Y-1029935D01*
X164317Y-1030775D01*
X164160Y-1031615D01*
X163690Y-1032140D01*
X163142Y-1032455D01*
X161183D01*
G01X163142D02*
X164317Y-1035500D01*
G01X167327D02*
Y-1029200D01*
X168893D01*
X169520Y-1029515D01*
X169990Y-1029935D01*
X170382Y-1030565D01*
X170695Y-1031300D01*
X170773Y-1032350D01*
X170695Y-1033400D01*
X170382Y-1034135D01*
X169990Y-1034765D01*
X169520Y-1035185D01*
X168893Y-1035500D01*
X167327D01*
G01X175350Y-1035710D02*
X175193Y-1035605D01*
Y-1035395D01*
X175350Y-1035290D01*
X175507Y-1035395D01*
Y-1035605D01*
X175350Y-1035710D01*
G01X77975Y-137410D02*
X79017Y-136480D01*
X79642Y-135395D01*
X79850Y-134000D01*
X79433Y-132605D01*
X78600Y-131520D01*
X77142Y-130745D01*
X75475Y-130590D01*
X73808Y-130900D01*
X72767Y-131675D01*
X71933Y-132760D01*
X71725Y-133845D01*
X71933Y-134930D01*
X72767Y-136325D01*
X67350Y-135860D01*
Y-131675D01*
G01X78392Y-124235D02*
X79433Y-123150D01*
X79850Y-121910D01*
X79433Y-120670D01*
X78184Y-119585D01*
X76308Y-118810D01*
X74433Y-118500D01*
X72142D01*
X70267Y-118810D01*
X68600Y-119585D01*
X67767Y-120515D01*
X67350Y-121600D01*
X67767Y-122840D01*
X68600Y-123770D01*
X69850Y-124390D01*
X71517Y-124700D01*
X72975Y-124390D01*
X74433Y-123615D01*
X75267Y-122685D01*
X75475Y-121600D01*
X75059Y-120360D01*
X74017Y-119430D01*
X72142Y-118500D01*
G01X67350Y-109200D02*
X67767Y-110440D01*
X68808Y-111370D01*
X70058Y-111990D01*
X71725Y-112455D01*
X73600Y-112610D01*
X75475Y-112455D01*
X77142Y-111990D01*
X78392Y-111370D01*
X79433Y-110440D01*
X79850Y-109200D01*
X79433Y-107960D01*
X78392Y-107030D01*
X77142Y-106410D01*
X75475Y-105945D01*
X73600Y-105790D01*
X71725Y-105945D01*
X70058Y-106410D01*
X68808Y-107030D01*
X67767Y-107960D01*
X67350Y-109200D01*
G01X80267Y-96800D02*
X80058Y-97110D01*
X79642D01*
X79433Y-96800D01*
X79642Y-96490D01*
X80058D01*
X80267Y-96800D01*
G01X77975Y-87810D02*
X79017Y-86880D01*
X79642Y-85795D01*
X79850Y-84400D01*
X79433Y-83005D01*
X78600Y-81920D01*
X77142Y-81145D01*
X75475Y-80990D01*
X73808Y-81300D01*
X72767Y-82075D01*
X71933Y-83160D01*
X71725Y-84245D01*
X71933Y-85330D01*
X72767Y-86725D01*
X67350Y-86260D01*
Y-82075D01*
G01X77975Y-75410D02*
X79017Y-74480D01*
X79642Y-73395D01*
X79850Y-72000D01*
X79433Y-70605D01*
X78600Y-69520D01*
X77142Y-68745D01*
X75475Y-68590D01*
X73808Y-68900D01*
X72767Y-69675D01*
X71933Y-70760D01*
X71725Y-71845D01*
X71933Y-72930D01*
X72767Y-74325D01*
X67350Y-73860D01*
Y-69675D01*
G01X65994Y-109050D02*
X53494D01*
X55994Y-110910D01*
G01X65994D02*
Y-107190D01*
G01X55577Y-99595D02*
X54328Y-98665D01*
X53702Y-97580D01*
X53494Y-96340D01*
X53911Y-94790D01*
X54952Y-93705D01*
X56202Y-93395D01*
X57453Y-93550D01*
X58494Y-94170D01*
X60577Y-97270D01*
X62036Y-98665D01*
X64119Y-99595D01*
X65994Y-99905D01*
Y-93395D01*
G01X75975Y748590D02*
X77017Y749520D01*
X77642Y750605D01*
X77850Y752000D01*
X77433Y753395D01*
X76600Y754480D01*
X75142Y755255D01*
X73475Y755410D01*
X71808Y755100D01*
X70767Y754325D01*
X69933Y753240D01*
X69725Y752155D01*
X69933Y751070D01*
X70767Y749675D01*
X65350Y750140D01*
Y754325D01*
G01X76392Y761765D02*
X77433Y762850D01*
X77850Y764090D01*
X77433Y765330D01*
X76184Y766415D01*
X74308Y767190D01*
X72433Y767500D01*
X70142D01*
X68267Y767190D01*
X66600Y766415D01*
X65767Y765485D01*
X65350Y764400D01*
X65767Y763160D01*
X66600Y762230D01*
X67850Y761610D01*
X69517Y761300D01*
X70975Y761610D01*
X72433Y762385D01*
X73267Y763315D01*
X73475Y764400D01*
X73059Y765640D01*
X72017Y766570D01*
X70142Y767500D01*
G01X65350Y776800D02*
X65767Y775560D01*
X66808Y774630D01*
X68058Y774010D01*
X69725Y773545D01*
X71600Y773390D01*
X73475Y773545D01*
X75142Y774010D01*
X76392Y774630D01*
X77433Y775560D01*
X77850Y776800D01*
X77433Y778040D01*
X76392Y778970D01*
X75142Y779590D01*
X73475Y780055D01*
X71600Y780210D01*
X69725Y780055D01*
X68058Y779590D01*
X66808Y778970D01*
X65767Y778040D01*
X65350Y776800D01*
G01X78267Y789200D02*
X78058Y788890D01*
X77642D01*
X77433Y789200D01*
X77642Y789510D01*
X78058D01*
X78267Y789200D01*
G01X75975Y798190D02*
X77017Y799120D01*
X77642Y800205D01*
X77850Y801600D01*
X77433Y802995D01*
X76600Y804080D01*
X75142Y804855D01*
X73475Y805010D01*
X71808Y804700D01*
X70767Y803925D01*
X69933Y802840D01*
X69725Y801755D01*
X69933Y800670D01*
X70767Y799275D01*
X65350Y799740D01*
Y803925D01*
G01X75975Y810590D02*
X77017Y811520D01*
X77642Y812605D01*
X77850Y814000D01*
X77433Y815395D01*
X76600Y816480D01*
X75142Y817255D01*
X73475Y817410D01*
X71808Y817100D01*
X70767Y816325D01*
X69933Y815240D01*
X69725Y814155D01*
X69933Y813070D01*
X70767Y811675D01*
X65350Y812140D01*
Y816325D01*
G01X104850Y-109050D02*
X92350D01*
X94850Y-110910D01*
G01X104850D02*
Y-107190D01*
G01X102975Y-100060D02*
X104017Y-99130D01*
X104642Y-98045D01*
X104850Y-96650D01*
X104433Y-95255D01*
X103600Y-94170D01*
X102142Y-93395D01*
X100475Y-93240D01*
X98808Y-93550D01*
X97767Y-94325D01*
X96933Y-95410D01*
X96725Y-96495D01*
X96933Y-97580D01*
X97767Y-98975D01*
X92350Y-98510D01*
Y-94325D01*
G01X102850Y776950D02*
X90350D01*
X92850Y775090D01*
G01X102850D02*
Y778810D01*
G01X100975Y785940D02*
X102017Y786870D01*
X102642Y787955D01*
X102850Y789350D01*
X102433Y790745D01*
X101600Y791830D01*
X100142Y792605D01*
X98475Y792760D01*
X96808Y792450D01*
X95767Y791675D01*
X94933Y790590D01*
X94725Y789505D01*
X94933Y788420D01*
X95767Y787025D01*
X90350Y787490D01*
Y791675D01*
G01X131053Y737800D02*
X118553D01*
X121053Y735940D01*
G01X131053D02*
Y739660D01*
G01X128553Y746790D02*
X130012Y747720D01*
X130845Y748960D01*
X131053Y750355D01*
X130845Y751595D01*
X129803Y752835D01*
X128553Y753610D01*
X127303Y753765D01*
X125845Y753455D01*
X124803Y752370D01*
X124386Y751285D01*
Y749890D01*
G01Y751285D02*
X123761Y752215D01*
X122720Y752990D01*
X121470Y753300D01*
X120220Y752990D01*
X119178Y752215D01*
X118553Y750820D01*
X118761Y749425D01*
X119595Y748030D01*
G01X131053Y762290D02*
X128345Y762600D01*
X126053Y763065D01*
X123970Y763685D01*
X121678Y764460D01*
X118553Y765700D01*
Y759500D01*
G01X128553Y771590D02*
X130012Y772520D01*
X130845Y773760D01*
X131053Y775155D01*
X130845Y776395D01*
X129803Y777635D01*
X128553Y778410D01*
X127303Y778565D01*
X125845Y778255D01*
X124803Y777170D01*
X124386Y776085D01*
Y774690D01*
G01Y776085D02*
X123761Y777015D01*
X122720Y777790D01*
X121470Y778100D01*
X120220Y777790D01*
X119178Y777015D01*
X118553Y775620D01*
X118761Y774225D01*
X119595Y772830D01*
G01X131470Y787400D02*
X131261Y787090D01*
X130845D01*
X130636Y787400D01*
X130845Y787710D01*
X131261D01*
X131470Y787400D01*
G01X118553Y799800D02*
X118970Y798560D01*
X120011Y797630D01*
X121261Y797010D01*
X122928Y796545D01*
X124803Y796390D01*
X126678Y796545D01*
X128345Y797010D01*
X129595Y797630D01*
X130636Y798560D01*
X131053Y799800D01*
X130636Y801040D01*
X129595Y801970D01*
X128345Y802590D01*
X126678Y803055D01*
X124803Y803210D01*
X122928Y803055D01*
X121261Y802590D01*
X120011Y801970D01*
X118970Y801040D01*
X118553Y799800D01*
G01X128553Y808790D02*
X130012Y809720D01*
X130845Y810960D01*
X131053Y812355D01*
X130845Y813595D01*
X129803Y814835D01*
X128553Y815610D01*
X127303Y815765D01*
X125845Y815455D01*
X124803Y814370D01*
X124386Y813285D01*
Y811890D01*
G01Y813285D02*
X123761Y814215D01*
X122720Y814990D01*
X121470Y815300D01*
X120220Y814990D01*
X119178Y814215D01*
X118553Y812820D01*
X118761Y811425D01*
X119595Y810030D01*
G01X118139Y850093D02*
X120379D01*
G01X119259D02*
Y842593D01*
G01X118139D02*
X120379D01*
G01X124332D02*
Y850093D01*
X126759Y843843D01*
X129186Y850093D01*
Y842593D01*
G01X131832D02*
Y850093D01*
X134259Y843843D01*
X136686Y850093D01*
Y842593D01*
G01X143626D02*
X139892D01*
Y850093D01*
X143626D01*
G01X142132Y846468D02*
X139892D01*
G01X147392Y842593D02*
Y850093D01*
X149726D01*
X150472Y849718D01*
X150939Y849218D01*
X151126Y848218D01*
X150939Y847218D01*
X150379Y846593D01*
X149726Y846218D01*
X147392D01*
G01X149726D02*
X151126Y842593D01*
G01X154799Y843593D02*
X155546Y842968D01*
X156386Y842593D01*
X157132D01*
X157879Y842968D01*
X158439Y843593D01*
X158719Y844468D01*
X158532Y845343D01*
X158066Y846093D01*
X157226Y846593D01*
X156106Y846843D01*
X155452Y847343D01*
X155172Y848218D01*
X155359Y849093D01*
X155826Y849718D01*
X156479Y850093D01*
X157132D01*
X157786Y849843D01*
X158346Y849218D01*
G01X163139Y850093D02*
X165379D01*
G01X164259D02*
Y842593D01*
G01X163139D02*
X165379D01*
G01X171759D02*
X171012Y842718D01*
X170359Y843218D01*
X169799Y843968D01*
X169426Y844843D01*
X169239Y845843D01*
Y846843D01*
X169426Y847843D01*
X169799Y848718D01*
X170359Y849468D01*
X171012Y849968D01*
X171759Y850093D01*
X172506Y849968D01*
X173159Y849468D01*
X173719Y848718D01*
X174092Y847843D01*
X174279Y846843D01*
Y845843D01*
X174092Y844843D01*
X173719Y843968D01*
X173159Y843218D01*
X172506Y842718D01*
X171759Y842593D01*
G01X177112D02*
Y850093D01*
X181406Y842593D01*
Y850093D01*
G01X194259D02*
Y842593D01*
G01X192112Y850093D02*
X196406D01*
G01X200639D02*
X202879D01*
G01X201759D02*
Y842593D01*
G01X200639D02*
X202879D01*
G01X207112D02*
Y850093D01*
X211406Y842593D01*
Y850093D01*
G01X215079Y842343D02*
X218439Y850093D01*
G01X223139D02*
X225379D01*
G01X224259D02*
Y842593D01*
G01X223139D02*
X225379D01*
G01X229332D02*
Y850093D01*
X231759Y843843D01*
X234186Y850093D01*
Y842593D01*
G01X236832D02*
Y850093D01*
X239259Y843843D01*
X241686Y850093D01*
Y842593D01*
G01X248626D02*
X244892D01*
Y850093D01*
X248626D01*
G01X247132Y846468D02*
X244892D01*
G01X252392Y842593D02*
Y850093D01*
X254726D01*
X255472Y849718D01*
X255939Y849218D01*
X256126Y848218D01*
X255939Y847218D01*
X255379Y846593D01*
X254726Y846218D01*
X252392D01*
G01X254726D02*
X256126Y842593D01*
G01X259799Y843593D02*
X260546Y842968D01*
X261386Y842593D01*
X262132D01*
X262879Y842968D01*
X263439Y843593D01*
X263719Y844468D01*
X263532Y845343D01*
X263066Y846093D01*
X262226Y846593D01*
X261106Y846843D01*
X260452Y847343D01*
X260172Y848218D01*
X260359Y849093D01*
X260826Y849718D01*
X261479Y850093D01*
X262132D01*
X262786Y849843D01*
X263346Y849218D01*
G01X268139Y850093D02*
X270379D01*
G01X269259D02*
Y842593D01*
G01X268139D02*
X270379D01*
G01X276759D02*
X276012Y842718D01*
X275359Y843218D01*
X274799Y843968D01*
X274426Y844843D01*
X274239Y845843D01*
Y846843D01*
X274426Y847843D01*
X274799Y848718D01*
X275359Y849468D01*
X276012Y849968D01*
X276759Y850093D01*
X277506Y849968D01*
X278159Y849468D01*
X278719Y848718D01*
X279092Y847843D01*
X279279Y846843D01*
Y845843D01*
X279092Y844843D01*
X278719Y843968D01*
X278159Y843218D01*
X277506Y842718D01*
X276759Y842593D01*
G01X282112D02*
Y850093D01*
X286406Y842593D01*
Y850093D01*
G01X297299Y843593D02*
X298046Y842968D01*
X298886Y842593D01*
X299632D01*
X300379Y842968D01*
X300939Y843593D01*
X301219Y844468D01*
X301032Y845343D01*
X300566Y846093D01*
X299726Y846593D01*
X298606Y846843D01*
X297952Y847343D01*
X297672Y848218D01*
X297859Y849093D01*
X298326Y849718D01*
X298979Y850093D01*
X299632D01*
X300286Y849843D01*
X300846Y849218D01*
G01X305639Y850093D02*
X307879D01*
G01X306759D02*
Y842593D01*
G01X305639D02*
X307879D01*
G01X312392Y850093D02*
Y842593D01*
X316126D01*
G01X319426Y850093D02*
X321759Y842593D01*
X324092Y850093D01*
G01X331126Y842593D02*
X327392D01*
Y850093D01*
X331126D01*
G01X329632Y846468D02*
X327392D01*
G01X334892Y842593D02*
Y850093D01*
X337226D01*
X337972Y849718D01*
X338439Y849218D01*
X338626Y848218D01*
X338439Y847218D01*
X337879Y846593D01*
X337226Y846218D01*
X334892D01*
G01X337226D02*
X338626Y842593D01*
G01X342579Y842343D02*
X345939Y850093D01*
G01X353812Y849468D02*
X353252Y849843D01*
X352599Y850093D01*
X351852D01*
X351012Y849718D01*
X350359Y849093D01*
X349892Y848343D01*
X349519Y847093D01*
X349426Y845968D01*
X349612Y844843D01*
X349892Y844093D01*
X350452Y843343D01*
X351106Y842843D01*
X351759Y842593D01*
X352412D01*
X353066Y842843D01*
X353626Y843218D01*
X354092Y843718D01*
G01X359259Y842593D02*
X358512Y842718D01*
X357859Y843218D01*
X357299Y843968D01*
X356926Y844843D01*
X356739Y845843D01*
Y846843D01*
X356926Y847843D01*
X357299Y848718D01*
X357859Y849468D01*
X358512Y849968D01*
X359259Y850093D01*
X360006Y849968D01*
X360659Y849468D01*
X361219Y848718D01*
X361592Y847843D01*
X361779Y846843D01*
Y845843D01*
X361592Y844843D01*
X361219Y843968D01*
X360659Y843218D01*
X360006Y842718D01*
X359259Y842593D01*
G01X364892D02*
Y850093D01*
X367132D01*
X367879Y849718D01*
X368439Y848843D01*
X368626Y847843D01*
X368439Y846843D01*
X367972Y846093D01*
X367132Y845718D01*
X364892D01*
G01X372392Y842593D02*
Y850093D01*
X374632D01*
X375379Y849718D01*
X375939Y848843D01*
X376126Y847843D01*
X375939Y846843D01*
X375472Y846093D01*
X374632Y845718D01*
X372392D01*
G01X383626Y842593D02*
X379892D01*
Y850093D01*
X383626D01*
G01X382132Y846468D02*
X379892D01*
G01X387392Y842593D02*
Y850093D01*
X389726D01*
X390472Y849718D01*
X390939Y849218D01*
X391126Y848218D01*
X390939Y847218D01*
X390379Y846593D01*
X389726Y846218D01*
X387392D01*
G01X389726D02*
X391126Y842593D01*
G01X396759Y842343D02*
X396572Y842468D01*
Y842718D01*
X396759Y842843D01*
X396946Y842718D01*
Y842468D01*
X396759Y842343D01*
G01Y845718D02*
X396572Y845843D01*
Y846093D01*
X396759Y846218D01*
X396946Y846093D01*
Y845843D01*
X396759Y845718D01*
G01X402392Y842593D02*
Y850093D01*
X404726D01*
X405472Y849718D01*
X405939Y849218D01*
X406126Y848218D01*
X405939Y847218D01*
X405379Y846593D01*
X404726Y846218D01*
X402392D01*
G01X404726D02*
X406126Y842593D01*
G01X413626D02*
X409892D01*
Y850093D01*
X413626D01*
G01X412132Y846468D02*
X409892D01*
G01X421312Y849468D02*
X420752Y849843D01*
X420099Y850093D01*
X419352D01*
X418512Y849718D01*
X417859Y849093D01*
X417392Y848343D01*
X417019Y847093D01*
X416926Y845968D01*
X417112Y844843D01*
X417392Y844093D01*
X417952Y843343D01*
X418606Y842843D01*
X419259Y842593D01*
X419912D01*
X420566Y842843D01*
X421126Y843218D01*
X421592Y843718D01*
G01X426759Y842593D02*
X426012Y842718D01*
X425359Y843218D01*
X424799Y843968D01*
X424426Y844843D01*
X424239Y845843D01*
Y846843D01*
X424426Y847843D01*
X424799Y848718D01*
X425359Y849468D01*
X426012Y849968D01*
X426759Y850093D01*
X427506Y849968D01*
X428159Y849468D01*
X428719Y848718D01*
X429092Y847843D01*
X429279Y846843D01*
Y845843D01*
X429092Y844843D01*
X428719Y843968D01*
X428159Y843218D01*
X427506Y842718D01*
X426759Y842593D01*
G01X431832D02*
Y850093D01*
X434259Y843843D01*
X436686Y850093D01*
Y842593D01*
G01X439332D02*
Y850093D01*
X441759Y843843D01*
X444186Y850093D01*
Y842593D01*
G01X451126D02*
X447392D01*
Y850093D01*
X451126D01*
G01X449632Y846468D02*
X447392D01*
G01X454612Y842593D02*
Y850093D01*
X458906Y842593D01*
Y850093D01*
G01X462206Y842593D02*
Y850093D01*
X464072D01*
X464819Y849718D01*
X465379Y849218D01*
X465846Y848468D01*
X466219Y847593D01*
X466312Y846343D01*
X466219Y845093D01*
X465846Y844218D01*
X465379Y843468D01*
X464819Y842968D01*
X464072Y842593D01*
X462206D01*
G01X473626D02*
X469892D01*
Y850093D01*
X473626D01*
G01X472132Y846468D02*
X469892D01*
G01X477206Y842593D02*
Y850093D01*
X479072D01*
X479819Y849718D01*
X480379Y849218D01*
X480846Y848468D01*
X481219Y847593D01*
X481312Y846343D01*
X481219Y845093D01*
X480846Y844218D01*
X480379Y843468D01*
X479819Y842968D01*
X479072Y842593D01*
X477206D01*
G01X492206D02*
Y850093D01*
X494072D01*
X494819Y849718D01*
X495379Y849218D01*
X495846Y848468D01*
X496219Y847593D01*
X496312Y846343D01*
X496219Y845093D01*
X495846Y844218D01*
X495379Y843468D01*
X494819Y842968D01*
X494072Y842593D01*
X492206D01*
G01X499892D02*
Y850093D01*
X502226D01*
X502972Y849718D01*
X503439Y849218D01*
X503626Y848218D01*
X503439Y847218D01*
X502879Y846593D01*
X502226Y846218D01*
X499892D01*
G01X502226D02*
X503626Y842593D01*
G01X508139Y850093D02*
X510379D01*
G01X509259D02*
Y842593D01*
G01X508139D02*
X510379D01*
G01X514892Y850093D02*
Y842593D01*
X518626D01*
G01X522392Y850093D02*
Y842593D01*
X526126D01*
G01X537299Y843593D02*
X538046Y842968D01*
X538886Y842593D01*
X539632D01*
X540379Y842968D01*
X540939Y843593D01*
X541219Y844468D01*
X541032Y845343D01*
X540566Y846093D01*
X539726Y846593D01*
X538606Y846843D01*
X537952Y847343D01*
X537672Y848218D01*
X537859Y849093D01*
X538326Y849718D01*
X538979Y850093D01*
X539632D01*
X540286Y849843D01*
X540846Y849218D01*
G01X545639Y850093D02*
X547879D01*
G01X546759D02*
Y842593D01*
G01X545639D02*
X547879D01*
G01X552486Y850093D02*
X556032D01*
X552486Y842593D01*
X556032D01*
G01X563626D02*
X559892D01*
Y850093D01*
X563626D01*
G01X562132Y846468D02*
X559892D01*
G01X574986Y842593D02*
Y850093D01*
X578532D01*
G01X577226Y846468D02*
X574986D01*
G01X584259Y842593D02*
X583512Y842718D01*
X582859Y843218D01*
X582299Y843968D01*
X581926Y844843D01*
X581739Y845843D01*
Y846843D01*
X581926Y847843D01*
X582299Y848718D01*
X582859Y849468D01*
X583512Y849968D01*
X584259Y850093D01*
X585006Y849968D01*
X585659Y849468D01*
X586219Y848718D01*
X586592Y847843D01*
X586779Y846843D01*
Y845843D01*
X586592Y844843D01*
X586219Y843968D01*
X585659Y843218D01*
X585006Y842718D01*
X584259Y842593D01*
G01X589892D02*
Y850093D01*
X592226D01*
X592972Y849718D01*
X593439Y849218D01*
X593626Y848218D01*
X593439Y847218D01*
X592879Y846593D01*
X592226Y846218D01*
X589892D01*
G01X592226D02*
X593626Y842593D01*
G01X606759Y850093D02*
X606012Y849843D01*
X605452Y849218D01*
X605079Y848468D01*
X604799Y847468D01*
X604706Y846343D01*
X604799Y845218D01*
X605079Y844218D01*
X605452Y843468D01*
X606012Y842843D01*
X606759Y842593D01*
X607506Y842843D01*
X608066Y843468D01*
X608439Y844218D01*
X608719Y845218D01*
X608812Y846343D01*
X608719Y847468D01*
X608439Y848468D01*
X608066Y849218D01*
X607506Y849843D01*
X606759Y850093D01*
G01X614259Y842343D02*
X614072Y842468D01*
Y842718D01*
X614259Y842843D01*
X614446Y842718D01*
Y842468D01*
X614259Y842343D01*
G01X621572Y842593D02*
X621759Y844218D01*
X622039Y845593D01*
X622412Y846843D01*
X622879Y848218D01*
X623626Y850093D01*
X619892D01*
G01X627206Y843718D02*
X627766Y843093D01*
X628419Y842718D01*
X629259Y842593D01*
X630099Y842843D01*
X630752Y843343D01*
X631219Y844218D01*
X631312Y845218D01*
X631126Y846218D01*
X630659Y846843D01*
X630006Y847343D01*
X629352Y847468D01*
X628699Y847343D01*
X627859Y846843D01*
X628139Y850093D01*
X630659D01*
G01X634332Y842593D02*
Y850093D01*
X636759Y843843D01*
X639186Y850093D01*
Y842593D01*
G01X641832D02*
Y850093D01*
X644259Y843843D01*
X646686Y850093D01*
Y842593D01*
G01X657486D02*
Y850093D01*
X661032D01*
G01X659726Y846468D02*
X657486D01*
G01X665639Y850093D02*
X667879D01*
G01X666759D02*
Y842593D01*
G01X665639D02*
X667879D01*
G01X672112D02*
Y850093D01*
X676406Y842593D01*
Y850093D01*
G01X680639D02*
X682879D01*
G01X681759D02*
Y842593D01*
G01X680639D02*
X682879D01*
G01X687299Y843593D02*
X688046Y842968D01*
X688886Y842593D01*
X689632D01*
X690379Y842968D01*
X690939Y843593D01*
X691219Y844468D01*
X691032Y845343D01*
X690566Y846093D01*
X689726Y846593D01*
X688606Y846843D01*
X687952Y847343D01*
X687672Y848218D01*
X687859Y849093D01*
X688326Y849718D01*
X688979Y850093D01*
X689632D01*
X690286Y849843D01*
X690846Y849218D01*
G01X694799Y842593D02*
Y850093D01*
G01X698719D02*
Y842593D01*
G01Y846343D02*
X694799D01*
G01X706126Y842593D02*
X702392D01*
Y850093D01*
X706126D01*
G01X704632Y846468D02*
X702392D01*
G01X709706Y842593D02*
Y850093D01*
X711572D01*
X712319Y849718D01*
X712879Y849218D01*
X713346Y848468D01*
X713719Y847593D01*
X713812Y846343D01*
X713719Y845093D01*
X713346Y844218D01*
X712879Y843468D01*
X712319Y842968D01*
X711572Y842593D01*
X709706D01*
G01X724892D02*
Y850093D01*
X727132D01*
X727879Y849718D01*
X728439Y848843D01*
X728626Y847843D01*
X728439Y846843D01*
X727972Y846093D01*
X727132Y845718D01*
X724892D01*
G01X734259Y850093D02*
Y842593D01*
G01X732112Y850093D02*
X736406D01*
G01X739799Y842593D02*
Y850093D01*
G01X743719D02*
Y842593D01*
G01Y846343D02*
X739799D01*
G01X755639Y850093D02*
X757879D01*
G01X756759D02*
Y842593D01*
G01X755639D02*
X757879D01*
G01X762299Y843593D02*
X763046Y842968D01*
X763886Y842593D01*
X764632D01*
X765379Y842968D01*
X765939Y843593D01*
X766219Y844468D01*
X766032Y845343D01*
X765566Y846093D01*
X764726Y846593D01*
X763606Y846843D01*
X762952Y847343D01*
X762672Y848218D01*
X762859Y849093D01*
X763326Y849718D01*
X763979Y850093D01*
X764632D01*
X765286Y849843D01*
X765846Y849218D01*
G01X779259Y850093D02*
X778512Y849843D01*
X777952Y849218D01*
X777579Y848468D01*
X777299Y847468D01*
X777206Y846343D01*
X777299Y845218D01*
X777579Y844218D01*
X777952Y843468D01*
X778512Y842843D01*
X779259Y842593D01*
X780006Y842843D01*
X780566Y843468D01*
X780939Y844218D01*
X781219Y845218D01*
X781312Y846343D01*
X781219Y847468D01*
X780939Y848468D01*
X780566Y849218D01*
X780006Y849843D01*
X779259Y850093D01*
G01X786759Y842343D02*
X786572Y842468D01*
Y842718D01*
X786759Y842843D01*
X786946Y842718D01*
Y842468D01*
X786759Y842343D01*
G01X794259Y842593D02*
X794912Y842718D01*
X795659Y843093D01*
X796126Y843718D01*
X796312Y844593D01*
X796126Y845468D01*
X795566Y846218D01*
X794726Y846593D01*
X793792D01*
X793232Y846843D01*
X792766Y847468D01*
X792579Y848343D01*
X792859Y849218D01*
X793512Y849843D01*
X794259Y850093D01*
X795006Y849843D01*
X795659Y849218D01*
X795939Y848343D01*
X795752Y847468D01*
X795286Y846843D01*
X794726Y846593D01*
X793792D01*
X792952Y846218D01*
X792392Y845468D01*
X792206Y844593D01*
X792392Y843718D01*
X792859Y843093D01*
X793606Y842718D01*
X794259Y842593D01*
G01X801759D02*
Y850093D01*
X800639Y848593D01*
G01Y842593D02*
X802879D01*
G01X808046Y845093D02*
X810472D01*
G01X816759Y850093D02*
X816012Y849843D01*
X815452Y849218D01*
X815079Y848468D01*
X814799Y847468D01*
X814706Y846343D01*
X814799Y845218D01*
X815079Y844218D01*
X815452Y843468D01*
X816012Y842843D01*
X816759Y842593D01*
X817506Y842843D01*
X818066Y843468D01*
X818439Y844218D01*
X818719Y845218D01*
X818812Y846343D01*
X818719Y847468D01*
X818439Y848468D01*
X818066Y849218D01*
X817506Y849843D01*
X816759Y850093D01*
G01X824259Y842343D02*
X824072Y842468D01*
Y842718D01*
X824259Y842843D01*
X824446Y842718D01*
Y842468D01*
X824259Y842343D01*
G01X831759Y842593D02*
X832412Y842718D01*
X833159Y843093D01*
X833626Y843718D01*
X833812Y844593D01*
X833626Y845468D01*
X833066Y846218D01*
X832226Y846593D01*
X831292D01*
X830732Y846843D01*
X830266Y847468D01*
X830079Y848343D01*
X830359Y849218D01*
X831012Y849843D01*
X831759Y850093D01*
X832506Y849843D01*
X833159Y849218D01*
X833439Y848343D01*
X833252Y847468D01*
X832786Y846843D01*
X832226Y846593D01*
X831292D01*
X830452Y846218D01*
X829892Y845468D01*
X829706Y844593D01*
X829892Y843718D01*
X830359Y843093D01*
X831106Y842718D01*
X831759Y842593D01*
G01X837486Y845718D02*
X838139Y846593D01*
X838699Y847093D01*
X839446Y847343D01*
X840099Y847093D01*
X840566Y846593D01*
X840939Y845843D01*
X841032Y844968D01*
X840939Y844218D01*
X840566Y843468D01*
X840006Y842843D01*
X839352Y842593D01*
X838606Y842843D01*
X837952Y843593D01*
X837579Y844718D01*
X837486Y845968D01*
X837672Y847593D01*
X837952Y848468D01*
X838419Y849343D01*
X839072Y849968D01*
X839726Y850093D01*
X840379Y849843D01*
X840846Y849218D01*
G01X844332Y842593D02*
Y850093D01*
X846759Y843843D01*
X849186Y850093D01*
Y842593D01*
G01X851832D02*
Y850093D01*
X854259Y843843D01*
X856686Y850093D01*
Y842593D01*
G01X861292Y840093D02*
X860359Y841343D01*
X859892Y842593D01*
Y847593D01*
X860359Y848843D01*
X861292Y850093D01*
G01X869259D02*
X868512Y849843D01*
X867952Y849218D01*
X867579Y848468D01*
X867299Y847468D01*
X867206Y846343D01*
X867299Y845218D01*
X867579Y844218D01*
X867952Y843468D01*
X868512Y842843D01*
X869259Y842593D01*
X870006Y842843D01*
X870566Y843468D01*
X870939Y844218D01*
X871219Y845218D01*
X871312Y846343D01*
X871219Y847468D01*
X870939Y848468D01*
X870566Y849218D01*
X870006Y849843D01*
X869259Y850093D01*
G01X876759Y842343D02*
X876572Y842468D01*
Y842718D01*
X876759Y842843D01*
X876946Y842718D01*
Y842468D01*
X876759Y842343D01*
G01X884259Y842593D02*
X884912Y842718D01*
X885659Y843093D01*
X886126Y843718D01*
X886312Y844593D01*
X886126Y845468D01*
X885566Y846218D01*
X884726Y846593D01*
X883792D01*
X883232Y846843D01*
X882766Y847468D01*
X882579Y848343D01*
X882859Y849218D01*
X883512Y849843D01*
X884259Y850093D01*
X885006Y849843D01*
X885659Y849218D01*
X885939Y848343D01*
X885752Y847468D01*
X885286Y846843D01*
X884726Y846593D01*
X883792D01*
X882952Y846218D01*
X882392Y845468D01*
X882206Y844593D01*
X882392Y843718D01*
X882859Y843093D01*
X883606Y842718D01*
X884259Y842593D01*
G01X889706Y843718D02*
X890266Y843093D01*
X890919Y842718D01*
X891759Y842593D01*
X892599Y842843D01*
X893252Y843343D01*
X893719Y844218D01*
X893812Y845218D01*
X893626Y846218D01*
X893159Y846843D01*
X892506Y847343D01*
X891852Y847468D01*
X891199Y847343D01*
X890359Y846843D01*
X890639Y850093D01*
X893159D01*
G01X896832Y842593D02*
Y850093D01*
X899259Y843843D01*
X901686Y850093D01*
Y842593D01*
G01X904332D02*
Y850093D01*
X906759Y843843D01*
X909186Y850093D01*
Y842593D01*
G01X919706D02*
Y850093D01*
X921572D01*
X922319Y849718D01*
X922879Y849218D01*
X923346Y848468D01*
X923719Y847593D01*
X923812Y846343D01*
X923719Y845093D01*
X923346Y844218D01*
X922879Y843468D01*
X922319Y842968D01*
X921572Y842593D01*
X919706D01*
G01X927392D02*
Y850093D01*
X929726D01*
X930472Y849718D01*
X930939Y849218D01*
X931126Y848218D01*
X930939Y847218D01*
X930379Y846593D01*
X929726Y846218D01*
X927392D01*
G01X929726D02*
X931126Y842593D01*
G01X935639Y850093D02*
X937879D01*
G01X936759D02*
Y842593D01*
G01X935639D02*
X937879D01*
G01X942392Y850093D02*
Y842593D01*
X946126D01*
G01X949892Y850093D02*
Y842593D01*
X953626D01*
G01X959726Y840093D02*
X960659Y841343D01*
X961126Y842593D01*
Y847593D01*
X960659Y848843D01*
X959726Y850093D01*
G01X966759Y842343D02*
X966572Y842468D01*
Y842718D01*
X966759Y842843D01*
X966946Y842718D01*
Y842468D01*
X966759Y842343D01*
G01X119319Y832943D02*
X121186D01*
Y830693D01*
X120626Y829943D01*
X119972Y829443D01*
X119039Y829193D01*
X118106Y829443D01*
X117452Y829943D01*
X116892Y830693D01*
X116519Y831568D01*
X116332Y832568D01*
Y833443D01*
X116519Y834193D01*
X116892Y835068D01*
X117452Y835818D01*
X118012Y836318D01*
X118759Y836693D01*
X119412D01*
X120159Y836443D01*
X120719Y835943D01*
G01X126259Y829193D02*
X125512Y829318D01*
X124859Y829818D01*
X124299Y830568D01*
X123926Y831443D01*
X123739Y832443D01*
Y833443D01*
X123926Y834443D01*
X124299Y835318D01*
X124859Y836068D01*
X125512Y836568D01*
X126259Y836693D01*
X127006Y836568D01*
X127659Y836068D01*
X128219Y835318D01*
X128592Y834443D01*
X128779Y833443D01*
Y832443D01*
X128592Y831443D01*
X128219Y830568D01*
X127659Y829818D01*
X127006Y829318D01*
X126259Y829193D01*
G01X131892Y836693D02*
Y829193D01*
X135626D01*
G01X139206D02*
Y836693D01*
X141072D01*
X141819Y836318D01*
X142379Y835818D01*
X142846Y835068D01*
X143219Y834193D01*
X143312Y832943D01*
X143219Y831693D01*
X142846Y830818D01*
X142379Y830068D01*
X141819Y829568D01*
X141072Y829193D01*
X139206D01*
G01X148759Y828943D02*
X148572Y829068D01*
Y829318D01*
X148759Y829443D01*
X148946Y829318D01*
Y829068D01*
X148759Y828943D01*
G01Y832318D02*
X148572Y832443D01*
Y832693D01*
X148759Y832818D01*
X148946Y832693D01*
Y832443D01*
X148759Y832318D01*
G01X154392Y829193D02*
Y836693D01*
X156726D01*
X157472Y836318D01*
X157939Y835818D01*
X158126Y834818D01*
X157939Y833818D01*
X157379Y833193D01*
X156726Y832818D01*
X154392D01*
G01X156726D02*
X158126Y829193D01*
G01X165626D02*
X161892D01*
Y836693D01*
X165626D01*
G01X164132Y833068D02*
X161892D01*
G01X173312Y836068D02*
X172752Y836443D01*
X172099Y836693D01*
X171352D01*
X170512Y836318D01*
X169859Y835693D01*
X169392Y834943D01*
X169019Y833693D01*
X168926Y832568D01*
X169112Y831443D01*
X169392Y830693D01*
X169952Y829943D01*
X170606Y829443D01*
X171259Y829193D01*
X171912D01*
X172566Y829443D01*
X173126Y829818D01*
X173592Y830318D01*
G01X178759Y829193D02*
X178012Y829318D01*
X177359Y829818D01*
X176799Y830568D01*
X176426Y831443D01*
X176239Y832443D01*
Y833443D01*
X176426Y834443D01*
X176799Y835318D01*
X177359Y836068D01*
X178012Y836568D01*
X178759Y836693D01*
X179506Y836568D01*
X180159Y836068D01*
X180719Y835318D01*
X181092Y834443D01*
X181279Y833443D01*
Y832443D01*
X181092Y831443D01*
X180719Y830568D01*
X180159Y829818D01*
X179506Y829318D01*
X178759Y829193D01*
G01X183832D02*
Y836693D01*
X186259Y830443D01*
X188686Y836693D01*
Y829193D01*
G01X191332D02*
Y836693D01*
X193759Y830443D01*
X196186Y836693D01*
Y829193D01*
G01X203126D02*
X199392D01*
Y836693D01*
X203126D01*
G01X201632Y833068D02*
X199392D01*
G01X206612Y829193D02*
Y836693D01*
X210906Y829193D01*
Y836693D01*
G01X214206Y829193D02*
Y836693D01*
X216072D01*
X216819Y836318D01*
X217379Y835818D01*
X217846Y835068D01*
X218219Y834193D01*
X218312Y832943D01*
X218219Y831693D01*
X217846Y830818D01*
X217379Y830068D01*
X216819Y829568D01*
X216072Y829193D01*
X214206D01*
G01X225626D02*
X221892D01*
Y836693D01*
X225626D01*
G01X224132Y833068D02*
X221892D01*
G01X229206Y829193D02*
Y836693D01*
X231072D01*
X231819Y836318D01*
X232379Y835818D01*
X232846Y835068D01*
X233219Y834193D01*
X233312Y832943D01*
X233219Y831693D01*
X232846Y830818D01*
X232379Y830068D01*
X231819Y829568D01*
X231072Y829193D01*
X229206D01*
G01X244206D02*
Y836693D01*
X246072D01*
X246819Y836318D01*
X247379Y835818D01*
X247846Y835068D01*
X248219Y834193D01*
X248312Y832943D01*
X248219Y831693D01*
X247846Y830818D01*
X247379Y830068D01*
X246819Y829568D01*
X246072Y829193D01*
X244206D01*
G01X251892D02*
Y836693D01*
X254226D01*
X254972Y836318D01*
X255439Y835818D01*
X255626Y834818D01*
X255439Y833818D01*
X254879Y833193D01*
X254226Y832818D01*
X251892D01*
G01X254226D02*
X255626Y829193D01*
G01X260139Y836693D02*
X262379D01*
G01X261259D02*
Y829193D01*
G01X260139D02*
X262379D01*
G01X266892Y836693D02*
Y829193D01*
X270626D01*
G01X274392Y836693D02*
Y829193D01*
X278126D01*
G01X289299Y830193D02*
X290046Y829568D01*
X290886Y829193D01*
X291632D01*
X292379Y829568D01*
X292939Y830193D01*
X293219Y831068D01*
X293032Y831943D01*
X292566Y832693D01*
X291726Y833193D01*
X290606Y833443D01*
X289952Y833943D01*
X289672Y834818D01*
X289859Y835693D01*
X290326Y836318D01*
X290979Y836693D01*
X291632D01*
X292286Y836443D01*
X292846Y835818D01*
G01X297639Y836693D02*
X299879D01*
G01X298759D02*
Y829193D01*
G01X297639D02*
X299879D01*
G01X304486Y836693D02*
X308032D01*
X304486Y829193D01*
X308032D01*
G01X315626D02*
X311892D01*
Y836693D01*
X315626D01*
G01X314132Y833068D02*
X311892D01*
G01X326986Y829193D02*
Y836693D01*
X330532D01*
G01X329226Y833068D02*
X326986D01*
G01X336259Y829193D02*
X335512Y829318D01*
X334859Y829818D01*
X334299Y830568D01*
X333926Y831443D01*
X333739Y832443D01*
Y833443D01*
X333926Y834443D01*
X334299Y835318D01*
X334859Y836068D01*
X335512Y836568D01*
X336259Y836693D01*
X337006Y836568D01*
X337659Y836068D01*
X338219Y835318D01*
X338592Y834443D01*
X338779Y833443D01*
Y832443D01*
X338592Y831443D01*
X338219Y830568D01*
X337659Y829818D01*
X337006Y829318D01*
X336259Y829193D01*
G01X341892D02*
Y836693D01*
X344226D01*
X344972Y836318D01*
X345439Y835818D01*
X345626Y834818D01*
X345439Y833818D01*
X344879Y833193D01*
X344226Y832818D01*
X341892D01*
G01X344226D02*
X345626Y829193D01*
G01X358759Y836693D02*
X358012Y836443D01*
X357452Y835818D01*
X357079Y835068D01*
X356799Y834068D01*
X356706Y832943D01*
X356799Y831818D01*
X357079Y830818D01*
X357452Y830068D01*
X358012Y829443D01*
X358759Y829193D01*
X359506Y829443D01*
X360066Y830068D01*
X360439Y830818D01*
X360719Y831818D01*
X360812Y832943D01*
X360719Y834068D01*
X360439Y835068D01*
X360066Y835818D01*
X359506Y836443D01*
X358759Y836693D01*
G01X366259Y828943D02*
X366072Y829068D01*
Y829318D01*
X366259Y829443D01*
X366446Y829318D01*
Y829068D01*
X366259Y828943D01*
G01X373572Y829193D02*
X373759Y830818D01*
X374039Y832193D01*
X374412Y833443D01*
X374879Y834818D01*
X375626Y836693D01*
X371892D01*
G01X382379Y829193D02*
Y836693D01*
X378926Y831318D01*
X383592D01*
G01X386706Y830318D02*
X387266Y829693D01*
X387919Y829318D01*
X388759Y829193D01*
X389599Y829443D01*
X390252Y829943D01*
X390719Y830818D01*
X390812Y831818D01*
X390626Y832818D01*
X390159Y833443D01*
X389506Y833943D01*
X388852Y834068D01*
X388199Y833943D01*
X387359Y833443D01*
X387639Y836693D01*
X390159D01*
G01X393832Y829193D02*
Y836693D01*
X396259Y830443D01*
X398686Y836693D01*
Y829193D01*
G01X401332D02*
Y836693D01*
X403759Y830443D01*
X406186Y836693D01*
Y829193D01*
G01X416986D02*
Y836693D01*
X420532D01*
G01X419226Y833068D02*
X416986D01*
G01X425139Y836693D02*
X427379D01*
G01X426259D02*
Y829193D01*
G01X425139D02*
X427379D01*
G01X431612D02*
Y836693D01*
X435906Y829193D01*
Y836693D01*
G01X440139D02*
X442379D01*
G01X441259D02*
Y829193D01*
G01X440139D02*
X442379D01*
G01X446799Y830193D02*
X447546Y829568D01*
X448386Y829193D01*
X449132D01*
X449879Y829568D01*
X450439Y830193D01*
X450719Y831068D01*
X450532Y831943D01*
X450066Y832693D01*
X449226Y833193D01*
X448106Y833443D01*
X447452Y833943D01*
X447172Y834818D01*
X447359Y835693D01*
X447826Y836318D01*
X448479Y836693D01*
X449132D01*
X449786Y836443D01*
X450346Y835818D01*
G01X454299Y829193D02*
Y836693D01*
G01X458219D02*
Y829193D01*
G01Y832943D02*
X454299D01*
G01X465626Y829193D02*
X461892D01*
Y836693D01*
X465626D01*
G01X464132Y833068D02*
X461892D01*
G01X469206Y829193D02*
Y836693D01*
X471072D01*
X471819Y836318D01*
X472379Y835818D01*
X472846Y835068D01*
X473219Y834193D01*
X473312Y832943D01*
X473219Y831693D01*
X472846Y830818D01*
X472379Y830068D01*
X471819Y829568D01*
X471072Y829193D01*
X469206D01*
G01X484392D02*
Y836693D01*
X486632D01*
X487379Y836318D01*
X487939Y835443D01*
X488126Y834443D01*
X487939Y833443D01*
X487472Y832693D01*
X486632Y832318D01*
X484392D01*
G01X493759Y836693D02*
Y829193D01*
G01X491612Y836693D02*
X495906D01*
G01X499299Y829193D02*
Y836693D01*
G01X503219D02*
Y829193D01*
G01Y832943D02*
X499299D01*
G01X515139Y836693D02*
X517379D01*
G01X516259D02*
Y829193D01*
G01X515139D02*
X517379D01*
G01X521799Y830193D02*
X522546Y829568D01*
X523386Y829193D01*
X524132D01*
X524879Y829568D01*
X525439Y830193D01*
X525719Y831068D01*
X525532Y831943D01*
X525066Y832693D01*
X524226Y833193D01*
X523106Y833443D01*
X522452Y833943D01*
X522172Y834818D01*
X522359Y835693D01*
X522826Y836318D01*
X523479Y836693D01*
X524132D01*
X524786Y836443D01*
X525346Y835818D01*
G01X538759Y836693D02*
X538012Y836443D01*
X537452Y835818D01*
X537079Y835068D01*
X536799Y834068D01*
X536706Y832943D01*
X536799Y831818D01*
X537079Y830818D01*
X537452Y830068D01*
X538012Y829443D01*
X538759Y829193D01*
X539506Y829443D01*
X540066Y830068D01*
X540439Y830818D01*
X540719Y831818D01*
X540812Y832943D01*
X540719Y834068D01*
X540439Y835068D01*
X540066Y835818D01*
X539506Y836443D01*
X538759Y836693D01*
G01X546259Y828943D02*
X546072Y829068D01*
Y829318D01*
X546259Y829443D01*
X546446Y829318D01*
Y829068D01*
X546259Y828943D01*
G01X553759Y829193D02*
X554412Y829318D01*
X555159Y829693D01*
X555626Y830318D01*
X555812Y831193D01*
X555626Y832068D01*
X555066Y832818D01*
X554226Y833193D01*
X553292D01*
X552732Y833443D01*
X552266Y834068D01*
X552079Y834943D01*
X552359Y835818D01*
X553012Y836443D01*
X553759Y836693D01*
X554506Y836443D01*
X555159Y835818D01*
X555439Y834943D01*
X555252Y834068D01*
X554786Y833443D01*
X554226Y833193D01*
X553292D01*
X552452Y832818D01*
X551892Y832068D01*
X551706Y831193D01*
X551892Y830318D01*
X552359Y829693D01*
X553106Y829318D01*
X553759Y829193D01*
G01X561259D02*
Y836693D01*
X560139Y835193D01*
G01Y829193D02*
X562379D01*
G01X567546Y831693D02*
X569972D01*
G01X576259Y836693D02*
X575512Y836443D01*
X574952Y835818D01*
X574579Y835068D01*
X574299Y834068D01*
X574206Y832943D01*
X574299Y831818D01*
X574579Y830818D01*
X574952Y830068D01*
X575512Y829443D01*
X576259Y829193D01*
X577006Y829443D01*
X577566Y830068D01*
X577939Y830818D01*
X578219Y831818D01*
X578312Y832943D01*
X578219Y834068D01*
X577939Y835068D01*
X577566Y835818D01*
X577006Y836443D01*
X576259Y836693D01*
G01X583759Y828943D02*
X583572Y829068D01*
Y829318D01*
X583759Y829443D01*
X583946Y829318D01*
Y829068D01*
X583759Y828943D01*
G01X591259Y829193D02*
X591912Y829318D01*
X592659Y829693D01*
X593126Y830318D01*
X593312Y831193D01*
X593126Y832068D01*
X592566Y832818D01*
X591726Y833193D01*
X590792D01*
X590232Y833443D01*
X589766Y834068D01*
X589579Y834943D01*
X589859Y835818D01*
X590512Y836443D01*
X591259Y836693D01*
X592006Y836443D01*
X592659Y835818D01*
X592939Y834943D01*
X592752Y834068D01*
X592286Y833443D01*
X591726Y833193D01*
X590792D01*
X589952Y832818D01*
X589392Y832068D01*
X589206Y831193D01*
X589392Y830318D01*
X589859Y829693D01*
X590606Y829318D01*
X591259Y829193D01*
G01X596986Y832318D02*
X597639Y833193D01*
X598199Y833693D01*
X598946Y833943D01*
X599599Y833693D01*
X600066Y833193D01*
X600439Y832443D01*
X600532Y831568D01*
X600439Y830818D01*
X600066Y830068D01*
X599506Y829443D01*
X598852Y829193D01*
X598106Y829443D01*
X597452Y830193D01*
X597079Y831318D01*
X596986Y832568D01*
X597172Y834193D01*
X597452Y835068D01*
X597919Y835943D01*
X598572Y836568D01*
X599226Y836693D01*
X599879Y836443D01*
X600346Y835818D01*
G01X603832Y829193D02*
Y836693D01*
X606259Y830443D01*
X608686Y836693D01*
Y829193D01*
G01X611332D02*
Y836693D01*
X613759Y830443D01*
X616186Y836693D01*
Y829193D01*
G01X620792Y826693D02*
X619859Y827943D01*
X619392Y829193D01*
Y834193D01*
X619859Y835443D01*
X620792Y836693D01*
G01X628759D02*
X628012Y836443D01*
X627452Y835818D01*
X627079Y835068D01*
X626799Y834068D01*
X626706Y832943D01*
X626799Y831818D01*
X627079Y830818D01*
X627452Y830068D01*
X628012Y829443D01*
X628759Y829193D01*
X629506Y829443D01*
X630066Y830068D01*
X630439Y830818D01*
X630719Y831818D01*
X630812Y832943D01*
X630719Y834068D01*
X630439Y835068D01*
X630066Y835818D01*
X629506Y836443D01*
X628759Y836693D01*
G01X636259Y828943D02*
X636072Y829068D01*
Y829318D01*
X636259Y829443D01*
X636446Y829318D01*
Y829068D01*
X636259Y828943D01*
G01X643759Y829193D02*
X644412Y829318D01*
X645159Y829693D01*
X645626Y830318D01*
X645812Y831193D01*
X645626Y832068D01*
X645066Y832818D01*
X644226Y833193D01*
X643292D01*
X642732Y833443D01*
X642266Y834068D01*
X642079Y834943D01*
X642359Y835818D01*
X643012Y836443D01*
X643759Y836693D01*
X644506Y836443D01*
X645159Y835818D01*
X645439Y834943D01*
X645252Y834068D01*
X644786Y833443D01*
X644226Y833193D01*
X643292D01*
X642452Y832818D01*
X641892Y832068D01*
X641706Y831193D01*
X641892Y830318D01*
X642359Y829693D01*
X643106Y829318D01*
X643759Y829193D01*
G01X649206Y830318D02*
X649766Y829693D01*
X650419Y829318D01*
X651259Y829193D01*
X652099Y829443D01*
X652752Y829943D01*
X653219Y830818D01*
X653312Y831818D01*
X653126Y832818D01*
X652659Y833443D01*
X652006Y833943D01*
X651352Y834068D01*
X650699Y833943D01*
X649859Y833443D01*
X650139Y836693D01*
X652659D01*
G01X656332Y829193D02*
Y836693D01*
X658759Y830443D01*
X661186Y836693D01*
Y829193D01*
G01X663832D02*
Y836693D01*
X666259Y830443D01*
X668686Y836693D01*
Y829193D01*
G01X679206D02*
Y836693D01*
X681072D01*
X681819Y836318D01*
X682379Y835818D01*
X682846Y835068D01*
X683219Y834193D01*
X683312Y832943D01*
X683219Y831693D01*
X682846Y830818D01*
X682379Y830068D01*
X681819Y829568D01*
X681072Y829193D01*
X679206D01*
G01X686892D02*
Y836693D01*
X689226D01*
X689972Y836318D01*
X690439Y835818D01*
X690626Y834818D01*
X690439Y833818D01*
X689879Y833193D01*
X689226Y832818D01*
X686892D01*
G01X689226D02*
X690626Y829193D01*
G01X695139Y836693D02*
X697379D01*
G01X696259D02*
Y829193D01*
G01X695139D02*
X697379D01*
G01X701892Y836693D02*
Y829193D01*
X705626D01*
G01X709392Y836693D02*
Y829193D01*
X713126D01*
G01X719226Y826693D02*
X720159Y827943D01*
X720626Y829193D01*
Y834193D01*
X720159Y835443D01*
X719226Y836693D01*
G01X726259Y828943D02*
X726072Y829068D01*
Y829318D01*
X726259Y829443D01*
X726446Y829318D01*
Y829068D01*
X726259Y828943D01*
G01X119259Y862493D02*
Y854993D01*
G01X117112Y862493D02*
X121406D01*
G01X125639D02*
X127879D01*
G01X126759D02*
Y854993D01*
G01X125639D02*
X127879D01*
G01X132112D02*
Y862493D01*
X136406Y854993D01*
Y862493D01*
G01X140546Y857493D02*
X142972D01*
G01X147392Y862493D02*
Y854993D01*
X151126D01*
G01X158626D02*
X154892D01*
Y862493D01*
X158626D01*
G01X157132Y858868D02*
X154892D01*
G01X161926Y854993D02*
X164259Y862493D01*
X166592Y854993D01*
G01X165752Y857618D02*
X162766D01*
G01X169706Y854993D02*
Y862493D01*
X171572D01*
X172319Y862118D01*
X172879Y861618D01*
X173346Y860868D01*
X173719Y859993D01*
X173812Y858743D01*
X173719Y857493D01*
X173346Y856618D01*
X172879Y855868D01*
X172319Y855368D01*
X171572Y854993D01*
X169706D01*
G01X179259Y854743D02*
X179072Y854868D01*
Y855118D01*
X179259Y855243D01*
X179446Y855118D01*
Y854868D01*
X179259Y854743D01*
G01Y858118D02*
X179072Y858243D01*
Y858493D01*
X179259Y858618D01*
X179446Y858493D01*
Y858243D01*
X179259Y858118D01*
G01X184892Y854993D02*
Y862493D01*
X187226D01*
X187972Y862118D01*
X188439Y861618D01*
X188626Y860618D01*
X188439Y859618D01*
X187879Y858993D01*
X187226Y858618D01*
X184892D01*
G01X187226D02*
X188626Y854993D01*
G01X196126D02*
X192392D01*
Y862493D01*
X196126D01*
G01X194632Y858868D02*
X192392D01*
G01X203812Y861868D02*
X203252Y862243D01*
X202599Y862493D01*
X201852D01*
X201012Y862118D01*
X200359Y861493D01*
X199892Y860743D01*
X199519Y859493D01*
X199426Y858368D01*
X199612Y857243D01*
X199892Y856493D01*
X200452Y855743D01*
X201106Y855243D01*
X201759Y854993D01*
X202412D01*
X203066Y855243D01*
X203626Y855618D01*
X204092Y856118D01*
G01X209259Y854993D02*
X208512Y855118D01*
X207859Y855618D01*
X207299Y856368D01*
X206926Y857243D01*
X206739Y858243D01*
Y859243D01*
X206926Y860243D01*
X207299Y861118D01*
X207859Y861868D01*
X208512Y862368D01*
X209259Y862493D01*
X210006Y862368D01*
X210659Y861868D01*
X211219Y861118D01*
X211592Y860243D01*
X211779Y859243D01*
Y858243D01*
X211592Y857243D01*
X211219Y856368D01*
X210659Y855618D01*
X210006Y855118D01*
X209259Y854993D01*
G01X214332D02*
Y862493D01*
X216759Y856243D01*
X219186Y862493D01*
Y854993D01*
G01X221832D02*
Y862493D01*
X224259Y856243D01*
X226686Y862493D01*
Y854993D01*
G01X233626D02*
X229892D01*
Y862493D01*
X233626D01*
G01X232132Y858868D02*
X229892D01*
G01X237112Y854993D02*
Y862493D01*
X241406Y854993D01*
Y862493D01*
G01X244706Y854993D02*
Y862493D01*
X246572D01*
X247319Y862118D01*
X247879Y861618D01*
X248346Y860868D01*
X248719Y859993D01*
X248812Y858743D01*
X248719Y857493D01*
X248346Y856618D01*
X247879Y855868D01*
X247319Y855368D01*
X246572Y854993D01*
X244706D01*
G01X256126D02*
X252392D01*
Y862493D01*
X256126D01*
G01X254632Y858868D02*
X252392D01*
G01X259706Y854993D02*
Y862493D01*
X261572D01*
X262319Y862118D01*
X262879Y861618D01*
X263346Y860868D01*
X263719Y859993D01*
X263812Y858743D01*
X263719Y857493D01*
X263346Y856618D01*
X262879Y855868D01*
X262319Y855368D01*
X261572Y854993D01*
X259706D01*
G01X274706D02*
Y862493D01*
X276572D01*
X277319Y862118D01*
X277879Y861618D01*
X278346Y860868D01*
X278719Y859993D01*
X278812Y858743D01*
X278719Y857493D01*
X278346Y856618D01*
X277879Y855868D01*
X277319Y855368D01*
X276572Y854993D01*
X274706D01*
G01X282392D02*
Y862493D01*
X284726D01*
X285472Y862118D01*
X285939Y861618D01*
X286126Y860618D01*
X285939Y859618D01*
X285379Y858993D01*
X284726Y858618D01*
X282392D01*
G01X284726D02*
X286126Y854993D01*
G01X290639Y862493D02*
X292879D01*
G01X291759D02*
Y854993D01*
G01X290639D02*
X292879D01*
G01X297392Y862493D02*
Y854993D01*
X301126D01*
G01X304892Y862493D02*
Y854993D01*
X308626D01*
G01X319799Y855993D02*
X320546Y855368D01*
X321386Y854993D01*
X322132D01*
X322879Y855368D01*
X323439Y855993D01*
X323719Y856868D01*
X323532Y857743D01*
X323066Y858493D01*
X322226Y858993D01*
X321106Y859243D01*
X320452Y859743D01*
X320172Y860618D01*
X320359Y861493D01*
X320826Y862118D01*
X321479Y862493D01*
X322132D01*
X322786Y862243D01*
X323346Y861618D01*
G01X328139Y862493D02*
X330379D01*
G01X329259D02*
Y854993D01*
G01X328139D02*
X330379D01*
G01X334986Y862493D02*
X338532D01*
X334986Y854993D01*
X338532D01*
G01X346126D02*
X342392D01*
Y862493D01*
X346126D01*
G01X344632Y858868D02*
X342392D01*
G01X357486Y854993D02*
Y862493D01*
X361032D01*
G01X359726Y858868D02*
X357486D01*
G01X366759Y854993D02*
X366012Y855118D01*
X365359Y855618D01*
X364799Y856368D01*
X364426Y857243D01*
X364239Y858243D01*
Y859243D01*
X364426Y860243D01*
X364799Y861118D01*
X365359Y861868D01*
X366012Y862368D01*
X366759Y862493D01*
X367506Y862368D01*
X368159Y861868D01*
X368719Y861118D01*
X369092Y860243D01*
X369279Y859243D01*
Y858243D01*
X369092Y857243D01*
X368719Y856368D01*
X368159Y855618D01*
X367506Y855118D01*
X366759Y854993D01*
G01X372392D02*
Y862493D01*
X374726D01*
X375472Y862118D01*
X375939Y861618D01*
X376126Y860618D01*
X375939Y859618D01*
X375379Y858993D01*
X374726Y858618D01*
X372392D01*
G01X374726D02*
X376126Y854993D01*
G01X389259Y862493D02*
X388512Y862243D01*
X387952Y861618D01*
X387579Y860868D01*
X387299Y859868D01*
X387206Y858743D01*
X387299Y857618D01*
X387579Y856618D01*
X387952Y855868D01*
X388512Y855243D01*
X389259Y854993D01*
X390006Y855243D01*
X390566Y855868D01*
X390939Y856618D01*
X391219Y857618D01*
X391312Y858743D01*
X391219Y859868D01*
X390939Y860868D01*
X390566Y861618D01*
X390006Y862243D01*
X389259Y862493D01*
G01X396759Y854743D02*
X396572Y854868D01*
Y855118D01*
X396759Y855243D01*
X396946Y855118D01*
Y854868D01*
X396759Y854743D01*
G01X404072Y854993D02*
X404259Y856618D01*
X404539Y857993D01*
X404912Y859243D01*
X405379Y860618D01*
X406126Y862493D01*
X402392D01*
G01X409986Y861243D02*
X410546Y861993D01*
X411199Y862368D01*
X411946Y862493D01*
X412879Y862243D01*
X413532Y861618D01*
X413719Y860868D01*
X413626Y860118D01*
X413252Y859493D01*
X411386Y858243D01*
X410546Y857368D01*
X409986Y856118D01*
X409799Y854993D01*
X413719D01*
G01X417206Y856118D02*
X417766Y855493D01*
X418419Y855118D01*
X419259Y854993D01*
X420099Y855243D01*
X420752Y855743D01*
X421219Y856618D01*
X421312Y857618D01*
X421126Y858618D01*
X420659Y859243D01*
X420006Y859743D01*
X419352Y859868D01*
X418699Y859743D01*
X417859Y859243D01*
X418139Y862493D01*
X420659D01*
G01X424332Y854993D02*
Y862493D01*
X426759Y856243D01*
X429186Y862493D01*
Y854993D01*
G01X431832D02*
Y862493D01*
X434259Y856243D01*
X436686Y862493D01*
Y854993D01*
G01X447486D02*
Y862493D01*
X451032D01*
G01X449726Y858868D02*
X447486D01*
G01X455639Y862493D02*
X457879D01*
G01X456759D02*
Y854993D01*
G01X455639D02*
X457879D01*
G01X462112D02*
Y862493D01*
X466406Y854993D01*
Y862493D01*
G01X470639D02*
X472879D01*
G01X471759D02*
Y854993D01*
G01X470639D02*
X472879D01*
G01X477299Y855993D02*
X478046Y855368D01*
X478886Y854993D01*
X479632D01*
X480379Y855368D01*
X480939Y855993D01*
X481219Y856868D01*
X481032Y857743D01*
X480566Y858493D01*
X479726Y858993D01*
X478606Y859243D01*
X477952Y859743D01*
X477672Y860618D01*
X477859Y861493D01*
X478326Y862118D01*
X478979Y862493D01*
X479632D01*
X480286Y862243D01*
X480846Y861618D01*
G01X484799Y854993D02*
Y862493D01*
G01X488719D02*
Y854993D01*
G01Y858743D02*
X484799D01*
G01X496126Y854993D02*
X492392D01*
Y862493D01*
X496126D01*
G01X494632Y858868D02*
X492392D01*
G01X499706Y854993D02*
Y862493D01*
X501572D01*
X502319Y862118D01*
X502879Y861618D01*
X503346Y860868D01*
X503719Y859993D01*
X503812Y858743D01*
X503719Y857493D01*
X503346Y856618D01*
X502879Y855868D01*
X502319Y855368D01*
X501572Y854993D01*
X499706D01*
G01X514892D02*
Y862493D01*
X517132D01*
X517879Y862118D01*
X518439Y861243D01*
X518626Y860243D01*
X518439Y859243D01*
X517972Y858493D01*
X517132Y858118D01*
X514892D01*
G01X524259Y862493D02*
Y854993D01*
G01X522112Y862493D02*
X526406D01*
G01X529799Y854993D02*
Y862493D01*
G01X533719D02*
Y854993D01*
G01Y858743D02*
X529799D01*
G01X545639Y862493D02*
X547879D01*
G01X546759D02*
Y854993D01*
G01X545639D02*
X547879D01*
G01X552299Y855993D02*
X553046Y855368D01*
X553886Y854993D01*
X554632D01*
X555379Y855368D01*
X555939Y855993D01*
X556219Y856868D01*
X556032Y857743D01*
X555566Y858493D01*
X554726Y858993D01*
X553606Y859243D01*
X552952Y859743D01*
X552672Y860618D01*
X552859Y861493D01*
X553326Y862118D01*
X553979Y862493D01*
X554632D01*
X555286Y862243D01*
X555846Y861618D01*
G01X569259Y862493D02*
X568512Y862243D01*
X567952Y861618D01*
X567579Y860868D01*
X567299Y859868D01*
X567206Y858743D01*
X567299Y857618D01*
X567579Y856618D01*
X567952Y855868D01*
X568512Y855243D01*
X569259Y854993D01*
X570006Y855243D01*
X570566Y855868D01*
X570939Y856618D01*
X571219Y857618D01*
X571312Y858743D01*
X571219Y859868D01*
X570939Y860868D01*
X570566Y861618D01*
X570006Y862243D01*
X569259Y862493D01*
G01X576759Y854743D02*
X576572Y854868D01*
Y855118D01*
X576759Y855243D01*
X576946Y855118D01*
Y854868D01*
X576759Y854743D01*
G01X584259Y854993D02*
X584912Y855118D01*
X585659Y855493D01*
X586126Y856118D01*
X586312Y856993D01*
X586126Y857868D01*
X585566Y858618D01*
X584726Y858993D01*
X583792D01*
X583232Y859243D01*
X582766Y859868D01*
X582579Y860743D01*
X582859Y861618D01*
X583512Y862243D01*
X584259Y862493D01*
X585006Y862243D01*
X585659Y861618D01*
X585939Y860743D01*
X585752Y859868D01*
X585286Y859243D01*
X584726Y858993D01*
X583792D01*
X582952Y858618D01*
X582392Y857868D01*
X582206Y856993D01*
X582392Y856118D01*
X582859Y855493D01*
X583606Y855118D01*
X584259Y854993D01*
G01X591759D02*
Y862493D01*
X590639Y860993D01*
G01Y854993D02*
X592879D01*
G01X598046Y857493D02*
X600472D01*
G01X606759Y862493D02*
X606012Y862243D01*
X605452Y861618D01*
X605079Y860868D01*
X604799Y859868D01*
X604706Y858743D01*
X604799Y857618D01*
X605079Y856618D01*
X605452Y855868D01*
X606012Y855243D01*
X606759Y854993D01*
X607506Y855243D01*
X608066Y855868D01*
X608439Y856618D01*
X608719Y857618D01*
X608812Y858743D01*
X608719Y859868D01*
X608439Y860868D01*
X608066Y861618D01*
X607506Y862243D01*
X606759Y862493D01*
G01X614259Y854743D02*
X614072Y854868D01*
Y855118D01*
X614259Y855243D01*
X614446Y855118D01*
Y854868D01*
X614259Y854743D01*
G01X621759Y854993D02*
X622412Y855118D01*
X623159Y855493D01*
X623626Y856118D01*
X623812Y856993D01*
X623626Y857868D01*
X623066Y858618D01*
X622226Y858993D01*
X621292D01*
X620732Y859243D01*
X620266Y859868D01*
X620079Y860743D01*
X620359Y861618D01*
X621012Y862243D01*
X621759Y862493D01*
X622506Y862243D01*
X623159Y861618D01*
X623439Y860743D01*
X623252Y859868D01*
X622786Y859243D01*
X622226Y858993D01*
X621292D01*
X620452Y858618D01*
X619892Y857868D01*
X619706Y856993D01*
X619892Y856118D01*
X620359Y855493D01*
X621106Y855118D01*
X621759Y854993D01*
G01X627486Y858118D02*
X628139Y858993D01*
X628699Y859493D01*
X629446Y859743D01*
X630099Y859493D01*
X630566Y858993D01*
X630939Y858243D01*
X631032Y857368D01*
X630939Y856618D01*
X630566Y855868D01*
X630006Y855243D01*
X629352Y854993D01*
X628606Y855243D01*
X627952Y855993D01*
X627579Y857118D01*
X627486Y858368D01*
X627672Y859993D01*
X627952Y860868D01*
X628419Y861743D01*
X629072Y862368D01*
X629726Y862493D01*
X630379Y862243D01*
X630846Y861618D01*
G01X634332Y854993D02*
Y862493D01*
X636759Y856243D01*
X639186Y862493D01*
Y854993D01*
G01X641832D02*
Y862493D01*
X644259Y856243D01*
X646686Y862493D01*
Y854993D01*
G01X651292Y852493D02*
X650359Y853743D01*
X649892Y854993D01*
Y859993D01*
X650359Y861243D01*
X651292Y862493D01*
G01X659259D02*
X658512Y862243D01*
X657952Y861618D01*
X657579Y860868D01*
X657299Y859868D01*
X657206Y858743D01*
X657299Y857618D01*
X657579Y856618D01*
X657952Y855868D01*
X658512Y855243D01*
X659259Y854993D01*
X660006Y855243D01*
X660566Y855868D01*
X660939Y856618D01*
X661219Y857618D01*
X661312Y858743D01*
X661219Y859868D01*
X660939Y860868D01*
X660566Y861618D01*
X660006Y862243D01*
X659259Y862493D01*
G01X666759Y854743D02*
X666572Y854868D01*
Y855118D01*
X666759Y855243D01*
X666946Y855118D01*
Y854868D01*
X666759Y854743D01*
G01X674259Y854993D02*
X674912Y855118D01*
X675659Y855493D01*
X676126Y856118D01*
X676312Y856993D01*
X676126Y857868D01*
X675566Y858618D01*
X674726Y858993D01*
X673792D01*
X673232Y859243D01*
X672766Y859868D01*
X672579Y860743D01*
X672859Y861618D01*
X673512Y862243D01*
X674259Y862493D01*
X675006Y862243D01*
X675659Y861618D01*
X675939Y860743D01*
X675752Y859868D01*
X675286Y859243D01*
X674726Y858993D01*
X673792D01*
X672952Y858618D01*
X672392Y857868D01*
X672206Y856993D01*
X672392Y856118D01*
X672859Y855493D01*
X673606Y855118D01*
X674259Y854993D01*
G01X679706Y856118D02*
X680266Y855493D01*
X680919Y855118D01*
X681759Y854993D01*
X682599Y855243D01*
X683252Y855743D01*
X683719Y856618D01*
X683812Y857618D01*
X683626Y858618D01*
X683159Y859243D01*
X682506Y859743D01*
X681852Y859868D01*
X681199Y859743D01*
X680359Y859243D01*
X680639Y862493D01*
X683159D01*
G01X686832Y854993D02*
Y862493D01*
X689259Y856243D01*
X691686Y862493D01*
Y854993D01*
G01X694332D02*
Y862493D01*
X696759Y856243D01*
X699186Y862493D01*
Y854993D01*
G01X709706D02*
Y862493D01*
X711572D01*
X712319Y862118D01*
X712879Y861618D01*
X713346Y860868D01*
X713719Y859993D01*
X713812Y858743D01*
X713719Y857493D01*
X713346Y856618D01*
X712879Y855868D01*
X712319Y855368D01*
X711572Y854993D01*
X709706D01*
G01X717392D02*
Y862493D01*
X719726D01*
X720472Y862118D01*
X720939Y861618D01*
X721126Y860618D01*
X720939Y859618D01*
X720379Y858993D01*
X719726Y858618D01*
X717392D01*
G01X719726D02*
X721126Y854993D01*
G01X725639Y862493D02*
X727879D01*
G01X726759D02*
Y854993D01*
G01X725639D02*
X727879D01*
G01X732392Y862493D02*
Y854993D01*
X736126D01*
G01X739892Y862493D02*
Y854993D01*
X743626D01*
G01X749726Y852493D02*
X750659Y853743D01*
X751126Y854993D01*
Y859993D01*
X750659Y861243D01*
X749726Y862493D01*
G01X756759Y854743D02*
X756572Y854868D01*
Y855118D01*
X756759Y855243D01*
X756946Y855118D01*
Y854868D01*
X756759Y854743D01*
G01X158294Y-58574D02*
X160534D01*
G01X159414D02*
Y-66074D01*
G01X158294D02*
X160534D01*
G01X164487D02*
Y-58574D01*
X166914Y-64824D01*
X169341Y-58574D01*
Y-66074D01*
G01X171987D02*
Y-58574D01*
X174414Y-64824D01*
X176841Y-58574D01*
Y-66074D01*
G01X183781D02*
X180047D01*
Y-58574D01*
X183781D01*
G01X182287Y-62199D02*
X180047D01*
G01X187547Y-66074D02*
Y-58574D01*
X189881D01*
X190627Y-58949D01*
X191094Y-59449D01*
X191281Y-60449D01*
X191094Y-61449D01*
X190534Y-62074D01*
X189881Y-62449D01*
X187547D01*
G01X189881D02*
X191281Y-66074D01*
G01X194954Y-65074D02*
X195701Y-65699D01*
X196541Y-66074D01*
X197287D01*
X198034Y-65699D01*
X198594Y-65074D01*
X198874Y-64199D01*
X198687Y-63324D01*
X198221Y-62574D01*
X197381Y-62074D01*
X196261Y-61824D01*
X195607Y-61324D01*
X195327Y-60449D01*
X195514Y-59574D01*
X195981Y-58949D01*
X196634Y-58574D01*
X197287D01*
X197941Y-58824D01*
X198501Y-59449D01*
G01X203294Y-58574D02*
X205534D01*
G01X204414D02*
Y-66074D01*
G01X203294D02*
X205534D01*
G01X211914D02*
X211167Y-65949D01*
X210514Y-65449D01*
X209954Y-64699D01*
X209581Y-63824D01*
X209394Y-62824D01*
Y-61824D01*
X209581Y-60824D01*
X209954Y-59949D01*
X210514Y-59199D01*
X211167Y-58699D01*
X211914Y-58574D01*
X212661Y-58699D01*
X213314Y-59199D01*
X213874Y-59949D01*
X214247Y-60824D01*
X214434Y-61824D01*
Y-62824D01*
X214247Y-63824D01*
X213874Y-64699D01*
X213314Y-65449D01*
X212661Y-65949D01*
X211914Y-66074D01*
G01X217267D02*
Y-58574D01*
X221561Y-66074D01*
Y-58574D01*
G01X234414D02*
Y-66074D01*
G01X232267Y-58574D02*
X236561D01*
G01X240794D02*
X243034D01*
G01X241914D02*
Y-66074D01*
G01X240794D02*
X243034D01*
G01X247267D02*
Y-58574D01*
X251561Y-66074D01*
Y-58574D01*
G01X255234Y-66324D02*
X258594Y-58574D01*
G01X266467Y-59199D02*
X265907Y-58824D01*
X265254Y-58574D01*
X264507D01*
X263667Y-58949D01*
X263014Y-59574D01*
X262547Y-60324D01*
X262174Y-61574D01*
X262081Y-62699D01*
X262267Y-63824D01*
X262547Y-64574D01*
X263107Y-65324D01*
X263761Y-65824D01*
X264414Y-66074D01*
X265067D01*
X265721Y-65824D01*
X266281Y-65449D01*
X266747Y-64949D01*
G01X271914Y-66074D02*
X271167Y-65949D01*
X270514Y-65449D01*
X269954Y-64699D01*
X269581Y-63824D01*
X269394Y-62824D01*
Y-61824D01*
X269581Y-60824D01*
X269954Y-59949D01*
X270514Y-59199D01*
X271167Y-58699D01*
X271914Y-58574D01*
X272661Y-58699D01*
X273314Y-59199D01*
X273874Y-59949D01*
X274247Y-60824D01*
X274434Y-61824D01*
Y-62824D01*
X274247Y-63824D01*
X273874Y-64699D01*
X273314Y-65449D01*
X272661Y-65949D01*
X271914Y-66074D01*
G01X277547D02*
Y-58574D01*
X279787D01*
X280534Y-58949D01*
X281094Y-59824D01*
X281281Y-60824D01*
X281094Y-61824D01*
X280627Y-62574D01*
X279787Y-62949D01*
X277547D01*
G01X285047Y-66074D02*
Y-58574D01*
X287287D01*
X288034Y-58949D01*
X288594Y-59824D01*
X288781Y-60824D01*
X288594Y-61824D01*
X288127Y-62574D01*
X287287Y-62949D01*
X285047D01*
G01X296281Y-66074D02*
X292547D01*
Y-58574D01*
X296281D01*
G01X294787Y-62199D02*
X292547D01*
G01X300047Y-66074D02*
Y-58574D01*
X302381D01*
X303127Y-58949D01*
X303594Y-59449D01*
X303781Y-60449D01*
X303594Y-61449D01*
X303034Y-62074D01*
X302381Y-62449D01*
X300047D01*
G01X302381D02*
X303781Y-66074D01*
G01X309414Y-66324D02*
X309227Y-66199D01*
Y-65949D01*
X309414Y-65824D01*
X309601Y-65949D01*
Y-66199D01*
X309414Y-66324D01*
G01Y-62949D02*
X309227Y-62824D01*
Y-62574D01*
X309414Y-62449D01*
X309601Y-62574D01*
Y-62824D01*
X309414Y-62949D01*
G01X315047Y-66074D02*
Y-58574D01*
X317381D01*
X318127Y-58949D01*
X318594Y-59449D01*
X318781Y-60449D01*
X318594Y-61449D01*
X318034Y-62074D01*
X317381Y-62449D01*
X315047D01*
G01X317381D02*
X318781Y-66074D01*
G01X326281D02*
X322547D01*
Y-58574D01*
X326281D01*
G01X324787Y-62199D02*
X322547D01*
G01X333967Y-59199D02*
X333407Y-58824D01*
X332754Y-58574D01*
X332007D01*
X331167Y-58949D01*
X330514Y-59574D01*
X330047Y-60324D01*
X329674Y-61574D01*
X329581Y-62699D01*
X329767Y-63824D01*
X330047Y-64574D01*
X330607Y-65324D01*
X331261Y-65824D01*
X331914Y-66074D01*
X332567D01*
X333221Y-65824D01*
X333781Y-65449D01*
X334247Y-64949D01*
G01X339414Y-66074D02*
X338667Y-65949D01*
X338014Y-65449D01*
X337454Y-64699D01*
X337081Y-63824D01*
X336894Y-62824D01*
Y-61824D01*
X337081Y-60824D01*
X337454Y-59949D01*
X338014Y-59199D01*
X338667Y-58699D01*
X339414Y-58574D01*
X340161Y-58699D01*
X340814Y-59199D01*
X341374Y-59949D01*
X341747Y-60824D01*
X341934Y-61824D01*
Y-62824D01*
X341747Y-63824D01*
X341374Y-64699D01*
X340814Y-65449D01*
X340161Y-65949D01*
X339414Y-66074D01*
G01X344487D02*
Y-58574D01*
X346914Y-64824D01*
X349341Y-58574D01*
Y-66074D01*
G01X351987D02*
Y-58574D01*
X354414Y-64824D01*
X356841Y-58574D01*
Y-66074D01*
G01X363781D02*
X360047D01*
Y-58574D01*
X363781D01*
G01X362287Y-62199D02*
X360047D01*
G01X367267Y-66074D02*
Y-58574D01*
X371561Y-66074D01*
Y-58574D01*
G01X374861Y-66074D02*
Y-58574D01*
X376727D01*
X377474Y-58949D01*
X378034Y-59449D01*
X378501Y-60199D01*
X378874Y-61074D01*
X378967Y-62324D01*
X378874Y-63574D01*
X378501Y-64449D01*
X378034Y-65199D01*
X377474Y-65699D01*
X376727Y-66074D01*
X374861D01*
G01X386281D02*
X382547D01*
Y-58574D01*
X386281D01*
G01X384787Y-62199D02*
X382547D01*
G01X389861Y-66074D02*
Y-58574D01*
X391727D01*
X392474Y-58949D01*
X393034Y-59449D01*
X393501Y-60199D01*
X393874Y-61074D01*
X393967Y-62324D01*
X393874Y-63574D01*
X393501Y-64449D01*
X393034Y-65199D01*
X392474Y-65699D01*
X391727Y-66074D01*
X389861D01*
G01X404861D02*
Y-58574D01*
X406727D01*
X407474Y-58949D01*
X408034Y-59449D01*
X408501Y-60199D01*
X408874Y-61074D01*
X408967Y-62324D01*
X408874Y-63574D01*
X408501Y-64449D01*
X408034Y-65199D01*
X407474Y-65699D01*
X406727Y-66074D01*
X404861D01*
G01X412547D02*
Y-58574D01*
X414881D01*
X415627Y-58949D01*
X416094Y-59449D01*
X416281Y-60449D01*
X416094Y-61449D01*
X415534Y-62074D01*
X414881Y-62449D01*
X412547D01*
G01X414881D02*
X416281Y-66074D01*
G01X420794Y-58574D02*
X423034D01*
G01X421914D02*
Y-66074D01*
G01X420794D02*
X423034D01*
G01X427547Y-58574D02*
Y-66074D01*
X431281D01*
G01X435047Y-58574D02*
Y-66074D01*
X438781D01*
G01X449954Y-65074D02*
X450701Y-65699D01*
X451541Y-66074D01*
X452287D01*
X453034Y-65699D01*
X453594Y-65074D01*
X453874Y-64199D01*
X453687Y-63324D01*
X453221Y-62574D01*
X452381Y-62074D01*
X451261Y-61824D01*
X450607Y-61324D01*
X450327Y-60449D01*
X450514Y-59574D01*
X450981Y-58949D01*
X451634Y-58574D01*
X452287D01*
X452941Y-58824D01*
X453501Y-59449D01*
G01X458294Y-58574D02*
X460534D01*
G01X459414D02*
Y-66074D01*
G01X458294D02*
X460534D01*
G01X465141Y-58574D02*
X468687D01*
X465141Y-66074D01*
X468687D01*
G01X476281D02*
X472547D01*
Y-58574D01*
X476281D01*
G01X474787Y-62199D02*
X472547D01*
G01X487641Y-66074D02*
Y-58574D01*
X491187D01*
G01X489881Y-62199D02*
X487641D01*
G01X496914Y-66074D02*
X496167Y-65949D01*
X495514Y-65449D01*
X494954Y-64699D01*
X494581Y-63824D01*
X494394Y-62824D01*
Y-61824D01*
X494581Y-60824D01*
X494954Y-59949D01*
X495514Y-59199D01*
X496167Y-58699D01*
X496914Y-58574D01*
X497661Y-58699D01*
X498314Y-59199D01*
X498874Y-59949D01*
X499247Y-60824D01*
X499434Y-61824D01*
Y-62824D01*
X499247Y-63824D01*
X498874Y-64699D01*
X498314Y-65449D01*
X497661Y-65949D01*
X496914Y-66074D01*
G01X502547D02*
Y-58574D01*
X504881D01*
X505627Y-58949D01*
X506094Y-59449D01*
X506281Y-60449D01*
X506094Y-61449D01*
X505534Y-62074D01*
X504881Y-62449D01*
X502547D01*
G01X504881D02*
X506281Y-66074D01*
G01X519414Y-58574D02*
X518667Y-58824D01*
X518107Y-59449D01*
X517734Y-60199D01*
X517454Y-61199D01*
X517361Y-62324D01*
X517454Y-63449D01*
X517734Y-64449D01*
X518107Y-65199D01*
X518667Y-65824D01*
X519414Y-66074D01*
X520161Y-65824D01*
X520721Y-65199D01*
X521094Y-64449D01*
X521374Y-63449D01*
X521467Y-62324D01*
X521374Y-61199D01*
X521094Y-60199D01*
X520721Y-59449D01*
X520161Y-58824D01*
X519414Y-58574D01*
G01X526914Y-66324D02*
X526727Y-66199D01*
Y-65949D01*
X526914Y-65824D01*
X527101Y-65949D01*
Y-66199D01*
X526914Y-66324D01*
G01X534227Y-66074D02*
X534414Y-64449D01*
X534694Y-63074D01*
X535067Y-61824D01*
X535534Y-60449D01*
X536281Y-58574D01*
X532547D01*
G01X539861Y-64949D02*
X540421Y-65574D01*
X541074Y-65949D01*
X541914Y-66074D01*
X542754Y-65824D01*
X543407Y-65324D01*
X543874Y-64449D01*
X543967Y-63449D01*
X543781Y-62449D01*
X543314Y-61824D01*
X542661Y-61324D01*
X542007Y-61199D01*
X541354Y-61324D01*
X540514Y-61824D01*
X540794Y-58574D01*
X543314D01*
G01X546987Y-66074D02*
Y-58574D01*
X549414Y-64824D01*
X551841Y-58574D01*
Y-66074D01*
G01X554487D02*
Y-58574D01*
X556914Y-64824D01*
X559341Y-58574D01*
Y-66074D01*
G01X570141D02*
Y-58574D01*
X573687D01*
G01X572381Y-62199D02*
X570141D01*
G01X578294Y-58574D02*
X580534D01*
G01X579414D02*
Y-66074D01*
G01X578294D02*
X580534D01*
G01X584767D02*
Y-58574D01*
X589061Y-66074D01*
Y-58574D01*
G01X593294D02*
X595534D01*
G01X594414D02*
Y-66074D01*
G01X593294D02*
X595534D01*
G01X599954Y-65074D02*
X600701Y-65699D01*
X601541Y-66074D01*
X602287D01*
X603034Y-65699D01*
X603594Y-65074D01*
X603874Y-64199D01*
X603687Y-63324D01*
X603221Y-62574D01*
X602381Y-62074D01*
X601261Y-61824D01*
X600607Y-61324D01*
X600327Y-60449D01*
X600514Y-59574D01*
X600981Y-58949D01*
X601634Y-58574D01*
X602287D01*
X602941Y-58824D01*
X603501Y-59449D01*
G01X607454Y-66074D02*
Y-58574D01*
G01X611374D02*
Y-66074D01*
G01Y-62324D02*
X607454D01*
G01X618781Y-66074D02*
X615047D01*
Y-58574D01*
X618781D01*
G01X617287Y-62199D02*
X615047D01*
G01X622361Y-66074D02*
Y-58574D01*
X624227D01*
X624974Y-58949D01*
X625534Y-59449D01*
X626001Y-60199D01*
X626374Y-61074D01*
X626467Y-62324D01*
X626374Y-63574D01*
X626001Y-64449D01*
X625534Y-65199D01*
X624974Y-65699D01*
X624227Y-66074D01*
X622361D01*
G01X637547D02*
Y-58574D01*
X639787D01*
X640534Y-58949D01*
X641094Y-59824D01*
X641281Y-60824D01*
X641094Y-61824D01*
X640627Y-62574D01*
X639787Y-62949D01*
X637547D01*
G01X646914Y-58574D02*
Y-66074D01*
G01X644767Y-58574D02*
X649061D01*
G01X652454Y-66074D02*
Y-58574D01*
G01X656374D02*
Y-66074D01*
G01Y-62324D02*
X652454D01*
G01X668294Y-58574D02*
X670534D01*
G01X669414D02*
Y-66074D01*
G01X668294D02*
X670534D01*
G01X674954Y-65074D02*
X675701Y-65699D01*
X676541Y-66074D01*
X677287D01*
X678034Y-65699D01*
X678594Y-65074D01*
X678874Y-64199D01*
X678687Y-63324D01*
X678221Y-62574D01*
X677381Y-62074D01*
X676261Y-61824D01*
X675607Y-61324D01*
X675327Y-60449D01*
X675514Y-59574D01*
X675981Y-58949D01*
X676634Y-58574D01*
X677287D01*
X677941Y-58824D01*
X678501Y-59449D01*
G01X691914Y-58574D02*
X691167Y-58824D01*
X690607Y-59449D01*
X690234Y-60199D01*
X689954Y-61199D01*
X689861Y-62324D01*
X689954Y-63449D01*
X690234Y-64449D01*
X690607Y-65199D01*
X691167Y-65824D01*
X691914Y-66074D01*
X692661Y-65824D01*
X693221Y-65199D01*
X693594Y-64449D01*
X693874Y-63449D01*
X693967Y-62324D01*
X693874Y-61199D01*
X693594Y-60199D01*
X693221Y-59449D01*
X692661Y-58824D01*
X691914Y-58574D01*
G01X699414Y-66324D02*
X699227Y-66199D01*
Y-65949D01*
X699414Y-65824D01*
X699601Y-65949D01*
Y-66199D01*
X699414Y-66324D01*
G01X706914Y-66074D02*
X707567Y-65949D01*
X708314Y-65574D01*
X708781Y-64949D01*
X708967Y-64074D01*
X708781Y-63199D01*
X708221Y-62449D01*
X707381Y-62074D01*
X706447D01*
X705887Y-61824D01*
X705421Y-61199D01*
X705234Y-60324D01*
X705514Y-59449D01*
X706167Y-58824D01*
X706914Y-58574D01*
X707661Y-58824D01*
X708314Y-59449D01*
X708594Y-60324D01*
X708407Y-61199D01*
X707941Y-61824D01*
X707381Y-62074D01*
X706447D01*
X705607Y-62449D01*
X705047Y-63199D01*
X704861Y-64074D01*
X705047Y-64949D01*
X705514Y-65574D01*
X706261Y-65949D01*
X706914Y-66074D01*
G01X714414D02*
Y-58574D01*
X713294Y-60074D01*
G01Y-66074D02*
X715534D01*
G01X720701Y-63574D02*
X723127D01*
G01X729414Y-58574D02*
X728667Y-58824D01*
X728107Y-59449D01*
X727734Y-60199D01*
X727454Y-61199D01*
X727361Y-62324D01*
X727454Y-63449D01*
X727734Y-64449D01*
X728107Y-65199D01*
X728667Y-65824D01*
X729414Y-66074D01*
X730161Y-65824D01*
X730721Y-65199D01*
X731094Y-64449D01*
X731374Y-63449D01*
X731467Y-62324D01*
X731374Y-61199D01*
X731094Y-60199D01*
X730721Y-59449D01*
X730161Y-58824D01*
X729414Y-58574D01*
G01X736914Y-66324D02*
X736727Y-66199D01*
Y-65949D01*
X736914Y-65824D01*
X737101Y-65949D01*
Y-66199D01*
X736914Y-66324D01*
G01X744414Y-66074D02*
X745067Y-65949D01*
X745814Y-65574D01*
X746281Y-64949D01*
X746467Y-64074D01*
X746281Y-63199D01*
X745721Y-62449D01*
X744881Y-62074D01*
X743947D01*
X743387Y-61824D01*
X742921Y-61199D01*
X742734Y-60324D01*
X743014Y-59449D01*
X743667Y-58824D01*
X744414Y-58574D01*
X745161Y-58824D01*
X745814Y-59449D01*
X746094Y-60324D01*
X745907Y-61199D01*
X745441Y-61824D01*
X744881Y-62074D01*
X743947D01*
X743107Y-62449D01*
X742547Y-63199D01*
X742361Y-64074D01*
X742547Y-64949D01*
X743014Y-65574D01*
X743761Y-65949D01*
X744414Y-66074D01*
G01X750141Y-62949D02*
X750794Y-62074D01*
X751354Y-61574D01*
X752101Y-61324D01*
X752754Y-61574D01*
X753221Y-62074D01*
X753594Y-62824D01*
X753687Y-63699D01*
X753594Y-64449D01*
X753221Y-65199D01*
X752661Y-65824D01*
X752007Y-66074D01*
X751261Y-65824D01*
X750607Y-65074D01*
X750234Y-63949D01*
X750141Y-62699D01*
X750327Y-61074D01*
X750607Y-60199D01*
X751074Y-59324D01*
X751727Y-58699D01*
X752381Y-58574D01*
X753034Y-58824D01*
X753501Y-59449D01*
G01X756987Y-66074D02*
Y-58574D01*
X759414Y-64824D01*
X761841Y-58574D01*
Y-66074D01*
G01X764487D02*
Y-58574D01*
X766914Y-64824D01*
X769341Y-58574D01*
Y-66074D01*
G01X773947Y-68574D02*
X773014Y-67324D01*
X772547Y-66074D01*
Y-61074D01*
X773014Y-59824D01*
X773947Y-58574D01*
G01X781914D02*
X781167Y-58824D01*
X780607Y-59449D01*
X780234Y-60199D01*
X779954Y-61199D01*
X779861Y-62324D01*
X779954Y-63449D01*
X780234Y-64449D01*
X780607Y-65199D01*
X781167Y-65824D01*
X781914Y-66074D01*
X782661Y-65824D01*
X783221Y-65199D01*
X783594Y-64449D01*
X783874Y-63449D01*
X783967Y-62324D01*
X783874Y-61199D01*
X783594Y-60199D01*
X783221Y-59449D01*
X782661Y-58824D01*
X781914Y-58574D01*
G01X789414Y-66324D02*
X789227Y-66199D01*
Y-65949D01*
X789414Y-65824D01*
X789601Y-65949D01*
Y-66199D01*
X789414Y-66324D01*
G01X796914Y-66074D02*
X797567Y-65949D01*
X798314Y-65574D01*
X798781Y-64949D01*
X798967Y-64074D01*
X798781Y-63199D01*
X798221Y-62449D01*
X797381Y-62074D01*
X796447D01*
X795887Y-61824D01*
X795421Y-61199D01*
X795234Y-60324D01*
X795514Y-59449D01*
X796167Y-58824D01*
X796914Y-58574D01*
X797661Y-58824D01*
X798314Y-59449D01*
X798594Y-60324D01*
X798407Y-61199D01*
X797941Y-61824D01*
X797381Y-62074D01*
X796447D01*
X795607Y-62449D01*
X795047Y-63199D01*
X794861Y-64074D01*
X795047Y-64949D01*
X795514Y-65574D01*
X796261Y-65949D01*
X796914Y-66074D01*
G01X802361Y-64949D02*
X802921Y-65574D01*
X803574Y-65949D01*
X804414Y-66074D01*
X805254Y-65824D01*
X805907Y-65324D01*
X806374Y-64449D01*
X806467Y-63449D01*
X806281Y-62449D01*
X805814Y-61824D01*
X805161Y-61324D01*
X804507Y-61199D01*
X803854Y-61324D01*
X803014Y-61824D01*
X803294Y-58574D01*
X805814D01*
G01X809487Y-66074D02*
Y-58574D01*
X811914Y-64824D01*
X814341Y-58574D01*
Y-66074D01*
G01X816987D02*
Y-58574D01*
X819414Y-64824D01*
X821841Y-58574D01*
Y-66074D01*
G01X832361D02*
Y-58574D01*
X834227D01*
X834974Y-58949D01*
X835534Y-59449D01*
X836001Y-60199D01*
X836374Y-61074D01*
X836467Y-62324D01*
X836374Y-63574D01*
X836001Y-64449D01*
X835534Y-65199D01*
X834974Y-65699D01*
X834227Y-66074D01*
X832361D01*
G01X840047D02*
Y-58574D01*
X842381D01*
X843127Y-58949D01*
X843594Y-59449D01*
X843781Y-60449D01*
X843594Y-61449D01*
X843034Y-62074D01*
X842381Y-62449D01*
X840047D01*
G01X842381D02*
X843781Y-66074D01*
G01X848294Y-58574D02*
X850534D01*
G01X849414D02*
Y-66074D01*
G01X848294D02*
X850534D01*
G01X855047Y-58574D02*
Y-66074D01*
X858781D01*
G01X862547Y-58574D02*
Y-66074D01*
X866281D01*
G01X872381Y-68574D02*
X873314Y-67324D01*
X873781Y-66074D01*
Y-61074D01*
X873314Y-59824D01*
X872381Y-58574D01*
G01X158714Y-46174D02*
Y-53674D01*
G01X156567Y-46174D02*
X160861D01*
G01X165094D02*
X167334D01*
G01X166214D02*
Y-53674D01*
G01X165094D02*
X167334D01*
G01X171567D02*
Y-46174D01*
X175861Y-53674D01*
Y-46174D01*
G01X180001Y-51174D02*
X182427D01*
G01X186847Y-46174D02*
Y-53674D01*
X190581D01*
G01X198081D02*
X194347D01*
Y-46174D01*
X198081D01*
G01X196587Y-49799D02*
X194347D01*
G01X201381Y-53674D02*
X203714Y-46174D01*
X206047Y-53674D01*
G01X205207Y-51049D02*
X202221D01*
G01X209161Y-53674D02*
Y-46174D01*
X211027D01*
X211774Y-46549D01*
X212334Y-47049D01*
X212801Y-47799D01*
X213174Y-48674D01*
X213267Y-49924D01*
X213174Y-51174D01*
X212801Y-52049D01*
X212334Y-52799D01*
X211774Y-53299D01*
X211027Y-53674D01*
X209161D01*
G01X218714Y-53924D02*
X218527Y-53799D01*
Y-53549D01*
X218714Y-53424D01*
X218901Y-53549D01*
Y-53799D01*
X218714Y-53924D01*
G01Y-50549D02*
X218527Y-50424D01*
Y-50174D01*
X218714Y-50049D01*
X218901Y-50174D01*
Y-50424D01*
X218714Y-50549D01*
G01X224347Y-53674D02*
Y-46174D01*
X226681D01*
X227427Y-46549D01*
X227894Y-47049D01*
X228081Y-48049D01*
X227894Y-49049D01*
X227334Y-49674D01*
X226681Y-50049D01*
X224347D01*
G01X226681D02*
X228081Y-53674D01*
G01X235581D02*
X231847D01*
Y-46174D01*
X235581D01*
G01X234087Y-49799D02*
X231847D01*
G01X243267Y-46799D02*
X242707Y-46424D01*
X242054Y-46174D01*
X241307D01*
X240467Y-46549D01*
X239814Y-47174D01*
X239347Y-47924D01*
X238974Y-49174D01*
X238881Y-50299D01*
X239067Y-51424D01*
X239347Y-52174D01*
X239907Y-52924D01*
X240561Y-53424D01*
X241214Y-53674D01*
X241867D01*
X242521Y-53424D01*
X243081Y-53049D01*
X243547Y-52549D01*
G01X248714Y-53674D02*
X247967Y-53549D01*
X247314Y-53049D01*
X246754Y-52299D01*
X246381Y-51424D01*
X246194Y-50424D01*
Y-49424D01*
X246381Y-48424D01*
X246754Y-47549D01*
X247314Y-46799D01*
X247967Y-46299D01*
X248714Y-46174D01*
X249461Y-46299D01*
X250114Y-46799D01*
X250674Y-47549D01*
X251047Y-48424D01*
X251234Y-49424D01*
Y-50424D01*
X251047Y-51424D01*
X250674Y-52299D01*
X250114Y-53049D01*
X249461Y-53549D01*
X248714Y-53674D01*
G01X253787D02*
Y-46174D01*
X256214Y-52424D01*
X258641Y-46174D01*
Y-53674D01*
G01X261287D02*
Y-46174D01*
X263714Y-52424D01*
X266141Y-46174D01*
Y-53674D01*
G01X273081D02*
X269347D01*
Y-46174D01*
X273081D01*
G01X271587Y-49799D02*
X269347D01*
G01X276567Y-53674D02*
Y-46174D01*
X280861Y-53674D01*
Y-46174D01*
G01X284161Y-53674D02*
Y-46174D01*
X286027D01*
X286774Y-46549D01*
X287334Y-47049D01*
X287801Y-47799D01*
X288174Y-48674D01*
X288267Y-49924D01*
X288174Y-51174D01*
X287801Y-52049D01*
X287334Y-52799D01*
X286774Y-53299D01*
X286027Y-53674D01*
X284161D01*
G01X295581D02*
X291847D01*
Y-46174D01*
X295581D01*
G01X294087Y-49799D02*
X291847D01*
G01X299161Y-53674D02*
Y-46174D01*
X301027D01*
X301774Y-46549D01*
X302334Y-47049D01*
X302801Y-47799D01*
X303174Y-48674D01*
X303267Y-49924D01*
X303174Y-51174D01*
X302801Y-52049D01*
X302334Y-52799D01*
X301774Y-53299D01*
X301027Y-53674D01*
X299161D01*
G01X314161D02*
Y-46174D01*
X316027D01*
X316774Y-46549D01*
X317334Y-47049D01*
X317801Y-47799D01*
X318174Y-48674D01*
X318267Y-49924D01*
X318174Y-51174D01*
X317801Y-52049D01*
X317334Y-52799D01*
X316774Y-53299D01*
X316027Y-53674D01*
X314161D01*
G01X321847D02*
Y-46174D01*
X324181D01*
X324927Y-46549D01*
X325394Y-47049D01*
X325581Y-48049D01*
X325394Y-49049D01*
X324834Y-49674D01*
X324181Y-50049D01*
X321847D01*
G01X324181D02*
X325581Y-53674D01*
G01X330094Y-46174D02*
X332334D01*
G01X331214D02*
Y-53674D01*
G01X330094D02*
X332334D01*
G01X336847Y-46174D02*
Y-53674D01*
X340581D01*
G01X344347Y-46174D02*
Y-53674D01*
X348081D01*
G01X359254Y-52674D02*
X360001Y-53299D01*
X360841Y-53674D01*
X361587D01*
X362334Y-53299D01*
X362894Y-52674D01*
X363174Y-51799D01*
X362987Y-50924D01*
X362521Y-50174D01*
X361681Y-49674D01*
X360561Y-49424D01*
X359907Y-48924D01*
X359627Y-48049D01*
X359814Y-47174D01*
X360281Y-46549D01*
X360934Y-46174D01*
X361587D01*
X362241Y-46424D01*
X362801Y-47049D01*
G01X367594Y-46174D02*
X369834D01*
G01X368714D02*
Y-53674D01*
G01X367594D02*
X369834D01*
G01X374441Y-46174D02*
X377987D01*
X374441Y-53674D01*
X377987D01*
G01X385581D02*
X381847D01*
Y-46174D01*
X385581D01*
G01X384087Y-49799D02*
X381847D01*
G01X396941Y-53674D02*
Y-46174D01*
X400487D01*
G01X399181Y-49799D02*
X396941D01*
G01X406214Y-53674D02*
X405467Y-53549D01*
X404814Y-53049D01*
X404254Y-52299D01*
X403881Y-51424D01*
X403694Y-50424D01*
Y-49424D01*
X403881Y-48424D01*
X404254Y-47549D01*
X404814Y-46799D01*
X405467Y-46299D01*
X406214Y-46174D01*
X406961Y-46299D01*
X407614Y-46799D01*
X408174Y-47549D01*
X408547Y-48424D01*
X408734Y-49424D01*
Y-50424D01*
X408547Y-51424D01*
X408174Y-52299D01*
X407614Y-53049D01*
X406961Y-53549D01*
X406214Y-53674D01*
G01X411847D02*
Y-46174D01*
X414181D01*
X414927Y-46549D01*
X415394Y-47049D01*
X415581Y-48049D01*
X415394Y-49049D01*
X414834Y-49674D01*
X414181Y-50049D01*
X411847D01*
G01X414181D02*
X415581Y-53674D01*
G01X428714Y-46174D02*
X427967Y-46424D01*
X427407Y-47049D01*
X427034Y-47799D01*
X426754Y-48799D01*
X426661Y-49924D01*
X426754Y-51049D01*
X427034Y-52049D01*
X427407Y-52799D01*
X427967Y-53424D01*
X428714Y-53674D01*
X429461Y-53424D01*
X430021Y-52799D01*
X430394Y-52049D01*
X430674Y-51049D01*
X430767Y-49924D01*
X430674Y-48799D01*
X430394Y-47799D01*
X430021Y-47049D01*
X429461Y-46424D01*
X428714Y-46174D01*
G01X436214Y-53924D02*
X436027Y-53799D01*
Y-53549D01*
X436214Y-53424D01*
X436401Y-53549D01*
Y-53799D01*
X436214Y-53924D01*
G01X443527Y-53674D02*
X443714Y-52049D01*
X443994Y-50674D01*
X444367Y-49424D01*
X444834Y-48049D01*
X445581Y-46174D01*
X441847D01*
G01X449441Y-47424D02*
X450001Y-46674D01*
X450654Y-46299D01*
X451401Y-46174D01*
X452334Y-46424D01*
X452987Y-47049D01*
X453174Y-47799D01*
X453081Y-48549D01*
X452707Y-49174D01*
X450841Y-50424D01*
X450001Y-51299D01*
X449441Y-52549D01*
X449254Y-53674D01*
X453174D01*
G01X456661Y-52549D02*
X457221Y-53174D01*
X457874Y-53549D01*
X458714Y-53674D01*
X459554Y-53424D01*
X460207Y-52924D01*
X460674Y-52049D01*
X460767Y-51049D01*
X460581Y-50049D01*
X460114Y-49424D01*
X459461Y-48924D01*
X458807Y-48799D01*
X458154Y-48924D01*
X457314Y-49424D01*
X457594Y-46174D01*
X460114D01*
G01X463787Y-53674D02*
Y-46174D01*
X466214Y-52424D01*
X468641Y-46174D01*
Y-53674D01*
G01X471287D02*
Y-46174D01*
X473714Y-52424D01*
X476141Y-46174D01*
Y-53674D01*
G01X486941D02*
Y-46174D01*
X490487D01*
G01X489181Y-49799D02*
X486941D01*
G01X495094Y-46174D02*
X497334D01*
G01X496214D02*
Y-53674D01*
G01X495094D02*
X497334D01*
G01X501567D02*
Y-46174D01*
X505861Y-53674D01*
Y-46174D01*
G01X510094D02*
X512334D01*
G01X511214D02*
Y-53674D01*
G01X510094D02*
X512334D01*
G01X516754Y-52674D02*
X517501Y-53299D01*
X518341Y-53674D01*
X519087D01*
X519834Y-53299D01*
X520394Y-52674D01*
X520674Y-51799D01*
X520487Y-50924D01*
X520021Y-50174D01*
X519181Y-49674D01*
X518061Y-49424D01*
X517407Y-48924D01*
X517127Y-48049D01*
X517314Y-47174D01*
X517781Y-46549D01*
X518434Y-46174D01*
X519087D01*
X519741Y-46424D01*
X520301Y-47049D01*
G01X524254Y-53674D02*
Y-46174D01*
G01X528174D02*
Y-53674D01*
G01Y-49924D02*
X524254D01*
G01X535581Y-53674D02*
X531847D01*
Y-46174D01*
X535581D01*
G01X534087Y-49799D02*
X531847D01*
G01X539161Y-53674D02*
Y-46174D01*
X541027D01*
X541774Y-46549D01*
X542334Y-47049D01*
X542801Y-47799D01*
X543174Y-48674D01*
X543267Y-49924D01*
X543174Y-51174D01*
X542801Y-52049D01*
X542334Y-52799D01*
X541774Y-53299D01*
X541027Y-53674D01*
X539161D01*
G01X554347D02*
Y-46174D01*
X556587D01*
X557334Y-46549D01*
X557894Y-47424D01*
X558081Y-48424D01*
X557894Y-49424D01*
X557427Y-50174D01*
X556587Y-50549D01*
X554347D01*
G01X563714Y-46174D02*
Y-53674D01*
G01X561567Y-46174D02*
X565861D01*
G01X569254Y-53674D02*
Y-46174D01*
G01X573174D02*
Y-53674D01*
G01Y-49924D02*
X569254D01*
G01X585094Y-46174D02*
X587334D01*
G01X586214D02*
Y-53674D01*
G01X585094D02*
X587334D01*
G01X591754Y-52674D02*
X592501Y-53299D01*
X593341Y-53674D01*
X594087D01*
X594834Y-53299D01*
X595394Y-52674D01*
X595674Y-51799D01*
X595487Y-50924D01*
X595021Y-50174D01*
X594181Y-49674D01*
X593061Y-49424D01*
X592407Y-48924D01*
X592127Y-48049D01*
X592314Y-47174D01*
X592781Y-46549D01*
X593434Y-46174D01*
X594087D01*
X594741Y-46424D01*
X595301Y-47049D01*
G01X608714Y-46174D02*
X607967Y-46424D01*
X607407Y-47049D01*
X607034Y-47799D01*
X606754Y-48799D01*
X606661Y-49924D01*
X606754Y-51049D01*
X607034Y-52049D01*
X607407Y-52799D01*
X607967Y-53424D01*
X608714Y-53674D01*
X609461Y-53424D01*
X610021Y-52799D01*
X610394Y-52049D01*
X610674Y-51049D01*
X610767Y-49924D01*
X610674Y-48799D01*
X610394Y-47799D01*
X610021Y-47049D01*
X609461Y-46424D01*
X608714Y-46174D01*
G01X616214Y-53924D02*
X616027Y-53799D01*
Y-53549D01*
X616214Y-53424D01*
X616401Y-53549D01*
Y-53799D01*
X616214Y-53924D01*
G01X623714Y-53674D02*
X624367Y-53549D01*
X625114Y-53174D01*
X625581Y-52549D01*
X625767Y-51674D01*
X625581Y-50799D01*
X625021Y-50049D01*
X624181Y-49674D01*
X623247D01*
X622687Y-49424D01*
X622221Y-48799D01*
X622034Y-47924D01*
X622314Y-47049D01*
X622967Y-46424D01*
X623714Y-46174D01*
X624461Y-46424D01*
X625114Y-47049D01*
X625394Y-47924D01*
X625207Y-48799D01*
X624741Y-49424D01*
X624181Y-49674D01*
X623247D01*
X622407Y-50049D01*
X621847Y-50799D01*
X621661Y-51674D01*
X621847Y-52549D01*
X622314Y-53174D01*
X623061Y-53549D01*
X623714Y-53674D01*
G01X631214D02*
Y-46174D01*
X630094Y-47674D01*
G01Y-53674D02*
X632334D01*
G01X637501Y-51174D02*
X639927D01*
G01X646214Y-46174D02*
X645467Y-46424D01*
X644907Y-47049D01*
X644534Y-47799D01*
X644254Y-48799D01*
X644161Y-49924D01*
X644254Y-51049D01*
X644534Y-52049D01*
X644907Y-52799D01*
X645467Y-53424D01*
X646214Y-53674D01*
X646961Y-53424D01*
X647521Y-52799D01*
X647894Y-52049D01*
X648174Y-51049D01*
X648267Y-49924D01*
X648174Y-48799D01*
X647894Y-47799D01*
X647521Y-47049D01*
X646961Y-46424D01*
X646214Y-46174D01*
G01X653714Y-53924D02*
X653527Y-53799D01*
Y-53549D01*
X653714Y-53424D01*
X653901Y-53549D01*
Y-53799D01*
X653714Y-53924D01*
G01X661214Y-53674D02*
X661867Y-53549D01*
X662614Y-53174D01*
X663081Y-52549D01*
X663267Y-51674D01*
X663081Y-50799D01*
X662521Y-50049D01*
X661681Y-49674D01*
X660747D01*
X660187Y-49424D01*
X659721Y-48799D01*
X659534Y-47924D01*
X659814Y-47049D01*
X660467Y-46424D01*
X661214Y-46174D01*
X661961Y-46424D01*
X662614Y-47049D01*
X662894Y-47924D01*
X662707Y-48799D01*
X662241Y-49424D01*
X661681Y-49674D01*
X660747D01*
X659907Y-50049D01*
X659347Y-50799D01*
X659161Y-51674D01*
X659347Y-52549D01*
X659814Y-53174D01*
X660561Y-53549D01*
X661214Y-53674D01*
G01X666941Y-50549D02*
X667594Y-49674D01*
X668154Y-49174D01*
X668901Y-48924D01*
X669554Y-49174D01*
X670021Y-49674D01*
X670394Y-50424D01*
X670487Y-51299D01*
X670394Y-52049D01*
X670021Y-52799D01*
X669461Y-53424D01*
X668807Y-53674D01*
X668061Y-53424D01*
X667407Y-52674D01*
X667034Y-51549D01*
X666941Y-50299D01*
X667127Y-48674D01*
X667407Y-47799D01*
X667874Y-46924D01*
X668527Y-46299D01*
X669181Y-46174D01*
X669834Y-46424D01*
X670301Y-47049D01*
G01X673787Y-53674D02*
Y-46174D01*
X676214Y-52424D01*
X678641Y-46174D01*
Y-53674D01*
G01X681287D02*
Y-46174D01*
X683714Y-52424D01*
X686141Y-46174D01*
Y-53674D01*
G01X690747Y-56174D02*
X689814Y-54924D01*
X689347Y-53674D01*
Y-48674D01*
X689814Y-47424D01*
X690747Y-46174D01*
G01X698714D02*
X697967Y-46424D01*
X697407Y-47049D01*
X697034Y-47799D01*
X696754Y-48799D01*
X696661Y-49924D01*
X696754Y-51049D01*
X697034Y-52049D01*
X697407Y-52799D01*
X697967Y-53424D01*
X698714Y-53674D01*
X699461Y-53424D01*
X700021Y-52799D01*
X700394Y-52049D01*
X700674Y-51049D01*
X700767Y-49924D01*
X700674Y-48799D01*
X700394Y-47799D01*
X700021Y-47049D01*
X699461Y-46424D01*
X698714Y-46174D01*
G01X706214Y-53924D02*
X706027Y-53799D01*
Y-53549D01*
X706214Y-53424D01*
X706401Y-53549D01*
Y-53799D01*
X706214Y-53924D01*
G01X713714Y-53674D02*
X714367Y-53549D01*
X715114Y-53174D01*
X715581Y-52549D01*
X715767Y-51674D01*
X715581Y-50799D01*
X715021Y-50049D01*
X714181Y-49674D01*
X713247D01*
X712687Y-49424D01*
X712221Y-48799D01*
X712034Y-47924D01*
X712314Y-47049D01*
X712967Y-46424D01*
X713714Y-46174D01*
X714461Y-46424D01*
X715114Y-47049D01*
X715394Y-47924D01*
X715207Y-48799D01*
X714741Y-49424D01*
X714181Y-49674D01*
X713247D01*
X712407Y-50049D01*
X711847Y-50799D01*
X711661Y-51674D01*
X711847Y-52549D01*
X712314Y-53174D01*
X713061Y-53549D01*
X713714Y-53674D01*
G01X719161Y-52549D02*
X719721Y-53174D01*
X720374Y-53549D01*
X721214Y-53674D01*
X722054Y-53424D01*
X722707Y-52924D01*
X723174Y-52049D01*
X723267Y-51049D01*
X723081Y-50049D01*
X722614Y-49424D01*
X721961Y-48924D01*
X721307Y-48799D01*
X720654Y-48924D01*
X719814Y-49424D01*
X720094Y-46174D01*
X722614D01*
G01X726287Y-53674D02*
Y-46174D01*
X728714Y-52424D01*
X731141Y-46174D01*
Y-53674D01*
G01X733787D02*
Y-46174D01*
X736214Y-52424D01*
X738641Y-46174D01*
Y-53674D01*
G01X749161D02*
Y-46174D01*
X751027D01*
X751774Y-46549D01*
X752334Y-47049D01*
X752801Y-47799D01*
X753174Y-48674D01*
X753267Y-49924D01*
X753174Y-51174D01*
X752801Y-52049D01*
X752334Y-52799D01*
X751774Y-53299D01*
X751027Y-53674D01*
X749161D01*
G01X756847D02*
Y-46174D01*
X759181D01*
X759927Y-46549D01*
X760394Y-47049D01*
X760581Y-48049D01*
X760394Y-49049D01*
X759834Y-49674D01*
X759181Y-50049D01*
X756847D01*
G01X759181D02*
X760581Y-53674D01*
G01X765094Y-46174D02*
X767334D01*
G01X766214D02*
Y-53674D01*
G01X765094D02*
X767334D01*
G01X771847Y-46174D02*
Y-53674D01*
X775581D01*
G01X779347Y-46174D02*
Y-53674D01*
X783081D01*
G01X789181Y-56174D02*
X790114Y-54924D01*
X790581Y-53674D01*
Y-48674D01*
X790114Y-47424D01*
X789181Y-46174D01*
G01X153553Y746940D02*
X155012Y747870D01*
X155845Y749110D01*
X156053Y750505D01*
X155845Y751745D01*
X154803Y752985D01*
X153553Y753760D01*
X152303Y753915D01*
X150845Y753605D01*
X149803Y752520D01*
X149386Y751435D01*
Y750040D01*
G01Y751435D02*
X148761Y752365D01*
X147720Y753140D01*
X146470Y753450D01*
X145220Y753140D01*
X144178Y752365D01*
X143553Y750970D01*
X143761Y749575D01*
X144595Y748180D01*
G01X156053Y764610D02*
X143553D01*
X152511Y758875D01*
Y766625D01*
G01X156470Y775150D02*
X156261Y774840D01*
X155845D01*
X155636Y775150D01*
X155845Y775460D01*
X156261D01*
X156470Y775150D01*
G01X156053Y787550D02*
X155845Y788635D01*
X155220Y789875D01*
X154178Y790650D01*
X152720Y790960D01*
X151262Y790650D01*
X150011Y789720D01*
X149386Y788325D01*
Y786775D01*
X148970Y785845D01*
X147928Y785070D01*
X146470Y784760D01*
X145011Y785225D01*
X143970Y786310D01*
X143553Y787550D01*
X143970Y788790D01*
X145011Y789875D01*
X146470Y790340D01*
X147928Y790030D01*
X148970Y789255D01*
X149386Y788325D01*
Y786775D01*
X150011Y785380D01*
X151262Y784450D01*
X152720Y784140D01*
X154178Y784450D01*
X155220Y785225D01*
X155845Y786465D01*
X156053Y787550D01*
G01Y799640D02*
X153345Y799950D01*
X151053Y800415D01*
X148970Y801035D01*
X146678Y801810D01*
X143553Y803050D01*
Y796850D01*
G01X224433Y-151145D02*
X223184Y-150215D01*
X222558Y-149130D01*
X222350Y-147890D01*
X222767Y-146340D01*
X223808Y-145255D01*
X225058Y-144945D01*
X226309Y-145100D01*
X227350Y-145720D01*
X229433Y-148820D01*
X230892Y-150215D01*
X232975Y-151145D01*
X234850Y-151455D01*
Y-144945D01*
G01Y-136110D02*
X232142Y-135800D01*
X229850Y-135335D01*
X227767Y-134715D01*
X225475Y-133940D01*
X222350Y-132700D01*
Y-138900D01*
G01X234850Y-121540D02*
X222350D01*
X231308Y-127275D01*
Y-119525D01*
G01X229642Y-113945D02*
X228183Y-112860D01*
X227350Y-111930D01*
X226933Y-110690D01*
X227350Y-109605D01*
X228183Y-108830D01*
X229433Y-108210D01*
X230892Y-108055D01*
X232142Y-108210D01*
X233392Y-108830D01*
X234433Y-109760D01*
X234850Y-110845D01*
X234433Y-112085D01*
X233184Y-113170D01*
X231308Y-113790D01*
X229225Y-113945D01*
X226517Y-113635D01*
X225058Y-113170D01*
X223600Y-112395D01*
X222558Y-111310D01*
X222350Y-110225D01*
X222767Y-109140D01*
X223808Y-108365D01*
G01X235267Y-98600D02*
X235058Y-98910D01*
X234642D01*
X234433Y-98600D01*
X234642Y-98290D01*
X235058D01*
X235267Y-98600D01*
G01X234850Y-84340D02*
X222350D01*
X231308Y-90075D01*
Y-82325D01*
G01X229642Y-76745D02*
X228183Y-75660D01*
X227350Y-74730D01*
X226933Y-73490D01*
X227350Y-72405D01*
X228183Y-71630D01*
X229433Y-71010D01*
X230892Y-70855D01*
X232142Y-71010D01*
X233392Y-71630D01*
X234433Y-72560D01*
X234850Y-73645D01*
X234433Y-74885D01*
X233184Y-75970D01*
X231308Y-76590D01*
X229225Y-76745D01*
X226517Y-76435D01*
X225058Y-75970D01*
X223600Y-75195D01*
X222558Y-74110D01*
X222350Y-73025D01*
X222767Y-71940D01*
X223808Y-71165D01*
G01X206955Y740855D02*
X205706Y741785D01*
X205080Y742870D01*
X204872Y744110D01*
X205289Y745660D01*
X206330Y746745D01*
X207580Y747055D01*
X208831Y746900D01*
X209872Y746280D01*
X211955Y743180D01*
X213414Y741785D01*
X215497Y740855D01*
X217372Y740545D01*
Y747055D01*
G01X206955Y753255D02*
X205706Y754185D01*
X205080Y755270D01*
X204872Y756510D01*
X205289Y758060D01*
X206330Y759145D01*
X207580Y759455D01*
X208831Y759300D01*
X209872Y758680D01*
X211955Y755580D01*
X213414Y754185D01*
X215497Y753255D01*
X217372Y752945D01*
Y759455D01*
G01X214872Y765190D02*
X216331Y766120D01*
X217164Y767360D01*
X217372Y768755D01*
X217164Y769995D01*
X216122Y771235D01*
X214872Y772010D01*
X213622Y772165D01*
X212164Y771855D01*
X211122Y770770D01*
X210705Y769685D01*
Y768290D01*
G01Y769685D02*
X210080Y770615D01*
X209039Y771390D01*
X207789Y771700D01*
X206539Y771390D01*
X205497Y770615D01*
X204872Y769220D01*
X205080Y767825D01*
X205914Y766430D01*
G01X212164Y778055D02*
X210705Y779140D01*
X209872Y780070D01*
X209455Y781310D01*
X209872Y782395D01*
X210705Y783170D01*
X211955Y783790D01*
X213414Y783945D01*
X214664Y783790D01*
X215914Y783170D01*
X216955Y782240D01*
X217372Y781155D01*
X216955Y779915D01*
X215706Y778830D01*
X213830Y778210D01*
X211747Y778055D01*
X209039Y778365D01*
X207580Y778830D01*
X206122Y779605D01*
X205080Y780690D01*
X204872Y781775D01*
X205289Y782860D01*
X206330Y783635D01*
G01X217789Y793400D02*
X217580Y793090D01*
X217164D01*
X216955Y793400D01*
X217164Y793710D01*
X217580D01*
X217789Y793400D01*
G01X206955Y802855D02*
X205706Y803785D01*
X205080Y804870D01*
X204872Y806110D01*
X205289Y807660D01*
X206330Y808745D01*
X207580Y809055D01*
X208831Y808900D01*
X209872Y808280D01*
X211955Y805180D01*
X213414Y803785D01*
X215497Y802855D01*
X217372Y802545D01*
Y809055D01*
G01X206955Y815255D02*
X205706Y816185D01*
X205080Y817270D01*
X204872Y818510D01*
X205289Y820060D01*
X206330Y821145D01*
X207580Y821455D01*
X208831Y821300D01*
X209872Y820680D01*
X211955Y817580D01*
X213414Y816185D01*
X215497Y815255D01*
X217372Y814945D01*
Y821455D01*
G01X243000Y-1004500D02*
Y-1012500D01*
X247000D01*
G01X254800D02*
Y-1007167D01*
G01Y-1008100D02*
X254400Y-1007567D01*
X253800Y-1007300D01*
X253100Y-1007167D01*
X252400Y-1007433D01*
X251800Y-1007967D01*
X251400Y-1008767D01*
X251200Y-1009833D01*
X251400Y-1010900D01*
X251800Y-1011700D01*
X252400Y-1012233D01*
X253100Y-1012500D01*
X253800Y-1012367D01*
X254400Y-1011967D01*
X254800Y-1011434D01*
G01X258900Y-1014900D02*
X259500Y-1015167D01*
X260300Y-1014900D01*
X260800Y-1014367D01*
X261200Y-1013700D01*
X261800Y-1011567D01*
X263100Y-1007167D01*
G01X259900D02*
X261800Y-1011567D01*
G01X267500Y-1008900D02*
X270700D01*
X270400Y-1007967D01*
X269900Y-1007433D01*
X269200Y-1007167D01*
X268500Y-1007300D01*
X267900Y-1007700D01*
X267500Y-1008633D01*
X267300Y-1009434D01*
Y-1010233D01*
X267500Y-1011033D01*
X268000Y-1011833D01*
X268600Y-1012367D01*
X269300Y-1012500D01*
X270000Y-1012233D01*
X270700Y-1011434D01*
G01X275600Y-1012500D02*
Y-1007167D01*
G01Y-1008233D02*
X276100Y-1007700D01*
X276600Y-1007300D01*
X277300Y-1007167D01*
X277800Y-1007300D01*
X278400Y-1007700D01*
G01X254642Y-138595D02*
X253183Y-137510D01*
X252350Y-136580D01*
X251933Y-135340D01*
X252350Y-134255D01*
X253183Y-133480D01*
X254433Y-132860D01*
X255892Y-132705D01*
X257142Y-132860D01*
X258392Y-133480D01*
X259433Y-134410D01*
X259850Y-135495D01*
X259433Y-136735D01*
X258184Y-137820D01*
X256308Y-138440D01*
X254225Y-138595D01*
X251517Y-138285D01*
X250058Y-137820D01*
X248600Y-137045D01*
X247558Y-135960D01*
X247350Y-134875D01*
X247767Y-133790D01*
X248808Y-133015D01*
G01X258392Y-125885D02*
X259433Y-124800D01*
X259850Y-123560D01*
X259433Y-122320D01*
X258184Y-121235D01*
X256308Y-120460D01*
X254433Y-120150D01*
X252142D01*
X250267Y-120460D01*
X248600Y-121235D01*
X247767Y-122165D01*
X247350Y-123250D01*
X247767Y-124490D01*
X248600Y-125420D01*
X249850Y-126040D01*
X251517Y-126350D01*
X252975Y-126040D01*
X254433Y-125265D01*
X255267Y-124335D01*
X255475Y-123250D01*
X255059Y-122010D01*
X254017Y-121080D01*
X252142Y-120150D01*
G01X260267Y-110850D02*
X260058Y-111160D01*
X259642D01*
X259433Y-110850D01*
X259642Y-110540D01*
X260058D01*
X260267Y-110850D01*
G01X259850Y-98760D02*
X257142Y-98450D01*
X254850Y-97985D01*
X252767Y-97365D01*
X250475Y-96590D01*
X247350Y-95350D01*
Y-101550D01*
G01X254642Y-88995D02*
X253183Y-87910D01*
X252350Y-86980D01*
X251933Y-85740D01*
X252350Y-84655D01*
X253183Y-83880D01*
X254433Y-83260D01*
X255892Y-83105D01*
X257142Y-83260D01*
X258392Y-83880D01*
X259433Y-84810D01*
X259850Y-85895D01*
X259433Y-87135D01*
X258184Y-88220D01*
X256308Y-88840D01*
X254225Y-88995D01*
X251517Y-88685D01*
X250058Y-88220D01*
X248600Y-87445D01*
X247558Y-86360D01*
X247350Y-85275D01*
X247767Y-84190D01*
X248808Y-83415D01*
G01X236007Y33233D02*
Y40733D01*
X238247D01*
X238994Y40358D01*
X239554Y39483D01*
X239741Y38483D01*
X239554Y37483D01*
X239087Y36733D01*
X238247Y36358D01*
X236007D01*
G01X245374Y40733D02*
Y33233D01*
G01X243227Y40733D02*
X247521D01*
G01X250914Y33233D02*
Y40733D01*
G01X254834D02*
Y33233D01*
G01Y36983D02*
X250914D01*
G01X240497Y759140D02*
X241539Y760070D01*
X242164Y761155D01*
X242372Y762550D01*
X241955Y763945D01*
X241122Y765030D01*
X239664Y765805D01*
X237997Y765960D01*
X236330Y765650D01*
X235289Y764875D01*
X234455Y763790D01*
X234247Y762705D01*
X234455Y761620D01*
X235289Y760225D01*
X229872Y760690D01*
Y764875D01*
G01X237164Y772005D02*
X235705Y773090D01*
X234872Y774020D01*
X234455Y775260D01*
X234872Y776345D01*
X235705Y777120D01*
X236955Y777740D01*
X238414Y777895D01*
X239664Y777740D01*
X240914Y777120D01*
X241955Y776190D01*
X242372Y775105D01*
X241955Y773865D01*
X240706Y772780D01*
X238830Y772160D01*
X236747Y772005D01*
X234039Y772315D01*
X232580Y772780D01*
X231122Y773555D01*
X230080Y774640D01*
X229872Y775725D01*
X230289Y776810D01*
X231330Y777585D01*
G01X242789Y787350D02*
X242580Y787040D01*
X242164D01*
X241955Y787350D01*
X242164Y787660D01*
X242580D01*
X242789Y787350D01*
G01X242372Y799750D02*
X242164Y800835D01*
X241539Y802075D01*
X240497Y802850D01*
X239039Y803160D01*
X237581Y802850D01*
X236330Y801920D01*
X235705Y800525D01*
Y798975D01*
X235289Y798045D01*
X234247Y797270D01*
X232789Y796960D01*
X231330Y797425D01*
X230289Y798510D01*
X229872Y799750D01*
X230289Y800990D01*
X231330Y802075D01*
X232789Y802540D01*
X234247Y802230D01*
X235289Y801455D01*
X235705Y800525D01*
Y798975D01*
X236330Y797580D01*
X237581Y796650D01*
X239039Y796340D01*
X240497Y796650D01*
X241539Y797425D01*
X242164Y798665D01*
X242372Y799750D01*
G01X262100Y-1054500D02*
X265900D01*
X262100Y-1062500D01*
X265900D01*
G01X272000Y-1057167D02*
Y-1062500D01*
G01Y-1055033D02*
X271800Y-1054900D01*
Y-1054633D01*
X272000Y-1054500D01*
X272200Y-1054633D01*
Y-1054900D01*
X272000Y-1055033D01*
G01X278700Y-1059833D02*
X281300D01*
G01X286200Y-1065167D02*
Y-1057167D01*
G01Y-1058367D02*
X286700Y-1057700D01*
X287200Y-1057300D01*
X288000Y-1057167D01*
X288700Y-1057300D01*
X289400Y-1057967D01*
X289700Y-1058900D01*
X289800Y-1059833D01*
X289700Y-1060767D01*
X289400Y-1061700D01*
X288800Y-1062233D01*
X288000Y-1062500D01*
X287300Y-1062367D01*
X286600Y-1061967D01*
X286200Y-1061434D01*
G01X296000Y-1057167D02*
Y-1062500D01*
G01Y-1055033D02*
X295800Y-1054900D01*
Y-1054633D01*
X296000Y-1054500D01*
X296200Y-1054633D01*
Y-1054900D01*
X296000Y-1055033D01*
G01X302300Y-1062500D02*
Y-1057167D01*
G01Y-1058500D02*
X302700Y-1057833D01*
X303300Y-1057300D01*
X304100Y-1057167D01*
X304800Y-1057300D01*
X305400Y-1057833D01*
X305700Y-1058767D01*
Y-1062500D01*
G01X310600Y-1064500D02*
X311300Y-1065033D01*
X312100Y-1065167D01*
X312800Y-1065033D01*
X313400Y-1064367D01*
X313800Y-1063433D01*
Y-1057167D01*
G01Y-1058233D02*
X313400Y-1057700D01*
X312800Y-1057300D01*
X312100Y-1057167D01*
X311300Y-1057433D01*
X310800Y-1057967D01*
X310400Y-1058900D01*
X310200Y-1059833D01*
X310300Y-1060633D01*
X310700Y-1061567D01*
X311300Y-1062233D01*
X312100Y-1062500D01*
X312700Y-1062367D01*
X313400Y-1061833D01*
X313800Y-1061300D01*
G01X267100Y-1037500D02*
Y-1029500D01*
X270900D01*
G01X269500Y-1033367D02*
X267100D01*
G01X274500Y-1037500D02*
X277000Y-1029500D01*
X279500Y-1037500D01*
G01X278600Y-1034700D02*
X275400D01*
G01X285800Y-1033233D02*
X286200Y-1032833D01*
X286500Y-1032167D01*
X286700Y-1031233D01*
X286500Y-1030433D01*
X286100Y-1029900D01*
X285400Y-1029500D01*
X282700D01*
Y-1037500D01*
X286000D01*
X286700Y-1036967D01*
X287100Y-1036167D01*
X287300Y-1035233D01*
X287100Y-1034300D01*
X286500Y-1033500D01*
X285800Y-1033233D01*
X282700D01*
G01X272350Y737390D02*
X273809Y738320D01*
X274642Y739560D01*
X274850Y740955D01*
X274642Y742195D01*
X273600Y743435D01*
X272350Y744210D01*
X271100Y744365D01*
X269642Y744055D01*
X268600Y742970D01*
X268183Y741885D01*
Y740490D01*
G01Y741885D02*
X267558Y742815D01*
X266517Y743590D01*
X265267Y743900D01*
X264017Y743590D01*
X262975Y742815D01*
X262350Y741420D01*
X262558Y740025D01*
X263392Y738630D01*
G01X262350Y753200D02*
X262767Y751960D01*
X263808Y751030D01*
X265058Y750410D01*
X266725Y749945D01*
X268600Y749790D01*
X270475Y749945D01*
X272142Y750410D01*
X273392Y751030D01*
X274433Y751960D01*
X274850Y753200D01*
X274433Y754440D01*
X273392Y755370D01*
X272142Y755990D01*
X270475Y756455D01*
X268600Y756610D01*
X266725Y756455D01*
X265058Y755990D01*
X263808Y755370D01*
X262767Y754440D01*
X262350Y753200D01*
G01X272350Y762190D02*
X273809Y763120D01*
X274642Y764360D01*
X274850Y765755D01*
X274642Y766995D01*
X273600Y768235D01*
X272350Y769010D01*
X271100Y769165D01*
X269642Y768855D01*
X268600Y767770D01*
X268183Y766685D01*
Y765290D01*
G01Y766685D02*
X267558Y767615D01*
X266517Y768390D01*
X265267Y768700D01*
X264017Y768390D01*
X262975Y767615D01*
X262350Y766220D01*
X262558Y764825D01*
X263392Y763430D01*
G01X274850Y778000D02*
X262350D01*
X264850Y776140D01*
G01X274850D02*
Y779860D01*
G01X275267Y790400D02*
X275058Y790090D01*
X274642D01*
X274433Y790400D01*
X274642Y790710D01*
X275058D01*
X275267Y790400D01*
G01X272975Y799390D02*
X274017Y800320D01*
X274642Y801405D01*
X274850Y802800D01*
X274433Y804195D01*
X273600Y805280D01*
X272142Y806055D01*
X270475Y806210D01*
X268808Y805900D01*
X267767Y805125D01*
X266933Y804040D01*
X266725Y802955D01*
X266933Y801870D01*
X267767Y800475D01*
X262350Y800940D01*
Y805125D01*
G01Y815200D02*
X262767Y813960D01*
X263808Y813030D01*
X265058Y812410D01*
X266725Y811945D01*
X268600Y811790D01*
X270475Y811945D01*
X272142Y812410D01*
X273392Y813030D01*
X274433Y813960D01*
X274850Y815200D01*
X274433Y816440D01*
X273392Y817370D01*
X272142Y817990D01*
X270475Y818455D01*
X268600Y818610D01*
X266725Y818455D01*
X265058Y817990D01*
X263808Y817370D01*
X262767Y816440D01*
X262350Y815200D01*
G01X289433Y-149145D02*
X288184Y-148215D01*
X287558Y-147130D01*
X287350Y-145890D01*
X287767Y-144340D01*
X288808Y-143255D01*
X290058Y-142945D01*
X291309Y-143100D01*
X292350Y-143720D01*
X294433Y-146820D01*
X295892Y-148215D01*
X297975Y-149145D01*
X299850Y-149455D01*
Y-142945D01*
G01Y-134110D02*
X297142Y-133800D01*
X294850Y-133335D01*
X292767Y-132715D01*
X290475Y-131940D01*
X287350Y-130700D01*
Y-136900D01*
G01X298392Y-124035D02*
X299433Y-122950D01*
X299850Y-121710D01*
X299433Y-120470D01*
X298184Y-119385D01*
X296308Y-118610D01*
X294433Y-118300D01*
X292142D01*
X290267Y-118610D01*
X288600Y-119385D01*
X287767Y-120315D01*
X287350Y-121400D01*
X287767Y-122640D01*
X288600Y-123570D01*
X289850Y-124190D01*
X291517Y-124500D01*
X292975Y-124190D01*
X294433Y-123415D01*
X295267Y-122485D01*
X295475Y-121400D01*
X295059Y-120160D01*
X294017Y-119230D01*
X292142Y-118300D01*
G01X297975Y-112410D02*
X299017Y-111480D01*
X299642Y-110395D01*
X299850Y-109000D01*
X299433Y-107605D01*
X298600Y-106520D01*
X297142Y-105745D01*
X295475Y-105590D01*
X293808Y-105900D01*
X292767Y-106675D01*
X291933Y-107760D01*
X291725Y-108845D01*
X291933Y-109930D01*
X292767Y-111325D01*
X287350Y-110860D01*
Y-106675D01*
G01X300267Y-96600D02*
X300058Y-96910D01*
X299642D01*
X299433Y-96600D01*
X299642Y-96290D01*
X300058D01*
X300267Y-96600D01*
G01X289433Y-87145D02*
X288184Y-86215D01*
X287558Y-85130D01*
X287350Y-83890D01*
X287767Y-82340D01*
X288808Y-81255D01*
X290058Y-80945D01*
X291309Y-81100D01*
X292350Y-81720D01*
X294433Y-84820D01*
X295892Y-86215D01*
X297975Y-87145D01*
X299850Y-87455D01*
Y-80945D01*
G01Y-71800D02*
X299642Y-70715D01*
X299017Y-69475D01*
X297975Y-68700D01*
X296517Y-68390D01*
X295059Y-68700D01*
X293808Y-69630D01*
X293183Y-71025D01*
Y-72575D01*
X292767Y-73505D01*
X291725Y-74280D01*
X290267Y-74590D01*
X288808Y-74125D01*
X287767Y-73040D01*
X287350Y-71800D01*
X287767Y-70560D01*
X288808Y-69475D01*
X290267Y-69010D01*
X291725Y-69320D01*
X292767Y-70095D01*
X293183Y-71025D01*
Y-72575D01*
X293808Y-73970D01*
X295059Y-74900D01*
X296517Y-75210D01*
X297975Y-74900D01*
X299017Y-74125D01*
X299642Y-72885D01*
X299850Y-71800D01*
G01X324850Y-115360D02*
X322142Y-115050D01*
X319850Y-114585D01*
X317767Y-113965D01*
X315475Y-113190D01*
X312350Y-111950D01*
Y-118150D01*
G01X324850Y-102650D02*
X312350D01*
X314850Y-104510D01*
G01X324850D02*
Y-100790D01*
G01X307036Y522906D02*
Y530406D01*
X309276D01*
X310023Y530031D01*
X310583Y529156D01*
X310770Y528156D01*
X310583Y527156D01*
X310116Y526406D01*
X309276Y526031D01*
X307036D01*
G01X316403Y530406D02*
Y522906D01*
G01X314256Y530406D02*
X318550D01*
G01X321943Y522906D02*
Y530406D01*
G01X325863D02*
Y522906D01*
G01Y526656D02*
X321943D01*
G01X299850Y771640D02*
X297142Y771950D01*
X294850Y772415D01*
X292767Y773035D01*
X290475Y773810D01*
X287350Y775050D01*
Y768850D01*
G01X299850Y784040D02*
X297142Y784350D01*
X294850Y784815D01*
X292767Y785435D01*
X290475Y786210D01*
X287350Y787450D01*
Y781250D01*
G01X330466Y663630D02*
Y671130D01*
X332800D01*
X333546Y670755D01*
X334013Y670255D01*
X334200Y669255D01*
X334013Y668255D01*
X333453Y667630D01*
X332800Y667255D01*
X330466D01*
G01X332800D02*
X334200Y663630D01*
G01X341700D02*
X337966D01*
Y671130D01*
X341700D01*
G01X340206Y667505D02*
X337966D01*
G01X349386Y670505D02*
X348826Y670880D01*
X348173Y671130D01*
X347426D01*
X346586Y670755D01*
X345933Y670130D01*
X345466Y669380D01*
X345093Y668130D01*
X345000Y667005D01*
X345186Y665880D01*
X345466Y665130D01*
X346026Y664380D01*
X346680Y663880D01*
X347333Y663630D01*
X347986D01*
X348640Y663880D01*
X349200Y664255D01*
X349666Y664755D01*
G01X354833Y663630D02*
X354086Y663755D01*
X353433Y664255D01*
X352873Y665005D01*
X352500Y665880D01*
X352313Y666880D01*
Y667880D01*
X352500Y668880D01*
X352873Y669755D01*
X353433Y670505D01*
X354086Y671005D01*
X354833Y671130D01*
X355580Y671005D01*
X356233Y670505D01*
X356793Y669755D01*
X357166Y668880D01*
X357353Y667880D01*
Y666880D01*
X357166Y665880D01*
X356793Y665005D01*
X356233Y664255D01*
X355580Y663755D01*
X354833Y663630D01*
G01X359906D02*
Y671130D01*
X362333Y664880D01*
X364760Y671130D01*
Y663630D01*
G01X367406D02*
Y671130D01*
X369833Y664880D01*
X372260Y671130D01*
Y663630D01*
G01X379200D02*
X375466D01*
Y671130D01*
X379200D01*
G01X377706Y667505D02*
X375466D01*
G01X382686Y663630D02*
Y671130D01*
X386980Y663630D01*
Y671130D01*
G01X390280Y663630D02*
Y671130D01*
X392146D01*
X392893Y670755D01*
X393453Y670255D01*
X393920Y669505D01*
X394293Y668630D01*
X394386Y667380D01*
X394293Y666130D01*
X393920Y665255D01*
X393453Y664505D01*
X392893Y664005D01*
X392146Y663630D01*
X390280D01*
G01X401700D02*
X397966D01*
Y671130D01*
X401700D01*
G01X400206Y667505D02*
X397966D01*
G01X405280Y663630D02*
Y671130D01*
X407146D01*
X407893Y670755D01*
X408453Y670255D01*
X408920Y669505D01*
X409293Y668630D01*
X409386Y667380D01*
X409293Y666130D01*
X408920Y665255D01*
X408453Y664505D01*
X407893Y664005D01*
X407146Y663630D01*
X405280D01*
G01X420280D02*
Y671130D01*
X422146D01*
X422893Y670755D01*
X423453Y670255D01*
X423920Y669505D01*
X424293Y668630D01*
X424386Y667380D01*
X424293Y666130D01*
X423920Y665255D01*
X423453Y664505D01*
X422893Y664005D01*
X422146Y663630D01*
X420280D01*
G01X427966D02*
Y671130D01*
X430300D01*
X431046Y670755D01*
X431513Y670255D01*
X431700Y669255D01*
X431513Y668255D01*
X430953Y667630D01*
X430300Y667255D01*
X427966D01*
G01X430300D02*
X431700Y663630D01*
G01X436213Y671130D02*
X438453D01*
G01X437333D02*
Y663630D01*
G01X436213D02*
X438453D01*
G01X442966Y671130D02*
Y663630D01*
X446700D01*
G01X450466Y671130D02*
Y663630D01*
X454200D01*
G01X465373Y664630D02*
X466120Y664005D01*
X466960Y663630D01*
X467706D01*
X468453Y664005D01*
X469013Y664630D01*
X469293Y665505D01*
X469106Y666380D01*
X468640Y667130D01*
X467800Y667630D01*
X466680Y667880D01*
X466026Y668380D01*
X465746Y669255D01*
X465933Y670130D01*
X466400Y670755D01*
X467053Y671130D01*
X467706D01*
X468360Y670880D01*
X468920Y670255D01*
G01X473713Y671130D02*
X475953D01*
G01X474833D02*
Y663630D01*
G01X473713D02*
X475953D01*
G01X480560Y671130D02*
X484106D01*
X480560Y663630D01*
X484106D01*
G01X491700D02*
X487966D01*
Y671130D01*
X491700D01*
G01X490206Y667505D02*
X487966D01*
G01X503060Y663630D02*
Y671130D01*
X506606D01*
G01X505300Y667505D02*
X503060D01*
G01X512333Y663630D02*
X511586Y663755D01*
X510933Y664255D01*
X510373Y665005D01*
X510000Y665880D01*
X509813Y666880D01*
Y667880D01*
X510000Y668880D01*
X510373Y669755D01*
X510933Y670505D01*
X511586Y671005D01*
X512333Y671130D01*
X513080Y671005D01*
X513733Y670505D01*
X514293Y669755D01*
X514666Y668880D01*
X514853Y667880D01*
Y666880D01*
X514666Y665880D01*
X514293Y665005D01*
X513733Y664255D01*
X513080Y663755D01*
X512333Y663630D01*
G01X517966D02*
Y671130D01*
X520300D01*
X521046Y670755D01*
X521513Y670255D01*
X521700Y669255D01*
X521513Y668255D01*
X520953Y667630D01*
X520300Y667255D01*
X517966D01*
G01X520300D02*
X521700Y663630D01*
G01X534833Y671130D02*
X534086Y670880D01*
X533526Y670255D01*
X533153Y669505D01*
X532873Y668505D01*
X532780Y667380D01*
X532873Y666255D01*
X533153Y665255D01*
X533526Y664505D01*
X534086Y663880D01*
X534833Y663630D01*
X535580Y663880D01*
X536140Y664505D01*
X536513Y665255D01*
X536793Y666255D01*
X536886Y667380D01*
X536793Y668505D01*
X536513Y669505D01*
X536140Y670255D01*
X535580Y670880D01*
X534833Y671130D01*
G01X542333Y663380D02*
X542146Y663505D01*
Y663755D01*
X542333Y663880D01*
X542520Y663755D01*
Y663505D01*
X542333Y663380D01*
G01X549646Y663630D02*
X549833Y665255D01*
X550113Y666630D01*
X550486Y667880D01*
X550953Y669255D01*
X551700Y671130D01*
X547966D01*
G01X555280Y664755D02*
X555840Y664130D01*
X556493Y663755D01*
X557333Y663630D01*
X558173Y663880D01*
X558826Y664380D01*
X559293Y665255D01*
X559386Y666255D01*
X559200Y667255D01*
X558733Y667880D01*
X558080Y668380D01*
X557426Y668505D01*
X556773Y668380D01*
X555933Y667880D01*
X556213Y671130D01*
X558733D01*
G01X562406Y663630D02*
Y671130D01*
X564833Y664880D01*
X567260Y671130D01*
Y663630D01*
G01X569906D02*
Y671130D01*
X572333Y664880D01*
X574760Y671130D01*
Y663630D01*
G01X585560D02*
Y671130D01*
X589106D01*
G01X587800Y667505D02*
X585560D01*
G01X593713Y671130D02*
X595953D01*
G01X594833D02*
Y663630D01*
G01X593713D02*
X595953D01*
G01X600186D02*
Y671130D01*
X604480Y663630D01*
Y671130D01*
G01X608713D02*
X610953D01*
G01X609833D02*
Y663630D01*
G01X608713D02*
X610953D01*
G01X615373Y664630D02*
X616120Y664005D01*
X616960Y663630D01*
X617706D01*
X618453Y664005D01*
X619013Y664630D01*
X619293Y665505D01*
X619106Y666380D01*
X618640Y667130D01*
X617800Y667630D01*
X616680Y667880D01*
X616026Y668380D01*
X615746Y669255D01*
X615933Y670130D01*
X616400Y670755D01*
X617053Y671130D01*
X617706D01*
X618360Y670880D01*
X618920Y670255D01*
G01X622873Y663630D02*
Y671130D01*
G01X626793D02*
Y663630D01*
G01Y667380D02*
X622873D01*
G01X634200Y663630D02*
X630466D01*
Y671130D01*
X634200D01*
G01X632706Y667505D02*
X630466D01*
G01X637780Y663630D02*
Y671130D01*
X639646D01*
X640393Y670755D01*
X640953Y670255D01*
X641420Y669505D01*
X641793Y668630D01*
X641886Y667380D01*
X641793Y666130D01*
X641420Y665255D01*
X640953Y664505D01*
X640393Y664005D01*
X639646Y663630D01*
X637780D01*
G01X652966D02*
Y671130D01*
X655206D01*
X655953Y670755D01*
X656513Y669880D01*
X656700Y668880D01*
X656513Y667880D01*
X656046Y667130D01*
X655206Y666755D01*
X652966D01*
G01X662333Y671130D02*
Y663630D01*
G01X660186Y671130D02*
X664480D01*
G01X667873Y663630D02*
Y671130D01*
G01X671793D02*
Y663630D01*
G01Y667380D02*
X667873D01*
G01X683713Y671130D02*
X685953D01*
G01X684833D02*
Y663630D01*
G01X683713D02*
X685953D01*
G01X690373Y664630D02*
X691120Y664005D01*
X691960Y663630D01*
X692706D01*
X693453Y664005D01*
X694013Y664630D01*
X694293Y665505D01*
X694106Y666380D01*
X693640Y667130D01*
X692800Y667630D01*
X691680Y667880D01*
X691026Y668380D01*
X690746Y669255D01*
X690933Y670130D01*
X691400Y670755D01*
X692053Y671130D01*
X692706D01*
X693360Y670880D01*
X693920Y670255D01*
G01X707333Y671130D02*
X706586Y670880D01*
X706026Y670255D01*
X705653Y669505D01*
X705373Y668505D01*
X705280Y667380D01*
X705373Y666255D01*
X705653Y665255D01*
X706026Y664505D01*
X706586Y663880D01*
X707333Y663630D01*
X708080Y663880D01*
X708640Y664505D01*
X709013Y665255D01*
X709293Y666255D01*
X709386Y667380D01*
X709293Y668505D01*
X709013Y669505D01*
X708640Y670255D01*
X708080Y670880D01*
X707333Y671130D01*
G01X714833Y663380D02*
X714646Y663505D01*
Y663755D01*
X714833Y663880D01*
X715020Y663755D01*
Y663505D01*
X714833Y663380D01*
G01X722333Y663630D02*
X722986Y663755D01*
X723733Y664130D01*
X724200Y664755D01*
X724386Y665630D01*
X724200Y666505D01*
X723640Y667255D01*
X722800Y667630D01*
X721866D01*
X721306Y667880D01*
X720840Y668505D01*
X720653Y669380D01*
X720933Y670255D01*
X721586Y670880D01*
X722333Y671130D01*
X723080Y670880D01*
X723733Y670255D01*
X724013Y669380D01*
X723826Y668505D01*
X723360Y667880D01*
X722800Y667630D01*
X721866D01*
X721026Y667255D01*
X720466Y666505D01*
X720280Y665630D01*
X720466Y664755D01*
X720933Y664130D01*
X721680Y663755D01*
X722333Y663630D01*
G01X729833D02*
Y671130D01*
X728713Y669630D01*
G01Y663630D02*
X730953D01*
G01X736120Y666130D02*
X738546D01*
G01X744833Y671130D02*
X744086Y670880D01*
X743526Y670255D01*
X743153Y669505D01*
X742873Y668505D01*
X742780Y667380D01*
X742873Y666255D01*
X743153Y665255D01*
X743526Y664505D01*
X744086Y663880D01*
X744833Y663630D01*
X745580Y663880D01*
X746140Y664505D01*
X746513Y665255D01*
X746793Y666255D01*
X746886Y667380D01*
X746793Y668505D01*
X746513Y669505D01*
X746140Y670255D01*
X745580Y670880D01*
X744833Y671130D01*
G01X752333Y663380D02*
X752146Y663505D01*
Y663755D01*
X752333Y663880D01*
X752520Y663755D01*
Y663505D01*
X752333Y663380D01*
G01X759833Y663630D02*
X760486Y663755D01*
X761233Y664130D01*
X761700Y664755D01*
X761886Y665630D01*
X761700Y666505D01*
X761140Y667255D01*
X760300Y667630D01*
X759366D01*
X758806Y667880D01*
X758340Y668505D01*
X758153Y669380D01*
X758433Y670255D01*
X759086Y670880D01*
X759833Y671130D01*
X760580Y670880D01*
X761233Y670255D01*
X761513Y669380D01*
X761326Y668505D01*
X760860Y667880D01*
X760300Y667630D01*
X759366D01*
X758526Y667255D01*
X757966Y666505D01*
X757780Y665630D01*
X757966Y664755D01*
X758433Y664130D01*
X759180Y663755D01*
X759833Y663630D01*
G01X765560Y666755D02*
X766213Y667630D01*
X766773Y668130D01*
X767520Y668380D01*
X768173Y668130D01*
X768640Y667630D01*
X769013Y666880D01*
X769106Y666005D01*
X769013Y665255D01*
X768640Y664505D01*
X768080Y663880D01*
X767426Y663630D01*
X766680Y663880D01*
X766026Y664630D01*
X765653Y665755D01*
X765560Y667005D01*
X765746Y668630D01*
X766026Y669505D01*
X766493Y670380D01*
X767146Y671005D01*
X767800Y671130D01*
X768453Y670880D01*
X768920Y670255D01*
G01X774366Y661130D02*
X773433Y662380D01*
X772966Y663630D01*
Y668630D01*
X773433Y669880D01*
X774366Y671130D01*
G01X782333D02*
X781586Y670880D01*
X781026Y670255D01*
X780653Y669505D01*
X780373Y668505D01*
X780280Y667380D01*
X780373Y666255D01*
X780653Y665255D01*
X781026Y664505D01*
X781586Y663880D01*
X782333Y663630D01*
X783080Y663880D01*
X783640Y664505D01*
X784013Y665255D01*
X784293Y666255D01*
X784386Y667380D01*
X784293Y668505D01*
X784013Y669505D01*
X783640Y670255D01*
X783080Y670880D01*
X782333Y671130D01*
G01X789833Y663380D02*
X789646Y663505D01*
Y663755D01*
X789833Y663880D01*
X790020Y663755D01*
Y663505D01*
X789833Y663380D01*
G01X797333Y663630D02*
X797986Y663755D01*
X798733Y664130D01*
X799200Y664755D01*
X799386Y665630D01*
X799200Y666505D01*
X798640Y667255D01*
X797800Y667630D01*
X796866D01*
X796306Y667880D01*
X795840Y668505D01*
X795653Y669380D01*
X795933Y670255D01*
X796586Y670880D01*
X797333Y671130D01*
X798080Y670880D01*
X798733Y670255D01*
X799013Y669380D01*
X798826Y668505D01*
X798360Y667880D01*
X797800Y667630D01*
X796866D01*
X796026Y667255D01*
X795466Y666505D01*
X795280Y665630D01*
X795466Y664755D01*
X795933Y664130D01*
X796680Y663755D01*
X797333Y663630D01*
G01X802780Y664755D02*
X803340Y664130D01*
X803993Y663755D01*
X804833Y663630D01*
X805673Y663880D01*
X806326Y664380D01*
X806793Y665255D01*
X806886Y666255D01*
X806700Y667255D01*
X806233Y667880D01*
X805580Y668380D01*
X804926Y668505D01*
X804273Y668380D01*
X803433Y667880D01*
X803713Y671130D01*
X806233D01*
G01X809906Y663630D02*
Y671130D01*
X812333Y664880D01*
X814760Y671130D01*
Y663630D01*
G01X817406D02*
Y671130D01*
X819833Y664880D01*
X822260Y671130D01*
Y663630D01*
G01X832780D02*
Y671130D01*
X834646D01*
X835393Y670755D01*
X835953Y670255D01*
X836420Y669505D01*
X836793Y668630D01*
X836886Y667380D01*
X836793Y666130D01*
X836420Y665255D01*
X835953Y664505D01*
X835393Y664005D01*
X834646Y663630D01*
X832780D01*
G01X840466D02*
Y671130D01*
X842800D01*
X843546Y670755D01*
X844013Y670255D01*
X844200Y669255D01*
X844013Y668255D01*
X843453Y667630D01*
X842800Y667255D01*
X840466D01*
G01X842800D02*
X844200Y663630D01*
G01X848713Y671130D02*
X850953D01*
G01X849833D02*
Y663630D01*
G01X848713D02*
X850953D01*
G01X855466Y671130D02*
Y663630D01*
X859200D01*
G01X862966Y671130D02*
Y663630D01*
X866700D01*
G01X872800Y661130D02*
X873733Y662380D01*
X874200Y663630D01*
Y668630D01*
X873733Y669880D01*
X872800Y671130D01*
G01X879833Y663380D02*
X879646Y663505D01*
Y663755D01*
X879833Y663880D01*
X880020Y663755D01*
Y663505D01*
X879833Y663380D01*
G01X338350Y743390D02*
X339809Y744320D01*
X340642Y745560D01*
X340850Y746955D01*
X340642Y748195D01*
X339600Y749435D01*
X338350Y750210D01*
X337100Y750365D01*
X335642Y750055D01*
X334600Y748970D01*
X334183Y747885D01*
Y746490D01*
G01Y747885D02*
X333558Y748815D01*
X332517Y749590D01*
X331267Y749900D01*
X330017Y749590D01*
X328975Y748815D01*
X328350Y747420D01*
X328558Y746025D01*
X329392Y744630D01*
G01X340850Y759200D02*
X328350D01*
X330850Y757340D01*
G01X340850D02*
Y761060D01*
G01Y773460D02*
X328350D01*
X337308Y767725D01*
Y775475D01*
G01X339392Y781365D02*
X340433Y782450D01*
X340850Y783690D01*
X340433Y784930D01*
X339184Y786015D01*
X337308Y786790D01*
X335433Y787100D01*
X333142D01*
X331267Y786790D01*
X329600Y786015D01*
X328767Y785085D01*
X328350Y784000D01*
X328767Y782760D01*
X329600Y781830D01*
X330850Y781210D01*
X332517Y780900D01*
X333975Y781210D01*
X335433Y781985D01*
X336267Y782915D01*
X336475Y784000D01*
X336059Y785240D01*
X335017Y786170D01*
X333142Y787100D01*
G01X341267Y796400D02*
X341058Y796090D01*
X340642D01*
X340433Y796400D01*
X340642Y796710D01*
X341058D01*
X341267Y796400D01*
G01X335642Y805855D02*
X334183Y806940D01*
X333350Y807870D01*
X332933Y809110D01*
X333350Y810195D01*
X334183Y810970D01*
X335433Y811590D01*
X336892Y811745D01*
X338142Y811590D01*
X339392Y810970D01*
X340433Y810040D01*
X340850Y808955D01*
X340433Y807715D01*
X339184Y806630D01*
X337308Y806010D01*
X335225Y805855D01*
X332517Y806165D01*
X331058Y806630D01*
X329600Y807405D01*
X328558Y808490D01*
X328350Y809575D01*
X328767Y810660D01*
X329808Y811435D01*
G01X340850Y821200D02*
X328350D01*
X330850Y819340D01*
G01X340850D02*
Y823060D01*
G01X369600Y-1055833D02*
X370200Y-1055033D01*
X370900Y-1054633D01*
X371700Y-1054500D01*
X372700Y-1054767D01*
X373400Y-1055433D01*
X373600Y-1056233D01*
X373500Y-1057034D01*
X373100Y-1057700D01*
X371100Y-1059033D01*
X370200Y-1059967D01*
X369600Y-1061300D01*
X369400Y-1062500D01*
X373600D01*
G01X379500Y-1054500D02*
X378700Y-1054767D01*
X378100Y-1055433D01*
X377700Y-1056233D01*
X377400Y-1057300D01*
X377300Y-1058500D01*
X377400Y-1059700D01*
X377700Y-1060767D01*
X378100Y-1061567D01*
X378700Y-1062233D01*
X379500Y-1062500D01*
X380300Y-1062233D01*
X380900Y-1061567D01*
X381300Y-1060767D01*
X381600Y-1059700D01*
X381700Y-1058500D01*
X381600Y-1057300D01*
X381300Y-1056233D01*
X380900Y-1055433D01*
X380300Y-1054767D01*
X379500Y-1054500D01*
G01X385600Y-1055833D02*
X386200Y-1055033D01*
X386900Y-1054633D01*
X387700Y-1054500D01*
X388700Y-1054767D01*
X389400Y-1055433D01*
X389600Y-1056233D01*
X389500Y-1057034D01*
X389100Y-1057700D01*
X387100Y-1059033D01*
X386200Y-1059967D01*
X385600Y-1061300D01*
X385400Y-1062500D01*
X389600D01*
G01X393600Y-1055833D02*
X394200Y-1055033D01*
X394900Y-1054633D01*
X395700Y-1054500D01*
X396700Y-1054767D01*
X397400Y-1055433D01*
X397600Y-1056233D01*
X397500Y-1057034D01*
X397100Y-1057700D01*
X395100Y-1059033D01*
X394200Y-1059967D01*
X393600Y-1061300D01*
X393400Y-1062500D01*
X397600D01*
G01X401700Y-1062767D02*
X405300Y-1054500D01*
G01X411500Y-1062500D02*
Y-1054500D01*
X410300Y-1056100D01*
G01Y-1062500D02*
X412700D01*
G01X417600Y-1055833D02*
X418200Y-1055033D01*
X418900Y-1054633D01*
X419700Y-1054500D01*
X420700Y-1054767D01*
X421400Y-1055433D01*
X421600Y-1056233D01*
X421500Y-1057034D01*
X421100Y-1057700D01*
X419100Y-1059033D01*
X418200Y-1059967D01*
X417600Y-1061300D01*
X417400Y-1062500D01*
X421600D01*
G01X425700Y-1062767D02*
X429300Y-1054500D01*
G01X435500Y-1062500D02*
Y-1054500D01*
X434300Y-1056100D01*
G01Y-1062500D02*
X436700D01*
G01X441300Y-1060900D02*
X441900Y-1061833D01*
X442700Y-1062367D01*
X443600Y-1062500D01*
X444400Y-1062367D01*
X445200Y-1061700D01*
X445700Y-1060900D01*
X445800Y-1060100D01*
X445600Y-1059167D01*
X444900Y-1058500D01*
X444200Y-1058233D01*
X443300D01*
G01X444200D02*
X444800Y-1057833D01*
X445300Y-1057167D01*
X445500Y-1056367D01*
X445300Y-1055567D01*
X444800Y-1054900D01*
X443900Y-1054500D01*
X443000Y-1054633D01*
X442100Y-1055167D01*
G01X369300Y-1040000D02*
Y-1032000D01*
X371300D01*
X372100Y-1032400D01*
X372700Y-1032933D01*
X373200Y-1033733D01*
X373600Y-1034667D01*
X373700Y-1036000D01*
X373600Y-1037333D01*
X373200Y-1038267D01*
X372700Y-1039067D01*
X372100Y-1039600D01*
X371300Y-1040000D01*
X369300D01*
G01X377000D02*
X379500Y-1032000D01*
X382000Y-1040000D01*
G01X381100Y-1037200D02*
X377900D01*
G01X385600Y-1040000D02*
Y-1032000D01*
X389400D01*
G01X388000Y-1035867D02*
X385600D01*
G01X395500Y-1032000D02*
X394700Y-1032267D01*
X394100Y-1032933D01*
X393700Y-1033733D01*
X393400Y-1034800D01*
X393300Y-1036000D01*
X393400Y-1037200D01*
X393700Y-1038267D01*
X394100Y-1039067D01*
X394700Y-1039733D01*
X395500Y-1040000D01*
X396300Y-1039733D01*
X396900Y-1039067D01*
X397300Y-1038267D01*
X397600Y-1037200D01*
X397700Y-1036000D01*
X397600Y-1034800D01*
X397300Y-1033733D01*
X396900Y-1032933D01*
X396300Y-1032267D01*
X395500Y-1032000D01*
G01X403500D02*
Y-1040000D01*
G01X401200Y-1032000D02*
X405800D01*
G01X409500Y-1040000D02*
Y-1032000D01*
X411900D01*
X412700Y-1032400D01*
X413300Y-1033333D01*
X413500Y-1034400D01*
X413300Y-1035467D01*
X412800Y-1036267D01*
X411900Y-1036667D01*
X409500D01*
G01X420300Y-1035733D02*
X420700Y-1035333D01*
X421000Y-1034667D01*
X421200Y-1033733D01*
X421000Y-1032933D01*
X420600Y-1032400D01*
X419900Y-1032000D01*
X417200D01*
Y-1040000D01*
X420500D01*
X421200Y-1039467D01*
X421600Y-1038667D01*
X421800Y-1037733D01*
X421600Y-1036800D01*
X421000Y-1036000D01*
X420300Y-1035733D01*
X417200D01*
G01X427500Y-1040000D02*
Y-1032000D01*
X426300Y-1033600D01*
G01Y-1040000D02*
X428700D01*
G01X433000D02*
X435500Y-1032000D01*
X438000Y-1040000D01*
G01X437100Y-1037200D02*
X433900D01*
G01X441600Y-1040000D02*
Y-1032000D01*
X445400D01*
G01X444000Y-1035867D02*
X441600D01*
G01X451500Y-1032000D02*
X450700Y-1032267D01*
X450100Y-1032933D01*
X449700Y-1033733D01*
X449400Y-1034800D01*
X449300Y-1036000D01*
X449400Y-1037200D01*
X449700Y-1038267D01*
X450100Y-1039067D01*
X450700Y-1039733D01*
X451500Y-1040000D01*
X452300Y-1039733D01*
X452900Y-1039067D01*
X453300Y-1038267D01*
X453600Y-1037200D01*
X453700Y-1036000D01*
X453600Y-1034800D01*
X453300Y-1033733D01*
X452900Y-1032933D01*
X452300Y-1032267D01*
X451500Y-1032000D01*
G01X366511Y156622D02*
Y164122D01*
X368751D01*
X369498Y163747D01*
X370058Y162872D01*
X370245Y161872D01*
X370058Y160872D01*
X369591Y160122D01*
X368751Y159747D01*
X366511D01*
G01X377931Y163497D02*
X377371Y163872D01*
X376718Y164122D01*
X375971D01*
X375131Y163747D01*
X374478Y163122D01*
X374011Y162372D01*
X373638Y161122D01*
X373545Y159997D01*
X373731Y158872D01*
X374011Y158122D01*
X374571Y157372D01*
X375225Y156872D01*
X375878Y156622D01*
X376531D01*
X377185Y156872D01*
X377745Y157247D01*
X378211Y157747D01*
G01X384125Y160622D02*
X384498Y160997D01*
X384778Y161622D01*
X384965Y162497D01*
X384778Y163247D01*
X384405Y163747D01*
X383751Y164122D01*
X381231D01*
Y156622D01*
X384311D01*
X384965Y157122D01*
X385338Y157872D01*
X385525Y158747D01*
X385338Y159622D01*
X384778Y160372D01*
X384125Y160622D01*
X381231D01*
G01X396045Y164122D02*
X398378Y156622D01*
X400711Y164122D01*
G01X407745Y156622D02*
X404011D01*
Y164122D01*
X407745D01*
G01X406251Y160497D02*
X404011D01*
G01X411231Y156622D02*
Y164122D01*
X415525Y156622D01*
Y164122D01*
G01X418825Y156622D02*
Y164122D01*
X420691D01*
X421438Y163747D01*
X421998Y163247D01*
X422465Y162497D01*
X422838Y161622D01*
X422931Y160372D01*
X422838Y159122D01*
X422465Y158247D01*
X421998Y157497D01*
X421438Y156997D01*
X420691Y156622D01*
X418825D01*
G01X428378D02*
X427631Y156747D01*
X426978Y157247D01*
X426418Y157997D01*
X426045Y158872D01*
X425858Y159872D01*
Y160872D01*
X426045Y161872D01*
X426418Y162747D01*
X426978Y163497D01*
X427631Y163997D01*
X428378Y164122D01*
X429125Y163997D01*
X429778Y163497D01*
X430338Y162747D01*
X430711Y161872D01*
X430898Y160872D01*
Y159872D01*
X430711Y158872D01*
X430338Y157997D01*
X429778Y157247D01*
X429125Y156747D01*
X428378Y156622D01*
G01X434011D02*
Y164122D01*
X436345D01*
X437091Y163747D01*
X437558Y163247D01*
X437745Y162247D01*
X437558Y161247D01*
X436998Y160622D01*
X436345Y160247D01*
X434011D01*
G01X436345D02*
X437745Y156622D01*
G01X384952Y465890D02*
X386411Y466820D01*
X387244Y468060D01*
X387452Y469455D01*
X387244Y470695D01*
X386202Y471935D01*
X384952Y472710D01*
X383702Y472865D01*
X382244Y472555D01*
X381202Y471470D01*
X380785Y470385D01*
Y468990D01*
G01Y470385D02*
X380160Y471315D01*
X379119Y472090D01*
X377869Y472400D01*
X376619Y472090D01*
X375577Y471315D01*
X374952Y469920D01*
X375160Y468525D01*
X375994Y467130D01*
G01X385994Y479065D02*
X387035Y480150D01*
X387452Y481390D01*
X387035Y482630D01*
X385786Y483715D01*
X383910Y484490D01*
X382035Y484800D01*
X379744D01*
X377869Y484490D01*
X376202Y483715D01*
X375369Y482785D01*
X374952Y481700D01*
X375369Y480460D01*
X376202Y479530D01*
X377452Y478910D01*
X379119Y478600D01*
X380577Y478910D01*
X382035Y479685D01*
X382869Y480615D01*
X383077Y481700D01*
X382661Y482940D01*
X381619Y483870D01*
X379744Y484800D01*
G01X384952Y490690D02*
X386411Y491620D01*
X387244Y492860D01*
X387452Y494255D01*
X387244Y495495D01*
X386202Y496735D01*
X384952Y497510D01*
X383702Y497665D01*
X382244Y497355D01*
X381202Y496270D01*
X380785Y495185D01*
Y493790D01*
G01Y495185D02*
X380160Y496115D01*
X379119Y496890D01*
X377869Y497200D01*
X376619Y496890D01*
X375577Y496115D01*
X374952Y494720D01*
X375160Y493325D01*
X375994Y491930D01*
G01X387452Y506190D02*
X384744Y506500D01*
X382452Y506965D01*
X380369Y507585D01*
X378077Y508360D01*
X374952Y509600D01*
Y503400D01*
G01X387869Y518900D02*
X387660Y518590D01*
X387244D01*
X387035Y518900D01*
X387244Y519210D01*
X387660D01*
X387869Y518900D01*
G01X374952Y531300D02*
X375369Y530060D01*
X376410Y529130D01*
X377660Y528510D01*
X379327Y528045D01*
X381202Y527890D01*
X383077Y528045D01*
X384744Y528510D01*
X385994Y529130D01*
X387035Y530060D01*
X387452Y531300D01*
X387035Y532540D01*
X385994Y533470D01*
X384744Y534090D01*
X383077Y534555D01*
X381202Y534710D01*
X379327Y534555D01*
X377660Y534090D01*
X376410Y533470D01*
X375369Y532540D01*
X374952Y531300D01*
G01X377035Y540755D02*
X375786Y541685D01*
X375160Y542770D01*
X374952Y544010D01*
X375369Y545560D01*
X376410Y546645D01*
X377660Y546955D01*
X378911Y546800D01*
X379952Y546180D01*
X382035Y543080D01*
X383494Y541685D01*
X385577Y540755D01*
X387452Y540445D01*
Y546955D01*
G01X365850Y777950D02*
X365642Y779035D01*
X365017Y780275D01*
X363975Y781050D01*
X362517Y781360D01*
X361059Y781050D01*
X359808Y780120D01*
X359183Y778725D01*
Y777175D01*
X358767Y776245D01*
X357725Y775470D01*
X356267Y775160D01*
X354808Y775625D01*
X353767Y776710D01*
X353350Y777950D01*
X353767Y779190D01*
X354808Y780275D01*
X356267Y780740D01*
X357725Y780430D01*
X358767Y779655D01*
X359183Y778725D01*
Y777175D01*
X359808Y775780D01*
X361059Y774850D01*
X362517Y774540D01*
X363975Y774850D01*
X365017Y775625D01*
X365642Y776865D01*
X365850Y777950D01*
G01X353350Y790350D02*
X353767Y789110D01*
X354808Y788180D01*
X356058Y787560D01*
X357725Y787095D01*
X359600Y786940D01*
X361475Y787095D01*
X363142Y787560D01*
X364392Y788180D01*
X365433Y789110D01*
X365850Y790350D01*
X365433Y791590D01*
X364392Y792520D01*
X363142Y793140D01*
X361475Y793605D01*
X359600Y793760D01*
X357725Y793605D01*
X356058Y793140D01*
X354808Y792520D01*
X353767Y791590D01*
X353350Y790350D01*
G01X389600Y-1012500D02*
Y-1004500D01*
X393400D01*
G01X392000Y-1008367D02*
X389600D01*
G01X399500Y-1004500D02*
X398700Y-1004767D01*
X398100Y-1005433D01*
X397700Y-1006233D01*
X397400Y-1007300D01*
X397300Y-1008500D01*
X397400Y-1009700D01*
X397700Y-1010767D01*
X398100Y-1011567D01*
X398700Y-1012233D01*
X399500Y-1012500D01*
X400300Y-1012233D01*
X400900Y-1011567D01*
X401300Y-1010767D01*
X401600Y-1009700D01*
X401700Y-1008500D01*
X401600Y-1007300D01*
X401300Y-1006233D01*
X400900Y-1005433D01*
X400300Y-1004767D01*
X399500Y-1004500D01*
G01X407500D02*
Y-1012500D01*
G01X405200Y-1004500D02*
X409800D01*
G01X412500Y-1015167D02*
X418500D01*
G01X421500Y-1012500D02*
Y-1004500D01*
X423900D01*
X424700Y-1004900D01*
X425300Y-1005833D01*
X425500Y-1006900D01*
X425300Y-1007967D01*
X424800Y-1008767D01*
X423900Y-1009167D01*
X421500D01*
G01X429300Y-1012500D02*
Y-1004500D01*
X431300D01*
X432100Y-1004900D01*
X432700Y-1005433D01*
X433200Y-1006233D01*
X433600Y-1007167D01*
X433700Y-1008500D01*
X433600Y-1009833D01*
X433200Y-1010767D01*
X432700Y-1011567D01*
X432100Y-1012100D01*
X431300Y-1012500D01*
X429300D01*
G01X440300Y-1008233D02*
X440700Y-1007833D01*
X441000Y-1007167D01*
X441200Y-1006233D01*
X441000Y-1005433D01*
X440600Y-1004900D01*
X439900Y-1004500D01*
X437200D01*
Y-1012500D01*
X440500D01*
X441200Y-1011967D01*
X441600Y-1011167D01*
X441800Y-1010233D01*
X441600Y-1009300D01*
X441000Y-1008500D01*
X440300Y-1008233D01*
X437200D01*
G01X444500Y-1015167D02*
X450500D01*
G01X456300Y-1008233D02*
X456700Y-1007833D01*
X457000Y-1007167D01*
X457200Y-1006233D01*
X457000Y-1005433D01*
X456600Y-1004900D01*
X455900Y-1004500D01*
X453200D01*
Y-1012500D01*
X456500D01*
X457200Y-1011967D01*
X457600Y-1011167D01*
X457800Y-1010233D01*
X457600Y-1009300D01*
X457000Y-1008500D01*
X456300Y-1008233D01*
X453200D01*
G01X461300Y-1012500D02*
Y-1004500D01*
X463300D01*
X464100Y-1004900D01*
X464700Y-1005433D01*
X465200Y-1006233D01*
X465600Y-1007167D01*
X465700Y-1008500D01*
X465600Y-1009833D01*
X465200Y-1010767D01*
X464700Y-1011567D01*
X464100Y-1012100D01*
X463300Y-1012500D01*
X461300D01*
G01X468500Y-1015167D02*
X474500D01*
G01X480100Y-1008500D02*
X482100D01*
Y-1010900D01*
X481500Y-1011700D01*
X480800Y-1012233D01*
X479800Y-1012500D01*
X478800Y-1012233D01*
X478100Y-1011700D01*
X477500Y-1010900D01*
X477100Y-1009967D01*
X476900Y-1008900D01*
Y-1007967D01*
X477100Y-1007167D01*
X477500Y-1006233D01*
X478100Y-1005433D01*
X478700Y-1004900D01*
X479500Y-1004500D01*
X480200D01*
X481000Y-1004767D01*
X481600Y-1005300D01*
G01X485500Y-1012500D02*
Y-1004500D01*
X487900D01*
X488700Y-1004900D01*
X489300Y-1005833D01*
X489500Y-1006900D01*
X489300Y-1007967D01*
X488800Y-1008767D01*
X487900Y-1009167D01*
X485500D01*
G01X493300Y-1004500D02*
Y-1010233D01*
X493700Y-1011434D01*
X494500Y-1012233D01*
X495500Y-1012500D01*
X496500Y-1012233D01*
X497300Y-1011434D01*
X497700Y-1010233D01*
Y-1004500D01*
G01X389011Y148374D02*
Y140874D01*
X392745D01*
G01X398378D02*
X397631Y140999D01*
X396978Y141499D01*
X396418Y142249D01*
X396045Y143124D01*
X395858Y144124D01*
Y145124D01*
X396045Y146124D01*
X396418Y146999D01*
X396978Y147749D01*
X397631Y148249D01*
X398378Y148374D01*
X399125Y148249D01*
X399778Y147749D01*
X400338Y146999D01*
X400711Y146124D01*
X400898Y145124D01*
Y144124D01*
X400711Y143124D01*
X400338Y142249D01*
X399778Y141499D01*
X399125Y140999D01*
X398378Y140874D01*
G01X406438Y144624D02*
X408305D01*
Y142374D01*
X407745Y141624D01*
X407091Y141124D01*
X406158Y140874D01*
X405225Y141124D01*
X404571Y141624D01*
X404011Y142374D01*
X403638Y143249D01*
X403451Y144249D01*
Y145124D01*
X403638Y145874D01*
X404011Y146749D01*
X404571Y147499D01*
X405131Y147999D01*
X405878Y148374D01*
X406531D01*
X407278Y148124D01*
X407838Y147624D01*
G01X413378Y140874D02*
X412631Y140999D01*
X411978Y141499D01*
X411418Y142249D01*
X411045Y143124D01*
X410858Y144124D01*
Y145124D01*
X411045Y146124D01*
X411418Y146999D01*
X411978Y147749D01*
X412631Y148249D01*
X413378Y148374D01*
X414125Y148249D01*
X414778Y147749D01*
X415338Y146999D01*
X415711Y146124D01*
X415898Y145124D01*
Y144124D01*
X415711Y143124D01*
X415338Y142249D01*
X414778Y141499D01*
X414125Y140999D01*
X413378Y140874D01*
G01X382206Y310501D02*
Y318001D01*
X384446D01*
X385193Y317626D01*
X385753Y316751D01*
X385940Y315751D01*
X385753Y314751D01*
X385286Y314001D01*
X384446Y313626D01*
X382206D01*
G01X391573Y318001D02*
Y310501D01*
G01X389426Y318001D02*
X393720D01*
G01X397113Y310501D02*
Y318001D01*
G01X401033D02*
Y310501D01*
G01Y314251D02*
X397113D01*
G01X412452Y494250D02*
X399952D01*
X402452Y492390D01*
G01X412452D02*
Y496110D01*
G01X399952Y506650D02*
X400369Y505410D01*
X401410Y504480D01*
X402660Y503860D01*
X404327Y503395D01*
X406202Y503240D01*
X408077Y503395D01*
X409744Y503860D01*
X410994Y504480D01*
X412035Y505410D01*
X412452Y506650D01*
X412035Y507890D01*
X410994Y508820D01*
X409744Y509440D01*
X408077Y509905D01*
X406202Y510060D01*
X404327Y509905D01*
X402660Y509440D01*
X401410Y508820D01*
X400369Y507890D01*
X399952Y506650D01*
G01Y519050D02*
X400369Y517810D01*
X401410Y516880D01*
X402660Y516260D01*
X404327Y515795D01*
X406202Y515640D01*
X408077Y515795D01*
X409744Y516260D01*
X410994Y516880D01*
X412035Y517810D01*
X412452Y519050D01*
X412035Y520290D01*
X410994Y521220D01*
X409744Y521840D01*
X408077Y522305D01*
X406202Y522460D01*
X404327Y522305D01*
X402660Y521840D01*
X401410Y521220D01*
X400369Y520290D01*
X399952Y519050D01*
G01X426890Y569148D02*
X427820Y568106D01*
X428905Y567481D01*
X430300Y567273D01*
X431695Y567690D01*
X432780Y568523D01*
X433555Y569981D01*
X433710Y571648D01*
X433400Y573315D01*
X432625Y574356D01*
X431540Y575190D01*
X430455Y575398D01*
X429370Y575190D01*
X427975Y574356D01*
X428440Y579773D01*
X432625D01*
G01X439755Y572481D02*
X440840Y573940D01*
X441770Y574773D01*
X443010Y575190D01*
X444095Y574773D01*
X444870Y573940D01*
X445490Y572690D01*
X445645Y571231D01*
X445490Y569981D01*
X444870Y568731D01*
X443940Y567690D01*
X442855Y567273D01*
X441615Y567690D01*
X440530Y568939D01*
X439910Y570815D01*
X439755Y572898D01*
X440065Y575606D01*
X440530Y577065D01*
X441305Y578523D01*
X442390Y579565D01*
X443475Y579773D01*
X444560Y579356D01*
X445335Y578315D01*
G01X455100Y567273D02*
Y579773D01*
X453240Y577273D01*
G01Y567273D02*
X456960D01*
G01X467500Y579773D02*
X466260Y579356D01*
X465330Y578315D01*
X464710Y577065D01*
X464245Y575398D01*
X464090Y573523D01*
X464245Y571648D01*
X464710Y569981D01*
X465330Y568731D01*
X466260Y567690D01*
X467500Y567273D01*
X468740Y567690D01*
X469670Y568731D01*
X470290Y569981D01*
X470755Y571648D01*
X470910Y573523D01*
X470755Y575398D01*
X470290Y577065D01*
X469670Y578315D01*
X468740Y579356D01*
X467500Y579773D01*
G01X479900Y566856D02*
X479590Y567065D01*
Y567481D01*
X479900Y567690D01*
X480210Y567481D01*
Y567065D01*
X479900Y566856D01*
G01X489355Y577690D02*
X490285Y578939D01*
X491370Y579565D01*
X492610Y579773D01*
X494160Y579356D01*
X495245Y578315D01*
X495555Y577065D01*
X495400Y575814D01*
X494780Y574773D01*
X491680Y572690D01*
X490285Y571231D01*
X489355Y569148D01*
X489045Y567273D01*
X495555D01*
G01X501290Y569773D02*
X502220Y568314D01*
X503460Y567481D01*
X504855Y567273D01*
X506095Y567481D01*
X507335Y568523D01*
X508110Y569773D01*
X508265Y571023D01*
X507955Y572481D01*
X506870Y573523D01*
X505785Y573940D01*
X504390D01*
G01X505785D02*
X506715Y574565D01*
X507490Y575606D01*
X507800Y576856D01*
X507490Y578106D01*
X506715Y579148D01*
X505320Y579773D01*
X503925Y579565D01*
X502530Y578731D01*
G01X433100Y598691D02*
Y611191D01*
X431240Y608691D01*
G01Y598691D02*
X434960D01*
G01X442090Y600566D02*
X443020Y599524D01*
X444105Y598899D01*
X445500Y598691D01*
X446895Y599108D01*
X447980Y599941D01*
X448755Y601399D01*
X448910Y603066D01*
X448600Y604733D01*
X447825Y605774D01*
X446740Y606608D01*
X445655Y606816D01*
X444570Y606608D01*
X443175Y605774D01*
X443640Y611191D01*
X447825D01*
G01X454955Y603899D02*
X456040Y605358D01*
X456970Y606191D01*
X458210Y606608D01*
X459295Y606191D01*
X460070Y605358D01*
X460690Y604108D01*
X460845Y602649D01*
X460690Y601399D01*
X460070Y600149D01*
X459140Y599108D01*
X458055Y598691D01*
X456815Y599108D01*
X455730Y600357D01*
X455110Y602233D01*
X454955Y604316D01*
X455265Y607024D01*
X455730Y608483D01*
X456505Y609941D01*
X457590Y610983D01*
X458675Y611191D01*
X459760Y610774D01*
X460535Y609733D01*
G01X470300Y598274D02*
X469990Y598483D01*
Y598899D01*
X470300Y599108D01*
X470610Y598899D01*
Y598483D01*
X470300Y598274D01*
G01X482700Y598691D02*
X483785Y598899D01*
X485025Y599524D01*
X485800Y600566D01*
X486110Y602024D01*
X485800Y603482D01*
X484870Y604733D01*
X483475Y605358D01*
X481925D01*
X480995Y605774D01*
X480220Y606816D01*
X479910Y608274D01*
X480375Y609733D01*
X481460Y610774D01*
X482700Y611191D01*
X483940Y610774D01*
X485025Y609733D01*
X485490Y608274D01*
X485180Y606816D01*
X484405Y605774D01*
X483475Y605358D01*
X481925D01*
X480530Y604733D01*
X479600Y603482D01*
X479290Y602024D01*
X479600Y600566D01*
X480375Y599524D01*
X481615Y598899D01*
X482700Y598691D01*
G01X491690Y601191D02*
X492620Y599732D01*
X493860Y598899D01*
X495255Y598691D01*
X496495Y598899D01*
X497735Y599941D01*
X498510Y601191D01*
X498665Y602441D01*
X498355Y603899D01*
X497270Y604941D01*
X496185Y605358D01*
X494790D01*
G01X496185D02*
X497115Y605983D01*
X497890Y607024D01*
X498200Y608274D01*
X497890Y609524D01*
X497115Y610566D01*
X495720Y611191D01*
X494325Y610983D01*
X492930Y610149D01*
G01X423805Y628899D02*
X424890Y630358D01*
X425820Y631191D01*
X427060Y631608D01*
X428145Y631191D01*
X428920Y630358D01*
X429540Y629108D01*
X429695Y627649D01*
X429540Y626399D01*
X428920Y625149D01*
X427990Y624108D01*
X426905Y623691D01*
X425665Y624108D01*
X424580Y625357D01*
X423960Y627233D01*
X423805Y629316D01*
X424115Y632024D01*
X424580Y633483D01*
X425355Y634941D01*
X426440Y635983D01*
X427525Y636191D01*
X428610Y635774D01*
X429385Y634733D01*
G01X439150Y623691D02*
Y636191D01*
X437290Y633691D01*
G01Y623691D02*
X441010D01*
G01X451240D02*
X451550Y626399D01*
X452015Y628691D01*
X452635Y630774D01*
X453410Y633066D01*
X454650Y636191D01*
X448450D01*
G01X465810Y623691D02*
Y636191D01*
X460075Y627233D01*
X467825D01*
G01X476350Y623274D02*
X476040Y623483D01*
Y623899D01*
X476350Y624108D01*
X476660Y623899D01*
Y623483D01*
X476350Y623274D01*
G01X490610Y623691D02*
Y636191D01*
X484875Y627233D01*
X492625D01*
G01X501150Y623691D02*
Y636191D01*
X499290Y633691D01*
G01Y623691D02*
X503010D01*
G01X458000Y-1065500D02*
Y-1057500D01*
X456800Y-1059100D01*
G01Y-1065500D02*
X459200D01*
G01X464100Y-1062167D02*
X464800Y-1061233D01*
X465400Y-1060700D01*
X466200Y-1060433D01*
X466900Y-1060700D01*
X467400Y-1061233D01*
X467800Y-1062033D01*
X467900Y-1062967D01*
X467800Y-1063767D01*
X467400Y-1064567D01*
X466800Y-1065233D01*
X466100Y-1065500D01*
X465300Y-1065233D01*
X464600Y-1064434D01*
X464200Y-1063233D01*
X464100Y-1061900D01*
X464300Y-1060167D01*
X464600Y-1059233D01*
X465100Y-1058300D01*
X465800Y-1057633D01*
X466500Y-1057500D01*
X467200Y-1057767D01*
X467700Y-1058433D01*
G01X474000Y-1065767D02*
X473800Y-1065633D01*
Y-1065367D01*
X474000Y-1065233D01*
X474200Y-1065367D01*
Y-1065633D01*
X474000Y-1065767D01*
G01X480100Y-1062167D02*
X480800Y-1061233D01*
X481400Y-1060700D01*
X482200Y-1060433D01*
X482900Y-1060700D01*
X483400Y-1061233D01*
X483800Y-1062033D01*
X483900Y-1062967D01*
X483800Y-1063767D01*
X483400Y-1064567D01*
X482800Y-1065233D01*
X482100Y-1065500D01*
X481300Y-1065233D01*
X480600Y-1064434D01*
X480200Y-1063233D01*
X480100Y-1061900D01*
X480300Y-1060167D01*
X480600Y-1059233D01*
X481100Y-1058300D01*
X481800Y-1057633D01*
X482500Y-1057500D01*
X483200Y-1057767D01*
X483700Y-1058433D01*
G01X442850Y542273D02*
Y554773D01*
X440990Y552273D01*
G01Y542273D02*
X444710D01*
G01X457110D02*
Y554773D01*
X451375Y545815D01*
X459125D01*
G01X464705Y552690D02*
X465635Y553939D01*
X466720Y554565D01*
X467960Y554773D01*
X469510Y554356D01*
X470595Y553315D01*
X470905Y552065D01*
X470750Y550814D01*
X470130Y549773D01*
X467030Y547690D01*
X465635Y546231D01*
X464705Y544148D01*
X464395Y542273D01*
X470905D01*
G01X480050Y541856D02*
X479740Y542065D01*
Y542481D01*
X480050Y542690D01*
X480360Y542481D01*
Y542065D01*
X480050Y541856D01*
G01X489040Y544148D02*
X489970Y543106D01*
X491055Y542481D01*
X492450Y542273D01*
X493845Y542690D01*
X494930Y543523D01*
X495705Y544981D01*
X495860Y546648D01*
X495550Y548315D01*
X494775Y549356D01*
X493690Y550190D01*
X492605Y550398D01*
X491520Y550190D01*
X490125Y549356D01*
X490590Y554773D01*
X494775D01*
G01X503000Y-1065500D02*
Y-1057500D01*
X501800Y-1059100D01*
G01Y-1065500D02*
X504200D01*
G01X510800D02*
X511000Y-1063767D01*
X511300Y-1062300D01*
X511700Y-1060967D01*
X512200Y-1059500D01*
X513000Y-1057500D01*
X509000D01*
G01X519000Y-1065767D02*
X518800Y-1065633D01*
Y-1065367D01*
X519000Y-1065233D01*
X519200Y-1065367D01*
Y-1065633D01*
X519000Y-1065767D01*
G01X525100Y-1058833D02*
X525700Y-1058033D01*
X526400Y-1057633D01*
X527200Y-1057500D01*
X528200Y-1057767D01*
X528900Y-1058433D01*
X529100Y-1059233D01*
X529000Y-1060034D01*
X528600Y-1060700D01*
X526600Y-1062033D01*
X525700Y-1062967D01*
X525100Y-1064300D01*
X524900Y-1065500D01*
X529100D01*
G01X523100Y-1040500D02*
Y-1032500D01*
X526900D01*
G01X525500Y-1036367D02*
X523100D01*
G01X597507Y449940D02*
Y446840D01*
X596587D01*
X596280Y446995D01*
X596050Y447357D01*
X595973Y447770D01*
X596050Y448183D01*
X596242Y448493D01*
X596587Y448648D01*
X597507D01*
G01X592797Y447098D02*
X593027Y446943D01*
X593295Y446840D01*
X593602D01*
X593947Y446995D01*
X594215Y447253D01*
X594407Y447563D01*
X594560Y448080D01*
X594598Y448545D01*
X594522Y449010D01*
X594407Y449320D01*
X594177Y449630D01*
X593908Y449837D01*
X593640Y449940D01*
X593372D01*
X593103Y449837D01*
X592873Y449682D01*
X592682Y449475D01*
G01X590233Y448287D02*
X590080Y448132D01*
X589965Y447873D01*
X589888Y447512D01*
X589965Y447202D01*
X590118Y446995D01*
X590387Y446840D01*
X591422D01*
Y449940D01*
X590157D01*
X589888Y449733D01*
X589735Y449423D01*
X589658Y449062D01*
X589735Y448700D01*
X589965Y448390D01*
X590233Y448287D01*
X591422D01*
G01X585298Y446840D02*
X584340Y449940D01*
X583382Y446840D01*
G01X580473Y449940D02*
X582007D01*
Y446840D01*
X580473D01*
G01X581087Y448338D02*
X582007D01*
G01X579022Y449940D02*
Y446840D01*
X577258Y449940D01*
Y446840D01*
G01X575883Y449940D02*
Y446840D01*
X575117D01*
X574810Y446995D01*
X574580Y447202D01*
X574388Y447512D01*
X574235Y447873D01*
X574197Y448390D01*
X574235Y448907D01*
X574388Y449268D01*
X574580Y449578D01*
X574810Y449785D01*
X575117Y449940D01*
X575883D01*
G01X571940D02*
X572247Y449888D01*
X572515Y449682D01*
X572745Y449372D01*
X572898Y449010D01*
X572975Y448597D01*
Y448183D01*
X572898Y447770D01*
X572745Y447408D01*
X572515Y447098D01*
X572247Y446892D01*
X571940Y446840D01*
X571633Y446892D01*
X571365Y447098D01*
X571135Y447408D01*
X570982Y447770D01*
X570905Y448183D01*
Y448597D01*
X570982Y449010D01*
X571135Y449372D01*
X571365Y449682D01*
X571633Y449888D01*
X571940Y449940D01*
G01X569607D02*
Y446840D01*
X568648D01*
X568342Y446995D01*
X568150Y447202D01*
X568073Y447615D01*
X568150Y448028D01*
X568380Y448287D01*
X568648Y448442D01*
X569607D01*
G01X568648D02*
X568073Y449940D01*
G01X597507D02*
Y446840D01*
X596587D01*
X596280Y446995D01*
X596050Y447357D01*
X595973Y447770D01*
X596050Y448183D01*
X596242Y448493D01*
X596587Y448648D01*
X597507D01*
G01X592797Y447098D02*
X593027Y446943D01*
X593295Y446840D01*
X593602D01*
X593947Y446995D01*
X594215Y447253D01*
X594407Y447563D01*
X594560Y448080D01*
X594598Y448545D01*
X594522Y449010D01*
X594407Y449320D01*
X594177Y449630D01*
X593908Y449837D01*
X593640Y449940D01*
X593372D01*
X593103Y449837D01*
X592873Y449682D01*
X592682Y449475D01*
G01X590233Y448287D02*
X590080Y448132D01*
X589965Y447873D01*
X589888Y447512D01*
X589965Y447202D01*
X590118Y446995D01*
X590387Y446840D01*
X591422D01*
Y449940D01*
X590157D01*
X589888Y449733D01*
X589735Y449423D01*
X589658Y449062D01*
X589735Y448700D01*
X589965Y448390D01*
X590233Y448287D01*
X591422D01*
G01X585298Y446840D02*
X584340Y449940D01*
X583382Y446840D01*
G01X580473Y449940D02*
X582007D01*
Y446840D01*
X580473D01*
G01X581087Y448338D02*
X582007D01*
G01X579022Y449940D02*
Y446840D01*
X577258Y449940D01*
Y446840D01*
G01X575883Y449940D02*
Y446840D01*
X575117D01*
X574810Y446995D01*
X574580Y447202D01*
X574388Y447512D01*
X574235Y447873D01*
X574197Y448390D01*
X574235Y448907D01*
X574388Y449268D01*
X574580Y449578D01*
X574810Y449785D01*
X575117Y449940D01*
X575883D01*
G01X571940D02*
X572247Y449888D01*
X572515Y449682D01*
X572745Y449372D01*
X572898Y449010D01*
X572975Y448597D01*
Y448183D01*
X572898Y447770D01*
X572745Y447408D01*
X572515Y447098D01*
X572247Y446892D01*
X571940Y446840D01*
X571633Y446892D01*
X571365Y447098D01*
X571135Y447408D01*
X570982Y447770D01*
X570905Y448183D01*
Y448597D01*
X570982Y449010D01*
X571135Y449372D01*
X571365Y449682D01*
X571633Y449888D01*
X571940Y449940D01*
G01X569607D02*
Y446840D01*
X568648D01*
X568342Y446995D01*
X568150Y447202D01*
X568073Y447615D01*
X568150Y448028D01*
X568380Y448287D01*
X568648Y448442D01*
X569607D01*
G01X568648D02*
X568073Y449940D01*
G01X597507D02*
Y446840D01*
X596587D01*
X596280Y446995D01*
X596050Y447357D01*
X595973Y447770D01*
X596050Y448183D01*
X596242Y448493D01*
X596587Y448648D01*
X597507D01*
G01X592797Y447098D02*
X593027Y446943D01*
X593295Y446840D01*
X593602D01*
X593947Y446995D01*
X594215Y447253D01*
X594407Y447563D01*
X594560Y448080D01*
X594598Y448545D01*
X594522Y449010D01*
X594407Y449320D01*
X594177Y449630D01*
X593908Y449837D01*
X593640Y449940D01*
X593372D01*
X593103Y449837D01*
X592873Y449682D01*
X592682Y449475D01*
G01X590233Y448287D02*
X590080Y448132D01*
X589965Y447873D01*
X589888Y447512D01*
X589965Y447202D01*
X590118Y446995D01*
X590387Y446840D01*
X591422D01*
Y449940D01*
X590157D01*
X589888Y449733D01*
X589735Y449423D01*
X589658Y449062D01*
X589735Y448700D01*
X589965Y448390D01*
X590233Y448287D01*
X591422D01*
G01X585298Y446840D02*
X584340Y449940D01*
X583382Y446840D01*
G01X580473Y449940D02*
X582007D01*
Y446840D01*
X580473D01*
G01X581087Y448338D02*
X582007D01*
G01X579022Y449940D02*
Y446840D01*
X577258Y449940D01*
Y446840D01*
G01X575883Y449940D02*
Y446840D01*
X575117D01*
X574810Y446995D01*
X574580Y447202D01*
X574388Y447512D01*
X574235Y447873D01*
X574197Y448390D01*
X574235Y448907D01*
X574388Y449268D01*
X574580Y449578D01*
X574810Y449785D01*
X575117Y449940D01*
X575883D01*
G01X571940D02*
X572247Y449888D01*
X572515Y449682D01*
X572745Y449372D01*
X572898Y449010D01*
X572975Y448597D01*
Y448183D01*
X572898Y447770D01*
X572745Y447408D01*
X572515Y447098D01*
X572247Y446892D01*
X571940Y446840D01*
X571633Y446892D01*
X571365Y447098D01*
X571135Y447408D01*
X570982Y447770D01*
X570905Y448183D01*
Y448597D01*
X570982Y449010D01*
X571135Y449372D01*
X571365Y449682D01*
X571633Y449888D01*
X571940Y449940D01*
G01X569607D02*
Y446840D01*
X568648D01*
X568342Y446995D01*
X568150Y447202D01*
X568073Y447615D01*
X568150Y448028D01*
X568380Y448287D01*
X568648Y448442D01*
X569607D01*
G01X568648D02*
X568073Y449940D01*
G01X589107Y452240D02*
Y455340D01*
X587573D01*
G01X585240D02*
X585547Y455288D01*
X585815Y455082D01*
X586045Y454772D01*
X586198Y454410D01*
X586275Y453997D01*
Y453583D01*
X586198Y453170D01*
X586045Y452808D01*
X585815Y452498D01*
X585547Y452292D01*
X585240Y452240D01*
X584933Y452292D01*
X584665Y452498D01*
X584435Y452808D01*
X584282Y453170D01*
X584205Y453583D01*
Y453997D01*
X584282Y454410D01*
X584435Y454772D01*
X584665Y455082D01*
X584933Y455288D01*
X585240Y455340D01*
G01X581910Y453790D02*
X581143D01*
Y454720D01*
X581373Y455030D01*
X581642Y455237D01*
X582025Y455340D01*
X582408Y455237D01*
X582677Y455030D01*
X582907Y454720D01*
X583060Y454358D01*
X583137Y453945D01*
Y453583D01*
X583060Y453273D01*
X582907Y452912D01*
X582677Y452602D01*
X582447Y452395D01*
X582140Y452240D01*
X581872D01*
X581565Y452343D01*
X581335Y452550D01*
G01X579040Y455340D02*
X579347Y455288D01*
X579615Y455082D01*
X579845Y454772D01*
X579998Y454410D01*
X580075Y453997D01*
Y453583D01*
X579998Y453170D01*
X579845Y452808D01*
X579615Y452498D01*
X579347Y452292D01*
X579040Y452240D01*
X578733Y452292D01*
X578465Y452498D01*
X578235Y452808D01*
X578082Y453170D01*
X578005Y453583D01*
Y453997D01*
X578082Y454410D01*
X578235Y454772D01*
X578465Y455082D01*
X578733Y455288D01*
X579040Y455340D01*
G01X589107Y452240D02*
Y455340D01*
X587573D01*
G01X585240D02*
X585547Y455288D01*
X585815Y455082D01*
X586045Y454772D01*
X586198Y454410D01*
X586275Y453997D01*
Y453583D01*
X586198Y453170D01*
X586045Y452808D01*
X585815Y452498D01*
X585547Y452292D01*
X585240Y452240D01*
X584933Y452292D01*
X584665Y452498D01*
X584435Y452808D01*
X584282Y453170D01*
X584205Y453583D01*
Y453997D01*
X584282Y454410D01*
X584435Y454772D01*
X584665Y455082D01*
X584933Y455288D01*
X585240Y455340D01*
G01X581910Y453790D02*
X581143D01*
Y454720D01*
X581373Y455030D01*
X581642Y455237D01*
X582025Y455340D01*
X582408Y455237D01*
X582677Y455030D01*
X582907Y454720D01*
X583060Y454358D01*
X583137Y453945D01*
Y453583D01*
X583060Y453273D01*
X582907Y452912D01*
X582677Y452602D01*
X582447Y452395D01*
X582140Y452240D01*
X581872D01*
X581565Y452343D01*
X581335Y452550D01*
G01X579040Y455340D02*
X579347Y455288D01*
X579615Y455082D01*
X579845Y454772D01*
X579998Y454410D01*
X580075Y453997D01*
Y453583D01*
X579998Y453170D01*
X579845Y452808D01*
X579615Y452498D01*
X579347Y452292D01*
X579040Y452240D01*
X578733Y452292D01*
X578465Y452498D01*
X578235Y452808D01*
X578082Y453170D01*
X578005Y453583D01*
Y453997D01*
X578082Y454410D01*
X578235Y454772D01*
X578465Y455082D01*
X578733Y455288D01*
X579040Y455340D01*
G01X589107Y452240D02*
Y455340D01*
X587573D01*
G01X585240D02*
X585547Y455288D01*
X585815Y455082D01*
X586045Y454772D01*
X586198Y454410D01*
X586275Y453997D01*
Y453583D01*
X586198Y453170D01*
X586045Y452808D01*
X585815Y452498D01*
X585547Y452292D01*
X585240Y452240D01*
X584933Y452292D01*
X584665Y452498D01*
X584435Y452808D01*
X584282Y453170D01*
X584205Y453583D01*
Y453997D01*
X584282Y454410D01*
X584435Y454772D01*
X584665Y455082D01*
X584933Y455288D01*
X585240Y455340D01*
G01X581910Y453790D02*
X581143D01*
Y454720D01*
X581373Y455030D01*
X581642Y455237D01*
X582025Y455340D01*
X582408Y455237D01*
X582677Y455030D01*
X582907Y454720D01*
X583060Y454358D01*
X583137Y453945D01*
Y453583D01*
X583060Y453273D01*
X582907Y452912D01*
X582677Y452602D01*
X582447Y452395D01*
X582140Y452240D01*
X581872D01*
X581565Y452343D01*
X581335Y452550D01*
G01X579040Y455340D02*
X579347Y455288D01*
X579615Y455082D01*
X579845Y454772D01*
X579998Y454410D01*
X580075Y453997D01*
Y453583D01*
X579998Y453170D01*
X579845Y452808D01*
X579615Y452498D01*
X579347Y452292D01*
X579040Y452240D01*
X578733Y452292D01*
X578465Y452498D01*
X578235Y452808D01*
X578082Y453170D01*
X578005Y453583D01*
Y453997D01*
X578082Y454410D01*
X578235Y454772D01*
X578465Y455082D01*
X578733Y455288D01*
X579040Y455340D01*
G01X635097Y12539D02*
Y20039D01*
X637431D01*
X638177Y19664D01*
X638644Y19164D01*
X638831Y18164D01*
X638644Y17164D01*
X638084Y16539D01*
X637431Y16164D01*
X635097D01*
G01X637431D02*
X638831Y12539D01*
G01X646331D02*
X642597D01*
Y20039D01*
X646331D01*
G01X644837Y16414D02*
X642597D01*
G01X654017Y19414D02*
X653457Y19789D01*
X652804Y20039D01*
X652057D01*
X651217Y19664D01*
X650564Y19039D01*
X650097Y18289D01*
X649724Y17039D01*
X649631Y15914D01*
X649817Y14789D01*
X650097Y14039D01*
X650657Y13289D01*
X651311Y12789D01*
X651964Y12539D01*
X652617D01*
X653271Y12789D01*
X653831Y13164D01*
X654297Y13664D01*
G01X659464Y12539D02*
X658717Y12664D01*
X658064Y13164D01*
X657504Y13914D01*
X657131Y14789D01*
X656944Y15789D01*
Y16789D01*
X657131Y17789D01*
X657504Y18664D01*
X658064Y19414D01*
X658717Y19914D01*
X659464Y20039D01*
X660211Y19914D01*
X660864Y19414D01*
X661424Y18664D01*
X661797Y17789D01*
X661984Y16789D01*
Y15789D01*
X661797Y14789D01*
X661424Y13914D01*
X660864Y13164D01*
X660211Y12664D01*
X659464Y12539D01*
G01X664537D02*
Y20039D01*
X666964Y13789D01*
X669391Y20039D01*
Y12539D01*
G01X672037D02*
Y20039D01*
X674464Y13789D01*
X676891Y20039D01*
Y12539D01*
G01X683831D02*
X680097D01*
Y20039D01*
X683831D01*
G01X682337Y16414D02*
X680097D01*
G01X687317Y12539D02*
Y20039D01*
X691611Y12539D01*
Y20039D01*
G01X694911Y12539D02*
Y20039D01*
X696777D01*
X697524Y19664D01*
X698084Y19164D01*
X698551Y18414D01*
X698924Y17539D01*
X699017Y16289D01*
X698924Y15039D01*
X698551Y14164D01*
X698084Y13414D01*
X697524Y12914D01*
X696777Y12539D01*
X694911D01*
G01X706331D02*
X702597D01*
Y20039D01*
X706331D01*
G01X704837Y16414D02*
X702597D01*
G01X709911Y12539D02*
Y20039D01*
X711777D01*
X712524Y19664D01*
X713084Y19164D01*
X713551Y18414D01*
X713924Y17539D01*
X714017Y16289D01*
X713924Y15039D01*
X713551Y14164D01*
X713084Y13414D01*
X712524Y12914D01*
X711777Y12539D01*
X709911D01*
G01X724911D02*
Y20039D01*
X726777D01*
X727524Y19664D01*
X728084Y19164D01*
X728551Y18414D01*
X728924Y17539D01*
X729017Y16289D01*
X728924Y15039D01*
X728551Y14164D01*
X728084Y13414D01*
X727524Y12914D01*
X726777Y12539D01*
X724911D01*
G01X732597D02*
Y20039D01*
X734931D01*
X735677Y19664D01*
X736144Y19164D01*
X736331Y18164D01*
X736144Y17164D01*
X735584Y16539D01*
X734931Y16164D01*
X732597D01*
G01X734931D02*
X736331Y12539D01*
G01X740844Y20039D02*
X743084D01*
G01X741964D02*
Y12539D01*
G01X740844D02*
X743084D01*
G01X747597Y20039D02*
Y12539D01*
X751331D01*
G01X755097Y20039D02*
Y12539D01*
X758831D01*
G01X770004Y13539D02*
X770751Y12914D01*
X771591Y12539D01*
X772337D01*
X773084Y12914D01*
X773644Y13539D01*
X773924Y14414D01*
X773737Y15289D01*
X773271Y16039D01*
X772431Y16539D01*
X771311Y16789D01*
X770657Y17289D01*
X770377Y18164D01*
X770564Y19039D01*
X771031Y19664D01*
X771684Y20039D01*
X772337D01*
X772991Y19789D01*
X773551Y19164D01*
G01X778344Y20039D02*
X780584D01*
G01X779464D02*
Y12539D01*
G01X778344D02*
X780584D01*
G01X785191Y20039D02*
X788737D01*
X785191Y12539D01*
X788737D01*
G01X796331D02*
X792597D01*
Y20039D01*
X796331D01*
G01X794837Y16414D02*
X792597D01*
G01X807691Y12539D02*
Y20039D01*
X811237D01*
G01X809931Y16414D02*
X807691D01*
G01X816964Y12539D02*
X816217Y12664D01*
X815564Y13164D01*
X815004Y13914D01*
X814631Y14789D01*
X814444Y15789D01*
Y16789D01*
X814631Y17789D01*
X815004Y18664D01*
X815564Y19414D01*
X816217Y19914D01*
X816964Y20039D01*
X817711Y19914D01*
X818364Y19414D01*
X818924Y18664D01*
X819297Y17789D01*
X819484Y16789D01*
Y15789D01*
X819297Y14789D01*
X818924Y13914D01*
X818364Y13164D01*
X817711Y12664D01*
X816964Y12539D01*
G01X822597D02*
Y20039D01*
X824931D01*
X825677Y19664D01*
X826144Y19164D01*
X826331Y18164D01*
X826144Y17164D01*
X825584Y16539D01*
X824931Y16164D01*
X822597D01*
G01X824931D02*
X826331Y12539D01*
G01X839464D02*
Y20039D01*
X838344Y18539D01*
G01Y12539D02*
X840584D01*
G01X846964Y12289D02*
X846777Y12414D01*
Y12664D01*
X846964Y12789D01*
X847151Y12664D01*
Y12414D01*
X846964Y12289D01*
G01X854464Y20039D02*
X853717Y19789D01*
X853157Y19164D01*
X852784Y18414D01*
X852504Y17414D01*
X852411Y16289D01*
X852504Y15164D01*
X852784Y14164D01*
X853157Y13414D01*
X853717Y12789D01*
X854464Y12539D01*
X855211Y12789D01*
X855771Y13414D01*
X856144Y14164D01*
X856424Y15164D01*
X856517Y16289D01*
X856424Y17414D01*
X856144Y18414D01*
X855771Y19164D01*
X855211Y19789D01*
X854464Y20039D01*
G01X860191Y18789D02*
X860751Y19539D01*
X861404Y19914D01*
X862151Y20039D01*
X863084Y19789D01*
X863737Y19164D01*
X863924Y18414D01*
X863831Y17664D01*
X863457Y17039D01*
X861591Y15789D01*
X860751Y14914D01*
X860191Y13664D01*
X860004Y12539D01*
X863924D01*
G01X867037D02*
Y20039D01*
X869464Y13789D01*
X871891Y20039D01*
Y12539D01*
G01X874537D02*
Y20039D01*
X876964Y13789D01*
X879391Y20039D01*
Y12539D01*
G01X890191D02*
Y20039D01*
X893737D01*
G01X892431Y16414D02*
X890191D01*
G01X898344Y20039D02*
X900584D01*
G01X899464D02*
Y12539D01*
G01X898344D02*
X900584D01*
G01X904817D02*
Y20039D01*
X909111Y12539D01*
Y20039D01*
G01X913344D02*
X915584D01*
G01X914464D02*
Y12539D01*
G01X913344D02*
X915584D01*
G01X920004Y13539D02*
X920751Y12914D01*
X921591Y12539D01*
X922337D01*
X923084Y12914D01*
X923644Y13539D01*
X923924Y14414D01*
X923737Y15289D01*
X923271Y16039D01*
X922431Y16539D01*
X921311Y16789D01*
X920657Y17289D01*
X920377Y18164D01*
X920564Y19039D01*
X921031Y19664D01*
X921684Y20039D01*
X922337D01*
X922991Y19789D01*
X923551Y19164D01*
G01X927504Y12539D02*
Y20039D01*
G01X931424D02*
Y12539D01*
G01Y16289D02*
X927504D01*
G01X938831Y12539D02*
X935097D01*
Y20039D01*
X938831D01*
G01X937337Y16414D02*
X935097D01*
G01X942411Y12539D02*
Y20039D01*
X944277D01*
X945024Y19664D01*
X945584Y19164D01*
X946051Y18414D01*
X946424Y17539D01*
X946517Y16289D01*
X946424Y15039D01*
X946051Y14164D01*
X945584Y13414D01*
X945024Y12914D01*
X944277Y12539D01*
X942411D01*
G01X957597D02*
Y20039D01*
X959837D01*
X960584Y19664D01*
X961144Y18789D01*
X961331Y17789D01*
X961144Y16789D01*
X960677Y16039D01*
X959837Y15664D01*
X957597D01*
G01X966964Y20039D02*
Y12539D01*
G01X964817Y20039D02*
X969111D01*
G01X972504Y12539D02*
Y20039D01*
G01X976424D02*
Y12539D01*
G01Y16289D02*
X972504D01*
G01X988344Y20039D02*
X990584D01*
G01X989464D02*
Y12539D01*
G01X988344D02*
X990584D01*
G01X995004Y13539D02*
X995751Y12914D01*
X996591Y12539D01*
X997337D01*
X998084Y12914D01*
X998644Y13539D01*
X998924Y14414D01*
X998737Y15289D01*
X998271Y16039D01*
X997431Y16539D01*
X996311Y16789D01*
X995657Y17289D01*
X995377Y18164D01*
X995564Y19039D01*
X996031Y19664D01*
X996684Y20039D01*
X997337D01*
X997991Y19789D01*
X998551Y19164D01*
G01X1011964Y12539D02*
Y20039D01*
X1010844Y18539D01*
G01Y12539D02*
X1013084D01*
G01X1019464Y12289D02*
X1019277Y12414D01*
Y12664D01*
X1019464Y12789D01*
X1019651Y12664D01*
Y12414D01*
X1019464Y12289D01*
G01X1026964Y12539D02*
Y20039D01*
X1025844Y18539D01*
G01Y12539D02*
X1028084D01*
G01X1032411Y13664D02*
X1032971Y13039D01*
X1033624Y12664D01*
X1034464Y12539D01*
X1035304Y12789D01*
X1035957Y13289D01*
X1036424Y14164D01*
X1036517Y15164D01*
X1036331Y16164D01*
X1035864Y16789D01*
X1035211Y17289D01*
X1034557Y17414D01*
X1033904Y17289D01*
X1033064Y16789D01*
X1033344Y20039D01*
X1035864D01*
G01X1040937Y15039D02*
X1043177D01*
G01X1041964Y16664D02*
Y13414D01*
G01X1047784Y12289D02*
X1051144Y20039D01*
G01X1055751Y15039D02*
X1058177D01*
G01X1064464Y20039D02*
X1063717Y19789D01*
X1063157Y19164D01*
X1062784Y18414D01*
X1062504Y17414D01*
X1062411Y16289D01*
X1062504Y15164D01*
X1062784Y14164D01*
X1063157Y13414D01*
X1063717Y12789D01*
X1064464Y12539D01*
X1065211Y12789D01*
X1065771Y13414D01*
X1066144Y14164D01*
X1066424Y15164D01*
X1066517Y16289D01*
X1066424Y17414D01*
X1066144Y18414D01*
X1065771Y19164D01*
X1065211Y19789D01*
X1064464Y20039D01*
G01X1071964Y12289D02*
X1071777Y12414D01*
Y12664D01*
X1071964Y12789D01*
X1072151Y12664D01*
Y12414D01*
X1071964Y12289D01*
G01X1079464Y20039D02*
X1078717Y19789D01*
X1078157Y19164D01*
X1077784Y18414D01*
X1077504Y17414D01*
X1077411Y16289D01*
X1077504Y15164D01*
X1077784Y14164D01*
X1078157Y13414D01*
X1078717Y12789D01*
X1079464Y12539D01*
X1080211Y12789D01*
X1080771Y13414D01*
X1081144Y14164D01*
X1081424Y15164D01*
X1081517Y16289D01*
X1081424Y17414D01*
X1081144Y18414D01*
X1080771Y19164D01*
X1080211Y19789D01*
X1079464Y20039D01*
G01X1085191Y18789D02*
X1085751Y19539D01*
X1086404Y19914D01*
X1087151Y20039D01*
X1088084Y19789D01*
X1088737Y19164D01*
X1088924Y18414D01*
X1088831Y17664D01*
X1088457Y17039D01*
X1086591Y15789D01*
X1085751Y14914D01*
X1085191Y13664D01*
X1085004Y12539D01*
X1088924D01*
G01X1092411Y13664D02*
X1092971Y13039D01*
X1093624Y12664D01*
X1094464Y12539D01*
X1095304Y12789D01*
X1095957Y13289D01*
X1096424Y14164D01*
X1096517Y15164D01*
X1096331Y16164D01*
X1095864Y16789D01*
X1095211Y17289D01*
X1094557Y17414D01*
X1093904Y17289D01*
X1093064Y16789D01*
X1093344Y20039D01*
X1095864D01*
G01X1099537Y12539D02*
Y20039D01*
X1101964Y13789D01*
X1104391Y20039D01*
Y12539D01*
G01X1107037D02*
Y20039D01*
X1109464Y13789D01*
X1111891Y20039D01*
Y12539D01*
G01X1116964Y12289D02*
X1116777Y12414D01*
Y12664D01*
X1116964Y12789D01*
X1117151Y12664D01*
Y12414D01*
X1116964Y12289D01*
G01X737002Y29784D02*
Y37284D01*
X739242D01*
X739989Y36909D01*
X740549Y36034D01*
X740736Y35034D01*
X740549Y34034D01*
X740082Y33284D01*
X739242Y32909D01*
X737002D01*
G01X746369Y37284D02*
Y29784D01*
G01X744222Y37284D02*
X748516D01*
G01X751909Y29784D02*
Y37284D01*
G01X755829D02*
Y29784D01*
G01Y33534D02*
X751909D01*
G01X739283Y309006D02*
Y316506D01*
X741523D01*
X742270Y316131D01*
X742830Y315256D01*
X743017Y314256D01*
X742830Y313256D01*
X742363Y312506D01*
X741523Y312131D01*
X739283D01*
G01X748650Y316506D02*
Y309006D01*
G01X746503Y316506D02*
X750797D01*
G01X754190Y309006D02*
Y316506D01*
G01X758110D02*
Y309006D01*
G01Y312756D02*
X754190D01*
G01X741782Y464990D02*
X739074Y465300D01*
X736782Y465765D01*
X734699Y466385D01*
X732407Y467160D01*
X729282Y468400D01*
Y462200D01*
G01X741782Y479560D02*
X729282D01*
X738240Y473825D01*
Y481575D01*
G01X741782Y490100D02*
X741574Y491185D01*
X740949Y492425D01*
X739907Y493200D01*
X738449Y493510D01*
X736991Y493200D01*
X735740Y492270D01*
X735115Y490875D01*
Y489325D01*
X734699Y488395D01*
X733657Y487620D01*
X732199Y487310D01*
X730740Y487775D01*
X729699Y488860D01*
X729282Y490100D01*
X729699Y491340D01*
X730740Y492425D01*
X732199Y492890D01*
X733657Y492580D01*
X734699Y491805D01*
X735115Y490875D01*
Y489325D01*
X735740Y487930D01*
X736991Y487000D01*
X738449Y486690D01*
X739907Y487000D01*
X740949Y487775D01*
X741574Y489015D01*
X741782Y490100D01*
G01X729282Y502500D02*
X729699Y501260D01*
X730740Y500330D01*
X731990Y499710D01*
X733657Y499245D01*
X735532Y499090D01*
X737407Y499245D01*
X739074Y499710D01*
X740324Y500330D01*
X741365Y501260D01*
X741782Y502500D01*
X741365Y503740D01*
X740324Y504670D01*
X739074Y505290D01*
X737407Y505755D01*
X735532Y505910D01*
X733657Y505755D01*
X731990Y505290D01*
X730740Y504670D01*
X729699Y503740D01*
X729282Y502500D01*
G01X742199Y514900D02*
X741990Y514590D01*
X741574D01*
X741365Y514900D01*
X741574Y515210D01*
X741990D01*
X742199Y514900D01*
G01X739282Y523890D02*
X740741Y524820D01*
X741574Y526060D01*
X741782Y527455D01*
X741574Y528695D01*
X740532Y529935D01*
X739282Y530710D01*
X738032Y530865D01*
X736574Y530555D01*
X735532Y529470D01*
X735115Y528385D01*
Y526990D01*
G01Y528385D02*
X734490Y529315D01*
X733449Y530090D01*
X732199Y530400D01*
X730949Y530090D01*
X729907Y529315D01*
X729282Y527920D01*
X729490Y526525D01*
X730324Y525130D01*
G01X731365Y536755D02*
X730116Y537685D01*
X729490Y538770D01*
X729282Y540010D01*
X729699Y541560D01*
X730740Y542645D01*
X731990Y542955D01*
X733241Y542800D01*
X734282Y542180D01*
X736365Y539080D01*
X737824Y537685D01*
X739907Y536755D01*
X741782Y536445D01*
Y542955D01*
G01X766782Y490250D02*
X754282D01*
X756782Y488390D01*
G01X766782D02*
Y492110D01*
G01X765324Y500015D02*
X766365Y501100D01*
X766782Y502340D01*
X766365Y503580D01*
X765116Y504665D01*
X763240Y505440D01*
X761365Y505750D01*
X759074D01*
X757199Y505440D01*
X755532Y504665D01*
X754699Y503735D01*
X754282Y502650D01*
X754699Y501410D01*
X755532Y500480D01*
X756782Y499860D01*
X758449Y499550D01*
X759907Y499860D01*
X761365Y500635D01*
X762199Y501565D01*
X762407Y502650D01*
X761991Y503890D01*
X760949Y504820D01*
X759074Y505750D01*
G01X754282Y515050D02*
X754699Y513810D01*
X755740Y512880D01*
X756990Y512260D01*
X758657Y511795D01*
X760532Y511640D01*
X762407Y511795D01*
X764074Y512260D01*
X765324Y512880D01*
X766365Y513810D01*
X766782Y515050D01*
X766365Y516290D01*
X765324Y517220D01*
X764074Y517840D01*
X762407Y518305D01*
X760532Y518460D01*
X758657Y518305D01*
X756990Y517840D01*
X755740Y517220D01*
X754699Y516290D01*
X754282Y515050D01*
G01X850804Y640312D02*
Y647812D01*
X853138D01*
X853884Y647437D01*
X854351Y646937D01*
X854538Y645937D01*
X854351Y644937D01*
X853791Y644312D01*
X853138Y643937D01*
X850804D01*
G01X853138D02*
X854538Y640312D01*
G01X862038D02*
X858304D01*
Y647812D01*
X862038D01*
G01X860544Y644187D02*
X858304D01*
G01X869724Y647187D02*
X869164Y647562D01*
X868511Y647812D01*
X867764D01*
X866924Y647437D01*
X866271Y646812D01*
X865804Y646062D01*
X865431Y644812D01*
X865338Y643687D01*
X865524Y642562D01*
X865804Y641812D01*
X866364Y641062D01*
X867018Y640562D01*
X867671Y640312D01*
X868324D01*
X868978Y640562D01*
X869538Y640937D01*
X870004Y641437D01*
G01X875171Y640312D02*
X874424Y640437D01*
X873771Y640937D01*
X873211Y641687D01*
X872838Y642562D01*
X872651Y643562D01*
Y644562D01*
X872838Y645562D01*
X873211Y646437D01*
X873771Y647187D01*
X874424Y647687D01*
X875171Y647812D01*
X875918Y647687D01*
X876571Y647187D01*
X877131Y646437D01*
X877504Y645562D01*
X877691Y644562D01*
Y643562D01*
X877504Y642562D01*
X877131Y641687D01*
X876571Y640937D01*
X875918Y640437D01*
X875171Y640312D01*
G01X880244D02*
Y647812D01*
X882671Y641562D01*
X885098Y647812D01*
Y640312D01*
G01X887744D02*
Y647812D01*
X890171Y641562D01*
X892598Y647812D01*
Y640312D01*
G01X899538D02*
X895804D01*
Y647812D01*
X899538D01*
G01X898044Y644187D02*
X895804D01*
G01X903024Y640312D02*
Y647812D01*
X907318Y640312D01*
Y647812D01*
G01X910618Y640312D02*
Y647812D01*
X912484D01*
X913231Y647437D01*
X913791Y646937D01*
X914258Y646187D01*
X914631Y645312D01*
X914724Y644062D01*
X914631Y642812D01*
X914258Y641937D01*
X913791Y641187D01*
X913231Y640687D01*
X912484Y640312D01*
X910618D01*
G01X922038D02*
X918304D01*
Y647812D01*
X922038D01*
G01X920544Y644187D02*
X918304D01*
G01X925618Y640312D02*
Y647812D01*
X927484D01*
X928231Y647437D01*
X928791Y646937D01*
X929258Y646187D01*
X929631Y645312D01*
X929724Y644062D01*
X929631Y642812D01*
X929258Y641937D01*
X928791Y641187D01*
X928231Y640687D01*
X927484Y640312D01*
X925618D01*
G01X940618D02*
Y647812D01*
X942484D01*
X943231Y647437D01*
X943791Y646937D01*
X944258Y646187D01*
X944631Y645312D01*
X944724Y644062D01*
X944631Y642812D01*
X944258Y641937D01*
X943791Y641187D01*
X943231Y640687D01*
X942484Y640312D01*
X940618D01*
G01X948304D02*
Y647812D01*
X950638D01*
X951384Y647437D01*
X951851Y646937D01*
X952038Y645937D01*
X951851Y644937D01*
X951291Y644312D01*
X950638Y643937D01*
X948304D01*
G01X950638D02*
X952038Y640312D01*
G01X956551Y647812D02*
X958791D01*
G01X957671D02*
Y640312D01*
G01X956551D02*
X958791D01*
G01X963304Y647812D02*
Y640312D01*
X967038D01*
G01X970804Y647812D02*
Y640312D01*
X974538D01*
G01X985711Y641312D02*
X986458Y640687D01*
X987298Y640312D01*
X988044D01*
X988791Y640687D01*
X989351Y641312D01*
X989631Y642187D01*
X989444Y643062D01*
X988978Y643812D01*
X988138Y644312D01*
X987018Y644562D01*
X986364Y645062D01*
X986084Y645937D01*
X986271Y646812D01*
X986738Y647437D01*
X987391Y647812D01*
X988044D01*
X988698Y647562D01*
X989258Y646937D01*
G01X994051Y647812D02*
X996291D01*
G01X995171D02*
Y640312D01*
G01X994051D02*
X996291D01*
G01X1000898Y647812D02*
X1004444D01*
X1000898Y640312D01*
X1004444D01*
G01X1012038D02*
X1008304D01*
Y647812D01*
X1012038D01*
G01X1010544Y644187D02*
X1008304D01*
G01X1023398Y640312D02*
Y647812D01*
X1026944D01*
G01X1025638Y644187D02*
X1023398D01*
G01X1032671Y640312D02*
X1031924Y640437D01*
X1031271Y640937D01*
X1030711Y641687D01*
X1030338Y642562D01*
X1030151Y643562D01*
Y644562D01*
X1030338Y645562D01*
X1030711Y646437D01*
X1031271Y647187D01*
X1031924Y647687D01*
X1032671Y647812D01*
X1033418Y647687D01*
X1034071Y647187D01*
X1034631Y646437D01*
X1035004Y645562D01*
X1035191Y644562D01*
Y643562D01*
X1035004Y642562D01*
X1034631Y641687D01*
X1034071Y640937D01*
X1033418Y640437D01*
X1032671Y640312D01*
G01X1038304D02*
Y647812D01*
X1040638D01*
X1041384Y647437D01*
X1041851Y646937D01*
X1042038Y645937D01*
X1041851Y644937D01*
X1041291Y644312D01*
X1040638Y643937D01*
X1038304D01*
G01X1040638D02*
X1042038Y640312D01*
G01X1055171Y647812D02*
X1054424Y647562D01*
X1053864Y646937D01*
X1053491Y646187D01*
X1053211Y645187D01*
X1053118Y644062D01*
X1053211Y642937D01*
X1053491Y641937D01*
X1053864Y641187D01*
X1054424Y640562D01*
X1055171Y640312D01*
X1055918Y640562D01*
X1056478Y641187D01*
X1056851Y641937D01*
X1057131Y642937D01*
X1057224Y644062D01*
X1057131Y645187D01*
X1056851Y646187D01*
X1056478Y646937D01*
X1055918Y647562D01*
X1055171Y647812D01*
G01X1062671Y640062D02*
X1062484Y640187D01*
Y640437D01*
X1062671Y640562D01*
X1062858Y640437D01*
Y640187D01*
X1062671Y640062D01*
G01X1069984Y640312D02*
X1070171Y641937D01*
X1070451Y643312D01*
X1070824Y644562D01*
X1071291Y645937D01*
X1072038Y647812D01*
X1068304D01*
G01X1075618Y641437D02*
X1076178Y640812D01*
X1076831Y640437D01*
X1077671Y640312D01*
X1078511Y640562D01*
X1079164Y641062D01*
X1079631Y641937D01*
X1079724Y642937D01*
X1079538Y643937D01*
X1079071Y644562D01*
X1078418Y645062D01*
X1077764Y645187D01*
X1077111Y645062D01*
X1076271Y644562D01*
X1076551Y647812D01*
X1079071D01*
G01X1082744Y640312D02*
Y647812D01*
X1085171Y641562D01*
X1087598Y647812D01*
Y640312D01*
G01X1090244D02*
Y647812D01*
X1092671Y641562D01*
X1095098Y647812D01*
Y640312D01*
G01X1105898D02*
Y647812D01*
X1109444D01*
G01X1108138Y644187D02*
X1105898D01*
G01X1114051Y647812D02*
X1116291D01*
G01X1115171D02*
Y640312D01*
G01X1114051D02*
X1116291D01*
G01X1120524D02*
Y647812D01*
X1124818Y640312D01*
Y647812D01*
G01X1129051D02*
X1131291D01*
G01X1130171D02*
Y640312D01*
G01X1129051D02*
X1131291D01*
G01X1135711Y641312D02*
X1136458Y640687D01*
X1137298Y640312D01*
X1138044D01*
X1138791Y640687D01*
X1139351Y641312D01*
X1139631Y642187D01*
X1139444Y643062D01*
X1138978Y643812D01*
X1138138Y644312D01*
X1137018Y644562D01*
X1136364Y645062D01*
X1136084Y645937D01*
X1136271Y646812D01*
X1136738Y647437D01*
X1137391Y647812D01*
X1138044D01*
X1138698Y647562D01*
X1139258Y646937D01*
G01X1143211Y640312D02*
Y647812D01*
G01X1147131D02*
Y640312D01*
G01Y644062D02*
X1143211D01*
G01X1154538Y640312D02*
X1150804D01*
Y647812D01*
X1154538D01*
G01X1153044Y644187D02*
X1150804D01*
G01X1158118Y640312D02*
Y647812D01*
X1159984D01*
X1160731Y647437D01*
X1161291Y646937D01*
X1161758Y646187D01*
X1162131Y645312D01*
X1162224Y644062D01*
X1162131Y642812D01*
X1161758Y641937D01*
X1161291Y641187D01*
X1160731Y640687D01*
X1159984Y640312D01*
X1158118D01*
G01X1173304D02*
Y647812D01*
X1175544D01*
X1176291Y647437D01*
X1176851Y646562D01*
X1177038Y645562D01*
X1176851Y644562D01*
X1176384Y643812D01*
X1175544Y643437D01*
X1173304D01*
G01X1182671Y647812D02*
Y640312D01*
G01X1180524Y647812D02*
X1184818D01*
G01X1188211Y640312D02*
Y647812D01*
G01X1192131D02*
Y640312D01*
G01Y644062D02*
X1188211D01*
G01X1204051Y647812D02*
X1206291D01*
G01X1205171D02*
Y640312D01*
G01X1204051D02*
X1206291D01*
G01X1210711Y641312D02*
X1211458Y640687D01*
X1212298Y640312D01*
X1213044D01*
X1213791Y640687D01*
X1214351Y641312D01*
X1214631Y642187D01*
X1214444Y643062D01*
X1213978Y643812D01*
X1213138Y644312D01*
X1212018Y644562D01*
X1211364Y645062D01*
X1211084Y645937D01*
X1211271Y646812D01*
X1211738Y647437D01*
X1212391Y647812D01*
X1213044D01*
X1213698Y647562D01*
X1214258Y646937D01*
G01X1227671Y647812D02*
X1226924Y647562D01*
X1226364Y646937D01*
X1225991Y646187D01*
X1225711Y645187D01*
X1225618Y644062D01*
X1225711Y642937D01*
X1225991Y641937D01*
X1226364Y641187D01*
X1226924Y640562D01*
X1227671Y640312D01*
X1228418Y640562D01*
X1228978Y641187D01*
X1229351Y641937D01*
X1229631Y642937D01*
X1229724Y644062D01*
X1229631Y645187D01*
X1229351Y646187D01*
X1228978Y646937D01*
X1228418Y647562D01*
X1227671Y647812D01*
G01X1235171Y640062D02*
X1234984Y640187D01*
Y640437D01*
X1235171Y640562D01*
X1235358Y640437D01*
Y640187D01*
X1235171Y640062D01*
G01X1242671Y640312D02*
X1243324Y640437D01*
X1244071Y640812D01*
X1244538Y641437D01*
X1244724Y642312D01*
X1244538Y643187D01*
X1243978Y643937D01*
X1243138Y644312D01*
X1242204D01*
X1241644Y644562D01*
X1241178Y645187D01*
X1240991Y646062D01*
X1241271Y646937D01*
X1241924Y647562D01*
X1242671Y647812D01*
X1243418Y647562D01*
X1244071Y646937D01*
X1244351Y646062D01*
X1244164Y645187D01*
X1243698Y644562D01*
X1243138Y644312D01*
X1242204D01*
X1241364Y643937D01*
X1240804Y643187D01*
X1240618Y642312D01*
X1240804Y641437D01*
X1241271Y640812D01*
X1242018Y640437D01*
X1242671Y640312D01*
G01X1250171D02*
Y647812D01*
X1249051Y646312D01*
G01Y640312D02*
X1251291D01*
G01X1256458Y642812D02*
X1258884D01*
G01X1265171Y647812D02*
X1264424Y647562D01*
X1263864Y646937D01*
X1263491Y646187D01*
X1263211Y645187D01*
X1263118Y644062D01*
X1263211Y642937D01*
X1263491Y641937D01*
X1263864Y641187D01*
X1264424Y640562D01*
X1265171Y640312D01*
X1265918Y640562D01*
X1266478Y641187D01*
X1266851Y641937D01*
X1267131Y642937D01*
X1267224Y644062D01*
X1267131Y645187D01*
X1266851Y646187D01*
X1266478Y646937D01*
X1265918Y647562D01*
X1265171Y647812D01*
G01X1272671Y640062D02*
X1272484Y640187D01*
Y640437D01*
X1272671Y640562D01*
X1272858Y640437D01*
Y640187D01*
X1272671Y640062D01*
G01X1280171Y640312D02*
X1280824Y640437D01*
X1281571Y640812D01*
X1282038Y641437D01*
X1282224Y642312D01*
X1282038Y643187D01*
X1281478Y643937D01*
X1280638Y644312D01*
X1279704D01*
X1279144Y644562D01*
X1278678Y645187D01*
X1278491Y646062D01*
X1278771Y646937D01*
X1279424Y647562D01*
X1280171Y647812D01*
X1280918Y647562D01*
X1281571Y646937D01*
X1281851Y646062D01*
X1281664Y645187D01*
X1281198Y644562D01*
X1280638Y644312D01*
X1279704D01*
X1278864Y643937D01*
X1278304Y643187D01*
X1278118Y642312D01*
X1278304Y641437D01*
X1278771Y640812D01*
X1279518Y640437D01*
X1280171Y640312D01*
G01X1285898Y643437D02*
X1286551Y644312D01*
X1287111Y644812D01*
X1287858Y645062D01*
X1288511Y644812D01*
X1288978Y644312D01*
X1289351Y643562D01*
X1289444Y642687D01*
X1289351Y641937D01*
X1288978Y641187D01*
X1288418Y640562D01*
X1287764Y640312D01*
X1287018Y640562D01*
X1286364Y641312D01*
X1285991Y642437D01*
X1285898Y643687D01*
X1286084Y645312D01*
X1286364Y646187D01*
X1286831Y647062D01*
X1287484Y647687D01*
X1288138Y647812D01*
X1288791Y647562D01*
X1289258Y646937D01*
G01X1294704Y637812D02*
X1293771Y639062D01*
X1293304Y640312D01*
Y645312D01*
X1293771Y646562D01*
X1294704Y647812D01*
G01X1302671D02*
X1301924Y647562D01*
X1301364Y646937D01*
X1300991Y646187D01*
X1300711Y645187D01*
X1300618Y644062D01*
X1300711Y642937D01*
X1300991Y641937D01*
X1301364Y641187D01*
X1301924Y640562D01*
X1302671Y640312D01*
X1303418Y640562D01*
X1303978Y641187D01*
X1304351Y641937D01*
X1304631Y642937D01*
X1304724Y644062D01*
X1304631Y645187D01*
X1304351Y646187D01*
X1303978Y646937D01*
X1303418Y647562D01*
X1302671Y647812D01*
G01X1310171Y640062D02*
X1309984Y640187D01*
Y640437D01*
X1310171Y640562D01*
X1310358Y640437D01*
Y640187D01*
X1310171Y640062D01*
G01X1317671Y640312D02*
X1318324Y640437D01*
X1319071Y640812D01*
X1319538Y641437D01*
X1319724Y642312D01*
X1319538Y643187D01*
X1318978Y643937D01*
X1318138Y644312D01*
X1317204D01*
X1316644Y644562D01*
X1316178Y645187D01*
X1315991Y646062D01*
X1316271Y646937D01*
X1316924Y647562D01*
X1317671Y647812D01*
X1318418Y647562D01*
X1319071Y646937D01*
X1319351Y646062D01*
X1319164Y645187D01*
X1318698Y644562D01*
X1318138Y644312D01*
X1317204D01*
X1316364Y643937D01*
X1315804Y643187D01*
X1315618Y642312D01*
X1315804Y641437D01*
X1316271Y640812D01*
X1317018Y640437D01*
X1317671Y640312D01*
G01X1323118Y641437D02*
X1323678Y640812D01*
X1324331Y640437D01*
X1325171Y640312D01*
X1326011Y640562D01*
X1326664Y641062D01*
X1327131Y641937D01*
X1327224Y642937D01*
X1327038Y643937D01*
X1326571Y644562D01*
X1325918Y645062D01*
X1325264Y645187D01*
X1324611Y645062D01*
X1323771Y644562D01*
X1324051Y647812D01*
X1326571D01*
G01X1330244Y640312D02*
Y647812D01*
X1332671Y641562D01*
X1335098Y647812D01*
Y640312D01*
G01X1337744D02*
Y647812D01*
X1340171Y641562D01*
X1342598Y647812D01*
Y640312D01*
G01X1353118D02*
Y647812D01*
X1354984D01*
X1355731Y647437D01*
X1356291Y646937D01*
X1356758Y646187D01*
X1357131Y645312D01*
X1357224Y644062D01*
X1357131Y642812D01*
X1356758Y641937D01*
X1356291Y641187D01*
X1355731Y640687D01*
X1354984Y640312D01*
X1353118D01*
G01X1360804D02*
Y647812D01*
X1363138D01*
X1363884Y647437D01*
X1364351Y646937D01*
X1364538Y645937D01*
X1364351Y644937D01*
X1363791Y644312D01*
X1363138Y643937D01*
X1360804D01*
G01X1363138D02*
X1364538Y640312D01*
G01X1369051Y647812D02*
X1371291D01*
G01X1370171D02*
Y640312D01*
G01X1369051D02*
X1371291D01*
G01X1375804Y647812D02*
Y640312D01*
X1379538D01*
G01X1383304Y647812D02*
Y640312D01*
X1387038D01*
G01X1393138Y637812D02*
X1394071Y639062D01*
X1394538Y640312D01*
Y645312D01*
X1394071Y646562D01*
X1393138Y647812D01*
G01X1400171Y640062D02*
X1399984Y640187D01*
Y640437D01*
X1400171Y640562D01*
X1400358Y640437D01*
Y640187D01*
X1400171Y640062D01*
G01X910700Y1032250D02*
Y1044750D01*
X908840Y1042250D01*
G01Y1032250D02*
X912560D01*
G01X923100D02*
X924185Y1032458D01*
X925425Y1033083D01*
X926200Y1034125D01*
X926510Y1035583D01*
X926200Y1037041D01*
X925270Y1038292D01*
X923875Y1038917D01*
X922325D01*
X921395Y1039333D01*
X920620Y1040375D01*
X920310Y1041833D01*
X920775Y1043292D01*
X921860Y1044333D01*
X923100Y1044750D01*
X924340Y1044333D01*
X925425Y1043292D01*
X925890Y1041833D01*
X925580Y1040375D01*
X924805Y1039333D01*
X923875Y1038917D01*
X922325D01*
X920930Y1038292D01*
X920000Y1037041D01*
X919690Y1035583D01*
X920000Y1034125D01*
X920775Y1033083D01*
X922015Y1032458D01*
X923100Y1032250D01*
G01X935190D02*
X935500Y1034958D01*
X935965Y1037250D01*
X936585Y1039333D01*
X937360Y1041625D01*
X938600Y1044750D01*
X932400D01*
G01X949760Y1032250D02*
Y1044750D01*
X944025Y1035792D01*
X951775D01*
G01X960300Y1044750D02*
X959060Y1044333D01*
X958130Y1043292D01*
X957510Y1042042D01*
X957045Y1040375D01*
X956890Y1038500D01*
X957045Y1036625D01*
X957510Y1034958D01*
X958130Y1033708D01*
X959060Y1032667D01*
X960300Y1032250D01*
X961540Y1032667D01*
X962470Y1033708D01*
X963090Y1034958D01*
X963555Y1036625D01*
X963710Y1038500D01*
X963555Y1040375D01*
X963090Y1042042D01*
X962470Y1043292D01*
X961540Y1044333D01*
X960300Y1044750D01*
G01X972700Y1031833D02*
X972390Y1032042D01*
Y1032458D01*
X972700Y1032667D01*
X973010Y1032458D01*
Y1032042D01*
X972700Y1031833D01*
G01X985100Y1032250D02*
Y1044750D01*
X983240Y1042250D01*
G01Y1032250D02*
X986960D01*
G01X994555Y1037458D02*
X995640Y1038917D01*
X996570Y1039750D01*
X997810Y1040167D01*
X998895Y1039750D01*
X999670Y1038917D01*
X1000290Y1037667D01*
X1000445Y1036208D01*
X1000290Y1034958D01*
X999670Y1033708D01*
X998740Y1032667D01*
X997655Y1032250D01*
X996415Y1032667D01*
X995330Y1033916D01*
X994710Y1035792D01*
X994555Y1037875D01*
X994865Y1040583D01*
X995330Y1042042D01*
X996105Y1043500D01*
X997190Y1044542D01*
X998275Y1044750D01*
X999360Y1044333D01*
X1000135Y1043292D01*
G01X943710Y1007250D02*
Y1019750D01*
X937975Y1010792D01*
X945725D01*
G01X953940Y1007250D02*
X954250Y1009958D01*
X954715Y1012250D01*
X955335Y1014333D01*
X956110Y1016625D01*
X957350Y1019750D01*
X951150D01*
G01X963705Y1012458D02*
X964790Y1013917D01*
X965720Y1014750D01*
X966960Y1015167D01*
X968045Y1014750D01*
X968820Y1013917D01*
X969440Y1012667D01*
X969595Y1011208D01*
X969440Y1009958D01*
X968820Y1008708D01*
X967890Y1007667D01*
X966805Y1007250D01*
X965565Y1007667D01*
X964480Y1008916D01*
X963860Y1010792D01*
X963705Y1012875D01*
X964015Y1015583D01*
X964480Y1017042D01*
X965255Y1018500D01*
X966340Y1019542D01*
X967425Y1019750D01*
X968510Y1019333D01*
X969285Y1018292D01*
G01X976252Y29471D02*
Y36971D01*
X978492D01*
X979239Y36596D01*
X979799Y35721D01*
X979986Y34721D01*
X979799Y33721D01*
X979332Y32971D01*
X978492Y32596D01*
X976252D01*
G01X985619Y36971D02*
Y29471D01*
G01X983472Y36971D02*
X987766D01*
G01X991159Y29471D02*
Y36971D01*
G01X995079D02*
Y29471D01*
G01Y33221D02*
X991159D01*
G01X973952Y310611D02*
Y318111D01*
X976192D01*
X976939Y317736D01*
X977499Y316861D01*
X977686Y315861D01*
X977499Y314861D01*
X977032Y314111D01*
X976192Y313736D01*
X973952D01*
G01X983319Y318111D02*
Y310611D01*
G01X981172Y318111D02*
X985466D01*
G01X988859Y310611D02*
Y318111D01*
G01X992779D02*
Y310611D01*
G01Y314361D02*
X988859D01*
G01X976544Y466665D02*
X977585Y467750D01*
X978002Y468990D01*
X977585Y470230D01*
X976336Y471315D01*
X974460Y472090D01*
X972585Y472400D01*
X970294D01*
X968419Y472090D01*
X966752Y471315D01*
X965919Y470385D01*
X965502Y469300D01*
X965919Y468060D01*
X966752Y467130D01*
X968002Y466510D01*
X969669Y466200D01*
X971127Y466510D01*
X972585Y467285D01*
X973419Y468215D01*
X973627Y469300D01*
X973211Y470540D01*
X972169Y471470D01*
X970294Y472400D01*
G01X978002Y481700D02*
X977794Y482785D01*
X977169Y484025D01*
X976127Y484800D01*
X974669Y485110D01*
X973211Y484800D01*
X971960Y483870D01*
X971335Y482475D01*
Y480925D01*
X970919Y479995D01*
X969877Y479220D01*
X968419Y478910D01*
X966960Y479375D01*
X965919Y480460D01*
X965502Y481700D01*
X965919Y482940D01*
X966960Y484025D01*
X968419Y484490D01*
X969877Y484180D01*
X970919Y483405D01*
X971335Y482475D01*
Y480925D01*
X971960Y479530D01*
X973211Y478600D01*
X974669Y478290D01*
X976127Y478600D01*
X977169Y479375D01*
X977794Y480615D01*
X978002Y481700D01*
G01Y495960D02*
X965502D01*
X974460Y490225D01*
Y497975D01*
G01X967585Y503555D02*
X966336Y504485D01*
X965710Y505570D01*
X965502Y506810D01*
X965919Y508360D01*
X966960Y509445D01*
X968210Y509755D01*
X969461Y509600D01*
X970502Y508980D01*
X972585Y505880D01*
X974044Y504485D01*
X976127Y503555D01*
X978002Y503245D01*
Y509755D01*
G01X978419Y518900D02*
X978210Y518590D01*
X977794D01*
X977585Y518900D01*
X977794Y519210D01*
X978210D01*
X978419Y518900D01*
G01X976127Y527890D02*
X977169Y528820D01*
X977794Y529905D01*
X978002Y531300D01*
X977585Y532695D01*
X976752Y533780D01*
X975294Y534555D01*
X973627Y534710D01*
X971960Y534400D01*
X970919Y533625D01*
X970085Y532540D01*
X969877Y531455D01*
X970085Y530370D01*
X970919Y528975D01*
X965502Y529440D01*
Y533625D01*
G01X967585Y540755D02*
X966336Y541685D01*
X965710Y542770D01*
X965502Y544010D01*
X965919Y545560D01*
X966960Y546645D01*
X968210Y546955D01*
X969461Y546800D01*
X970502Y546180D01*
X972585Y543080D01*
X974044Y541685D01*
X976127Y540755D01*
X978002Y540445D01*
Y546955D01*
G01X992585Y491305D02*
X991336Y492235D01*
X990710Y493320D01*
X990502Y494560D01*
X990919Y496110D01*
X991960Y497195D01*
X993210Y497505D01*
X994461Y497350D01*
X995502Y496730D01*
X997585Y493630D01*
X999044Y492235D01*
X1001127Y491305D01*
X1003002Y490995D01*
Y497505D01*
G01X1001127Y503240D02*
X1002169Y504170D01*
X1002794Y505255D01*
X1003002Y506650D01*
X1002585Y508045D01*
X1001752Y509130D01*
X1000294Y509905D01*
X998627Y510060D01*
X996960Y509750D01*
X995919Y508975D01*
X995085Y507890D01*
X994877Y506805D01*
X995085Y505720D01*
X995919Y504325D01*
X990502Y504790D01*
Y508975D01*
G01Y519050D02*
X990919Y517810D01*
X991960Y516880D01*
X993210Y516260D01*
X994877Y515795D01*
X996752Y515640D01*
X998627Y515795D01*
X1000294Y516260D01*
X1001544Y516880D01*
X1002585Y517810D01*
X1003002Y519050D01*
X1002585Y520290D01*
X1001544Y521220D01*
X1000294Y521840D01*
X998627Y522305D01*
X996752Y522460D01*
X994877Y522305D01*
X993210Y521840D01*
X991960Y521220D01*
X990919Y520290D01*
X990502Y519050D01*
G01X987388Y839371D02*
X989255D01*
Y837121D01*
X988695Y836371D01*
X988041Y835871D01*
X987108Y835621D01*
X986175Y835871D01*
X985521Y836371D01*
X984961Y837121D01*
X984588Y837996D01*
X984401Y838996D01*
Y839871D01*
X984588Y840621D01*
X984961Y841496D01*
X985521Y842246D01*
X986081Y842746D01*
X986828Y843121D01*
X987481D01*
X988228Y842871D01*
X988788Y842371D01*
G01X994328Y835621D02*
X993581Y835746D01*
X992928Y836246D01*
X992368Y836996D01*
X991995Y837871D01*
X991808Y838871D01*
Y839871D01*
X991995Y840871D01*
X992368Y841746D01*
X992928Y842496D01*
X993581Y842996D01*
X994328Y843121D01*
X995075Y842996D01*
X995728Y842496D01*
X996288Y841746D01*
X996661Y840871D01*
X996848Y839871D01*
Y838871D01*
X996661Y837871D01*
X996288Y836996D01*
X995728Y836246D01*
X995075Y835746D01*
X994328Y835621D01*
G01X999961Y843121D02*
Y835621D01*
X1003695D01*
G01X1007275D02*
Y843121D01*
X1009141D01*
X1009888Y842746D01*
X1010448Y842246D01*
X1010915Y841496D01*
X1011288Y840621D01*
X1011381Y839371D01*
X1011288Y838121D01*
X1010915Y837246D01*
X1010448Y836496D01*
X1009888Y835996D01*
X1009141Y835621D01*
X1007275D01*
G01X1016828Y835371D02*
X1016641Y835496D01*
Y835746D01*
X1016828Y835871D01*
X1017015Y835746D01*
Y835496D01*
X1016828Y835371D01*
G01Y838746D02*
X1016641Y838871D01*
Y839121D01*
X1016828Y839246D01*
X1017015Y839121D01*
Y838871D01*
X1016828Y838746D01*
G01X1022461Y835621D02*
Y843121D01*
X1024795D01*
X1025541Y842746D01*
X1026008Y842246D01*
X1026195Y841246D01*
X1026008Y840246D01*
X1025448Y839621D01*
X1024795Y839246D01*
X1022461D01*
G01X1024795D02*
X1026195Y835621D01*
G01X1033695D02*
X1029961D01*
Y843121D01*
X1033695D01*
G01X1032201Y839496D02*
X1029961D01*
G01X1041381Y842496D02*
X1040821Y842871D01*
X1040168Y843121D01*
X1039421D01*
X1038581Y842746D01*
X1037928Y842121D01*
X1037461Y841371D01*
X1037088Y840121D01*
X1036995Y838996D01*
X1037181Y837871D01*
X1037461Y837121D01*
X1038021Y836371D01*
X1038675Y835871D01*
X1039328Y835621D01*
X1039981D01*
X1040635Y835871D01*
X1041195Y836246D01*
X1041661Y836746D01*
G01X1046828Y835621D02*
X1046081Y835746D01*
X1045428Y836246D01*
X1044868Y836996D01*
X1044495Y837871D01*
X1044308Y838871D01*
Y839871D01*
X1044495Y840871D01*
X1044868Y841746D01*
X1045428Y842496D01*
X1046081Y842996D01*
X1046828Y843121D01*
X1047575Y842996D01*
X1048228Y842496D01*
X1048788Y841746D01*
X1049161Y840871D01*
X1049348Y839871D01*
Y838871D01*
X1049161Y837871D01*
X1048788Y836996D01*
X1048228Y836246D01*
X1047575Y835746D01*
X1046828Y835621D01*
G01X1051901D02*
Y843121D01*
X1054328Y836871D01*
X1056755Y843121D01*
Y835621D01*
G01X1059401D02*
Y843121D01*
X1061828Y836871D01*
X1064255Y843121D01*
Y835621D01*
G01X1071195D02*
X1067461D01*
Y843121D01*
X1071195D01*
G01X1069701Y839496D02*
X1067461D01*
G01X1074681Y835621D02*
Y843121D01*
X1078975Y835621D01*
Y843121D01*
G01X1082275Y835621D02*
Y843121D01*
X1084141D01*
X1084888Y842746D01*
X1085448Y842246D01*
X1085915Y841496D01*
X1086288Y840621D01*
X1086381Y839371D01*
X1086288Y838121D01*
X1085915Y837246D01*
X1085448Y836496D01*
X1084888Y835996D01*
X1084141Y835621D01*
X1082275D01*
G01X1093695D02*
X1089961D01*
Y843121D01*
X1093695D01*
G01X1092201Y839496D02*
X1089961D01*
G01X1097275Y835621D02*
Y843121D01*
X1099141D01*
X1099888Y842746D01*
X1100448Y842246D01*
X1100915Y841496D01*
X1101288Y840621D01*
X1101381Y839371D01*
X1101288Y838121D01*
X1100915Y837246D01*
X1100448Y836496D01*
X1099888Y835996D01*
X1099141Y835621D01*
X1097275D01*
G01X1112275D02*
Y843121D01*
X1114141D01*
X1114888Y842746D01*
X1115448Y842246D01*
X1115915Y841496D01*
X1116288Y840621D01*
X1116381Y839371D01*
X1116288Y838121D01*
X1115915Y837246D01*
X1115448Y836496D01*
X1114888Y835996D01*
X1114141Y835621D01*
X1112275D01*
G01X1119961D02*
Y843121D01*
X1122295D01*
X1123041Y842746D01*
X1123508Y842246D01*
X1123695Y841246D01*
X1123508Y840246D01*
X1122948Y839621D01*
X1122295Y839246D01*
X1119961D01*
G01X1122295D02*
X1123695Y835621D01*
G01X1128208Y843121D02*
X1130448D01*
G01X1129328D02*
Y835621D01*
G01X1128208D02*
X1130448D01*
G01X1134961Y843121D02*
Y835621D01*
X1138695D01*
G01X1142461Y843121D02*
Y835621D01*
X1146195D01*
G01X1157368Y836621D02*
X1158115Y835996D01*
X1158955Y835621D01*
X1159701D01*
X1160448Y835996D01*
X1161008Y836621D01*
X1161288Y837496D01*
X1161101Y838371D01*
X1160635Y839121D01*
X1159795Y839621D01*
X1158675Y839871D01*
X1158021Y840371D01*
X1157741Y841246D01*
X1157928Y842121D01*
X1158395Y842746D01*
X1159048Y843121D01*
X1159701D01*
X1160355Y842871D01*
X1160915Y842246D01*
G01X1165708Y843121D02*
X1167948D01*
G01X1166828D02*
Y835621D01*
G01X1165708D02*
X1167948D01*
G01X1172555Y843121D02*
X1176101D01*
X1172555Y835621D01*
X1176101D01*
G01X1183695D02*
X1179961D01*
Y843121D01*
X1183695D01*
G01X1182201Y839496D02*
X1179961D01*
G01X1195055Y835621D02*
Y843121D01*
X1198601D01*
G01X1197295Y839496D02*
X1195055D01*
G01X1204328Y835621D02*
X1203581Y835746D01*
X1202928Y836246D01*
X1202368Y836996D01*
X1201995Y837871D01*
X1201808Y838871D01*
Y839871D01*
X1201995Y840871D01*
X1202368Y841746D01*
X1202928Y842496D01*
X1203581Y842996D01*
X1204328Y843121D01*
X1205075Y842996D01*
X1205728Y842496D01*
X1206288Y841746D01*
X1206661Y840871D01*
X1206848Y839871D01*
Y838871D01*
X1206661Y837871D01*
X1206288Y836996D01*
X1205728Y836246D01*
X1205075Y835746D01*
X1204328Y835621D01*
G01X1209961D02*
Y843121D01*
X1212295D01*
X1213041Y842746D01*
X1213508Y842246D01*
X1213695Y841246D01*
X1213508Y840246D01*
X1212948Y839621D01*
X1212295Y839246D01*
X1209961D01*
G01X1212295D02*
X1213695Y835621D01*
G01X1226828Y843121D02*
X1226081Y842871D01*
X1225521Y842246D01*
X1225148Y841496D01*
X1224868Y840496D01*
X1224775Y839371D01*
X1224868Y838246D01*
X1225148Y837246D01*
X1225521Y836496D01*
X1226081Y835871D01*
X1226828Y835621D01*
X1227575Y835871D01*
X1228135Y836496D01*
X1228508Y837246D01*
X1228788Y838246D01*
X1228881Y839371D01*
X1228788Y840496D01*
X1228508Y841496D01*
X1228135Y842246D01*
X1227575Y842871D01*
X1226828Y843121D01*
G01X1234328Y835371D02*
X1234141Y835496D01*
Y835746D01*
X1234328Y835871D01*
X1234515Y835746D01*
Y835496D01*
X1234328Y835371D01*
G01X1241641Y835621D02*
X1241828Y837246D01*
X1242108Y838621D01*
X1242481Y839871D01*
X1242948Y841246D01*
X1243695Y843121D01*
X1239961D01*
G01X1250448Y835621D02*
Y843121D01*
X1246995Y837746D01*
X1251661D01*
G01X1254775Y836746D02*
X1255335Y836121D01*
X1255988Y835746D01*
X1256828Y835621D01*
X1257668Y835871D01*
X1258321Y836371D01*
X1258788Y837246D01*
X1258881Y838246D01*
X1258695Y839246D01*
X1258228Y839871D01*
X1257575Y840371D01*
X1256921Y840496D01*
X1256268Y840371D01*
X1255428Y839871D01*
X1255708Y843121D01*
X1258228D01*
G01X1261901Y835621D02*
Y843121D01*
X1264328Y836871D01*
X1266755Y843121D01*
Y835621D01*
G01X1269401D02*
Y843121D01*
X1271828Y836871D01*
X1274255Y843121D01*
Y835621D01*
G01X1285055D02*
Y843121D01*
X1288601D01*
G01X1287295Y839496D02*
X1285055D01*
G01X1293208Y843121D02*
X1295448D01*
G01X1294328D02*
Y835621D01*
G01X1293208D02*
X1295448D01*
G01X1299681D02*
Y843121D01*
X1303975Y835621D01*
Y843121D01*
G01X1308208D02*
X1310448D01*
G01X1309328D02*
Y835621D01*
G01X1308208D02*
X1310448D01*
G01X1314868Y836621D02*
X1315615Y835996D01*
X1316455Y835621D01*
X1317201D01*
X1317948Y835996D01*
X1318508Y836621D01*
X1318788Y837496D01*
X1318601Y838371D01*
X1318135Y839121D01*
X1317295Y839621D01*
X1316175Y839871D01*
X1315521Y840371D01*
X1315241Y841246D01*
X1315428Y842121D01*
X1315895Y842746D01*
X1316548Y843121D01*
X1317201D01*
X1317855Y842871D01*
X1318415Y842246D01*
G01X1322368Y835621D02*
Y843121D01*
G01X1326288D02*
Y835621D01*
G01Y839371D02*
X1322368D01*
G01X1333695Y835621D02*
X1329961D01*
Y843121D01*
X1333695D01*
G01X1332201Y839496D02*
X1329961D01*
G01X1337275Y835621D02*
Y843121D01*
X1339141D01*
X1339888Y842746D01*
X1340448Y842246D01*
X1340915Y841496D01*
X1341288Y840621D01*
X1341381Y839371D01*
X1341288Y838121D01*
X1340915Y837246D01*
X1340448Y836496D01*
X1339888Y835996D01*
X1339141Y835621D01*
X1337275D01*
G01X1352461D02*
Y843121D01*
X1354701D01*
X1355448Y842746D01*
X1356008Y841871D01*
X1356195Y840871D01*
X1356008Y839871D01*
X1355541Y839121D01*
X1354701Y838746D01*
X1352461D01*
G01X1361828Y843121D02*
Y835621D01*
G01X1359681Y843121D02*
X1363975D01*
G01X1367368Y835621D02*
Y843121D01*
G01X1371288D02*
Y835621D01*
G01Y839371D02*
X1367368D01*
G01X1383208Y843121D02*
X1385448D01*
G01X1384328D02*
Y835621D01*
G01X1383208D02*
X1385448D01*
G01X1389868Y836621D02*
X1390615Y835996D01*
X1391455Y835621D01*
X1392201D01*
X1392948Y835996D01*
X1393508Y836621D01*
X1393788Y837496D01*
X1393601Y838371D01*
X1393135Y839121D01*
X1392295Y839621D01*
X1391175Y839871D01*
X1390521Y840371D01*
X1390241Y841246D01*
X1390428Y842121D01*
X1390895Y842746D01*
X1391548Y843121D01*
X1392201D01*
X1392855Y842871D01*
X1393415Y842246D01*
G01X1406828Y843121D02*
X1406081Y842871D01*
X1405521Y842246D01*
X1405148Y841496D01*
X1404868Y840496D01*
X1404775Y839371D01*
X1404868Y838246D01*
X1405148Y837246D01*
X1405521Y836496D01*
X1406081Y835871D01*
X1406828Y835621D01*
X1407575Y835871D01*
X1408135Y836496D01*
X1408508Y837246D01*
X1408788Y838246D01*
X1408881Y839371D01*
X1408788Y840496D01*
X1408508Y841496D01*
X1408135Y842246D01*
X1407575Y842871D01*
X1406828Y843121D01*
G01X1414328Y835371D02*
X1414141Y835496D01*
Y835746D01*
X1414328Y835871D01*
X1414515Y835746D01*
Y835496D01*
X1414328Y835371D01*
G01X1421828Y835621D02*
X1422481Y835746D01*
X1423228Y836121D01*
X1423695Y836746D01*
X1423881Y837621D01*
X1423695Y838496D01*
X1423135Y839246D01*
X1422295Y839621D01*
X1421361D01*
X1420801Y839871D01*
X1420335Y840496D01*
X1420148Y841371D01*
X1420428Y842246D01*
X1421081Y842871D01*
X1421828Y843121D01*
X1422575Y842871D01*
X1423228Y842246D01*
X1423508Y841371D01*
X1423321Y840496D01*
X1422855Y839871D01*
X1422295Y839621D01*
X1421361D01*
X1420521Y839246D01*
X1419961Y838496D01*
X1419775Y837621D01*
X1419961Y836746D01*
X1420428Y836121D01*
X1421175Y835746D01*
X1421828Y835621D01*
G01X1429328D02*
Y843121D01*
X1428208Y841621D01*
G01Y835621D02*
X1430448D01*
G01X1435615Y838121D02*
X1438041D01*
G01X1444328Y843121D02*
X1443581Y842871D01*
X1443021Y842246D01*
X1442648Y841496D01*
X1442368Y840496D01*
X1442275Y839371D01*
X1442368Y838246D01*
X1442648Y837246D01*
X1443021Y836496D01*
X1443581Y835871D01*
X1444328Y835621D01*
X1445075Y835871D01*
X1445635Y836496D01*
X1446008Y837246D01*
X1446288Y838246D01*
X1446381Y839371D01*
X1446288Y840496D01*
X1446008Y841496D01*
X1445635Y842246D01*
X1445075Y842871D01*
X1444328Y843121D01*
G01X1451828Y835371D02*
X1451641Y835496D01*
Y835746D01*
X1451828Y835871D01*
X1452015Y835746D01*
Y835496D01*
X1451828Y835371D01*
G01X1459328Y835621D02*
X1459981Y835746D01*
X1460728Y836121D01*
X1461195Y836746D01*
X1461381Y837621D01*
X1461195Y838496D01*
X1460635Y839246D01*
X1459795Y839621D01*
X1458861D01*
X1458301Y839871D01*
X1457835Y840496D01*
X1457648Y841371D01*
X1457928Y842246D01*
X1458581Y842871D01*
X1459328Y843121D01*
X1460075Y842871D01*
X1460728Y842246D01*
X1461008Y841371D01*
X1460821Y840496D01*
X1460355Y839871D01*
X1459795Y839621D01*
X1458861D01*
X1458021Y839246D01*
X1457461Y838496D01*
X1457275Y837621D01*
X1457461Y836746D01*
X1457928Y836121D01*
X1458675Y835746D01*
X1459328Y835621D01*
G01X1465055Y838746D02*
X1465708Y839621D01*
X1466268Y840121D01*
X1467015Y840371D01*
X1467668Y840121D01*
X1468135Y839621D01*
X1468508Y838871D01*
X1468601Y837996D01*
X1468508Y837246D01*
X1468135Y836496D01*
X1467575Y835871D01*
X1466921Y835621D01*
X1466175Y835871D01*
X1465521Y836621D01*
X1465148Y837746D01*
X1465055Y838996D01*
X1465241Y840621D01*
X1465521Y841496D01*
X1465988Y842371D01*
X1466641Y842996D01*
X1467295Y843121D01*
X1467948Y842871D01*
X1468415Y842246D01*
G01X1471901Y835621D02*
Y843121D01*
X1474328Y836871D01*
X1476755Y843121D01*
Y835621D01*
G01X1479401D02*
Y843121D01*
X1481828Y836871D01*
X1484255Y843121D01*
Y835621D01*
G01X1488861Y833121D02*
X1487928Y834371D01*
X1487461Y835621D01*
Y840621D01*
X1487928Y841871D01*
X1488861Y843121D01*
G01X1496828D02*
X1496081Y842871D01*
X1495521Y842246D01*
X1495148Y841496D01*
X1494868Y840496D01*
X1494775Y839371D01*
X1494868Y838246D01*
X1495148Y837246D01*
X1495521Y836496D01*
X1496081Y835871D01*
X1496828Y835621D01*
X1497575Y835871D01*
X1498135Y836496D01*
X1498508Y837246D01*
X1498788Y838246D01*
X1498881Y839371D01*
X1498788Y840496D01*
X1498508Y841496D01*
X1498135Y842246D01*
X1497575Y842871D01*
X1496828Y843121D01*
G01X1504328Y835371D02*
X1504141Y835496D01*
Y835746D01*
X1504328Y835871D01*
X1504515Y835746D01*
Y835496D01*
X1504328Y835371D01*
G01X1511828Y835621D02*
X1512481Y835746D01*
X1513228Y836121D01*
X1513695Y836746D01*
X1513881Y837621D01*
X1513695Y838496D01*
X1513135Y839246D01*
X1512295Y839621D01*
X1511361D01*
X1510801Y839871D01*
X1510335Y840496D01*
X1510148Y841371D01*
X1510428Y842246D01*
X1511081Y842871D01*
X1511828Y843121D01*
X1512575Y842871D01*
X1513228Y842246D01*
X1513508Y841371D01*
X1513321Y840496D01*
X1512855Y839871D01*
X1512295Y839621D01*
X1511361D01*
X1510521Y839246D01*
X1509961Y838496D01*
X1509775Y837621D01*
X1509961Y836746D01*
X1510428Y836121D01*
X1511175Y835746D01*
X1511828Y835621D01*
G01X1517275Y836746D02*
X1517835Y836121D01*
X1518488Y835746D01*
X1519328Y835621D01*
X1520168Y835871D01*
X1520821Y836371D01*
X1521288Y837246D01*
X1521381Y838246D01*
X1521195Y839246D01*
X1520728Y839871D01*
X1520075Y840371D01*
X1519421Y840496D01*
X1518768Y840371D01*
X1517928Y839871D01*
X1518208Y843121D01*
X1520728D01*
G01X1524401Y835621D02*
Y843121D01*
X1526828Y836871D01*
X1529255Y843121D01*
Y835621D01*
G01X1531901D02*
Y843121D01*
X1534328Y836871D01*
X1536755Y843121D01*
Y835621D01*
G01X1547275D02*
Y843121D01*
X1549141D01*
X1549888Y842746D01*
X1550448Y842246D01*
X1550915Y841496D01*
X1551288Y840621D01*
X1551381Y839371D01*
X1551288Y838121D01*
X1550915Y837246D01*
X1550448Y836496D01*
X1549888Y835996D01*
X1549141Y835621D01*
X1547275D01*
G01X1554961D02*
Y843121D01*
X1557295D01*
X1558041Y842746D01*
X1558508Y842246D01*
X1558695Y841246D01*
X1558508Y840246D01*
X1557948Y839621D01*
X1557295Y839246D01*
X1554961D01*
G01X1557295D02*
X1558695Y835621D01*
G01X1563208Y843121D02*
X1565448D01*
G01X1564328D02*
Y835621D01*
G01X1563208D02*
X1565448D01*
G01X1569961Y843121D02*
Y835621D01*
X1573695D01*
G01X1577461Y843121D02*
Y835621D01*
X1581195D01*
G01X1587295Y833121D02*
X1588228Y834371D01*
X1588695Y835621D01*
Y840621D01*
X1588228Y841871D01*
X1587295Y843121D01*
G01X1594328Y835371D02*
X1594141Y835496D01*
Y835746D01*
X1594328Y835871D01*
X1594515Y835746D01*
Y835496D01*
X1594328Y835371D01*
G01X986208Y856521D02*
X988448D01*
G01X987328D02*
Y849021D01*
G01X986208D02*
X988448D01*
G01X992401D02*
Y856521D01*
X994828Y850271D01*
X997255Y856521D01*
Y849021D01*
G01X999901D02*
Y856521D01*
X1002328Y850271D01*
X1004755Y856521D01*
Y849021D01*
G01X1011695D02*
X1007961D01*
Y856521D01*
X1011695D01*
G01X1010201Y852896D02*
X1007961D01*
G01X1015461Y849021D02*
Y856521D01*
X1017795D01*
X1018541Y856146D01*
X1019008Y855646D01*
X1019195Y854646D01*
X1019008Y853646D01*
X1018448Y853021D01*
X1017795Y852646D01*
X1015461D01*
G01X1017795D02*
X1019195Y849021D01*
G01X1022868Y850021D02*
X1023615Y849396D01*
X1024455Y849021D01*
X1025201D01*
X1025948Y849396D01*
X1026508Y850021D01*
X1026788Y850896D01*
X1026601Y851771D01*
X1026135Y852521D01*
X1025295Y853021D01*
X1024175Y853271D01*
X1023521Y853771D01*
X1023241Y854646D01*
X1023428Y855521D01*
X1023895Y856146D01*
X1024548Y856521D01*
X1025201D01*
X1025855Y856271D01*
X1026415Y855646D01*
G01X1031208Y856521D02*
X1033448D01*
G01X1032328D02*
Y849021D01*
G01X1031208D02*
X1033448D01*
G01X1039828D02*
X1039081Y849146D01*
X1038428Y849646D01*
X1037868Y850396D01*
X1037495Y851271D01*
X1037308Y852271D01*
Y853271D01*
X1037495Y854271D01*
X1037868Y855146D01*
X1038428Y855896D01*
X1039081Y856396D01*
X1039828Y856521D01*
X1040575Y856396D01*
X1041228Y855896D01*
X1041788Y855146D01*
X1042161Y854271D01*
X1042348Y853271D01*
Y852271D01*
X1042161Y851271D01*
X1041788Y850396D01*
X1041228Y849646D01*
X1040575Y849146D01*
X1039828Y849021D01*
G01X1045181D02*
Y856521D01*
X1049475Y849021D01*
Y856521D01*
G01X1062328D02*
Y849021D01*
G01X1060181Y856521D02*
X1064475D01*
G01X1068708D02*
X1070948D01*
G01X1069828D02*
Y849021D01*
G01X1068708D02*
X1070948D01*
G01X1075181D02*
Y856521D01*
X1079475Y849021D01*
Y856521D01*
G01X1083148Y848771D02*
X1086508Y856521D01*
G01X1091208D02*
X1093448D01*
G01X1092328D02*
Y849021D01*
G01X1091208D02*
X1093448D01*
G01X1097401D02*
Y856521D01*
X1099828Y850271D01*
X1102255Y856521D01*
Y849021D01*
G01X1104901D02*
Y856521D01*
X1107328Y850271D01*
X1109755Y856521D01*
Y849021D01*
G01X1116695D02*
X1112961D01*
Y856521D01*
X1116695D01*
G01X1115201Y852896D02*
X1112961D01*
G01X1120461Y849021D02*
Y856521D01*
X1122795D01*
X1123541Y856146D01*
X1124008Y855646D01*
X1124195Y854646D01*
X1124008Y853646D01*
X1123448Y853021D01*
X1122795Y852646D01*
X1120461D01*
G01X1122795D02*
X1124195Y849021D01*
G01X1127868Y850021D02*
X1128615Y849396D01*
X1129455Y849021D01*
X1130201D01*
X1130948Y849396D01*
X1131508Y850021D01*
X1131788Y850896D01*
X1131601Y851771D01*
X1131135Y852521D01*
X1130295Y853021D01*
X1129175Y853271D01*
X1128521Y853771D01*
X1128241Y854646D01*
X1128428Y855521D01*
X1128895Y856146D01*
X1129548Y856521D01*
X1130201D01*
X1130855Y856271D01*
X1131415Y855646D01*
G01X1136208Y856521D02*
X1138448D01*
G01X1137328D02*
Y849021D01*
G01X1136208D02*
X1138448D01*
G01X1144828D02*
X1144081Y849146D01*
X1143428Y849646D01*
X1142868Y850396D01*
X1142495Y851271D01*
X1142308Y852271D01*
Y853271D01*
X1142495Y854271D01*
X1142868Y855146D01*
X1143428Y855896D01*
X1144081Y856396D01*
X1144828Y856521D01*
X1145575Y856396D01*
X1146228Y855896D01*
X1146788Y855146D01*
X1147161Y854271D01*
X1147348Y853271D01*
Y852271D01*
X1147161Y851271D01*
X1146788Y850396D01*
X1146228Y849646D01*
X1145575Y849146D01*
X1144828Y849021D01*
G01X1150181D02*
Y856521D01*
X1154475Y849021D01*
Y856521D01*
G01X1165368Y850021D02*
X1166115Y849396D01*
X1166955Y849021D01*
X1167701D01*
X1168448Y849396D01*
X1169008Y850021D01*
X1169288Y850896D01*
X1169101Y851771D01*
X1168635Y852521D01*
X1167795Y853021D01*
X1166675Y853271D01*
X1166021Y853771D01*
X1165741Y854646D01*
X1165928Y855521D01*
X1166395Y856146D01*
X1167048Y856521D01*
X1167701D01*
X1168355Y856271D01*
X1168915Y855646D01*
G01X1173708Y856521D02*
X1175948D01*
G01X1174828D02*
Y849021D01*
G01X1173708D02*
X1175948D01*
G01X1180461Y856521D02*
Y849021D01*
X1184195D01*
G01X1187495Y856521D02*
X1189828Y849021D01*
X1192161Y856521D01*
G01X1199195Y849021D02*
X1195461D01*
Y856521D01*
X1199195D01*
G01X1197701Y852896D02*
X1195461D01*
G01X1202961Y849021D02*
Y856521D01*
X1205295D01*
X1206041Y856146D01*
X1206508Y855646D01*
X1206695Y854646D01*
X1206508Y853646D01*
X1205948Y853021D01*
X1205295Y852646D01*
X1202961D01*
G01X1205295D02*
X1206695Y849021D01*
G01X1210648Y848771D02*
X1214008Y856521D01*
G01X1221881Y855896D02*
X1221321Y856271D01*
X1220668Y856521D01*
X1219921D01*
X1219081Y856146D01*
X1218428Y855521D01*
X1217961Y854771D01*
X1217588Y853521D01*
X1217495Y852396D01*
X1217681Y851271D01*
X1217961Y850521D01*
X1218521Y849771D01*
X1219175Y849271D01*
X1219828Y849021D01*
X1220481D01*
X1221135Y849271D01*
X1221695Y849646D01*
X1222161Y850146D01*
G01X1227328Y849021D02*
X1226581Y849146D01*
X1225928Y849646D01*
X1225368Y850396D01*
X1224995Y851271D01*
X1224808Y852271D01*
Y853271D01*
X1224995Y854271D01*
X1225368Y855146D01*
X1225928Y855896D01*
X1226581Y856396D01*
X1227328Y856521D01*
X1228075Y856396D01*
X1228728Y855896D01*
X1229288Y855146D01*
X1229661Y854271D01*
X1229848Y853271D01*
Y852271D01*
X1229661Y851271D01*
X1229288Y850396D01*
X1228728Y849646D01*
X1228075Y849146D01*
X1227328Y849021D01*
G01X1232961D02*
Y856521D01*
X1235201D01*
X1235948Y856146D01*
X1236508Y855271D01*
X1236695Y854271D01*
X1236508Y853271D01*
X1236041Y852521D01*
X1235201Y852146D01*
X1232961D01*
G01X1240461Y849021D02*
Y856521D01*
X1242701D01*
X1243448Y856146D01*
X1244008Y855271D01*
X1244195Y854271D01*
X1244008Y853271D01*
X1243541Y852521D01*
X1242701Y852146D01*
X1240461D01*
G01X1251695Y849021D02*
X1247961D01*
Y856521D01*
X1251695D01*
G01X1250201Y852896D02*
X1247961D01*
G01X1255461Y849021D02*
Y856521D01*
X1257795D01*
X1258541Y856146D01*
X1259008Y855646D01*
X1259195Y854646D01*
X1259008Y853646D01*
X1258448Y853021D01*
X1257795Y852646D01*
X1255461D01*
G01X1257795D02*
X1259195Y849021D01*
G01X1264828Y848771D02*
X1264641Y848896D01*
Y849146D01*
X1264828Y849271D01*
X1265015Y849146D01*
Y848896D01*
X1264828Y848771D01*
G01Y852146D02*
X1264641Y852271D01*
Y852521D01*
X1264828Y852646D01*
X1265015Y852521D01*
Y852271D01*
X1264828Y852146D01*
G01X1270461Y849021D02*
Y856521D01*
X1272795D01*
X1273541Y856146D01*
X1274008Y855646D01*
X1274195Y854646D01*
X1274008Y853646D01*
X1273448Y853021D01*
X1272795Y852646D01*
X1270461D01*
G01X1272795D02*
X1274195Y849021D01*
G01X1281695D02*
X1277961D01*
Y856521D01*
X1281695D01*
G01X1280201Y852896D02*
X1277961D01*
G01X1289381Y855896D02*
X1288821Y856271D01*
X1288168Y856521D01*
X1287421D01*
X1286581Y856146D01*
X1285928Y855521D01*
X1285461Y854771D01*
X1285088Y853521D01*
X1284995Y852396D01*
X1285181Y851271D01*
X1285461Y850521D01*
X1286021Y849771D01*
X1286675Y849271D01*
X1287328Y849021D01*
X1287981D01*
X1288635Y849271D01*
X1289195Y849646D01*
X1289661Y850146D01*
G01X1294828Y849021D02*
X1294081Y849146D01*
X1293428Y849646D01*
X1292868Y850396D01*
X1292495Y851271D01*
X1292308Y852271D01*
Y853271D01*
X1292495Y854271D01*
X1292868Y855146D01*
X1293428Y855896D01*
X1294081Y856396D01*
X1294828Y856521D01*
X1295575Y856396D01*
X1296228Y855896D01*
X1296788Y855146D01*
X1297161Y854271D01*
X1297348Y853271D01*
Y852271D01*
X1297161Y851271D01*
X1296788Y850396D01*
X1296228Y849646D01*
X1295575Y849146D01*
X1294828Y849021D01*
G01X1299901D02*
Y856521D01*
X1302328Y850271D01*
X1304755Y856521D01*
Y849021D01*
G01X1307401D02*
Y856521D01*
X1309828Y850271D01*
X1312255Y856521D01*
Y849021D01*
G01X1319195D02*
X1315461D01*
Y856521D01*
X1319195D01*
G01X1317701Y852896D02*
X1315461D01*
G01X1322681Y849021D02*
Y856521D01*
X1326975Y849021D01*
Y856521D01*
G01X1330275Y849021D02*
Y856521D01*
X1332141D01*
X1332888Y856146D01*
X1333448Y855646D01*
X1333915Y854896D01*
X1334288Y854021D01*
X1334381Y852771D01*
X1334288Y851521D01*
X1333915Y850646D01*
X1333448Y849896D01*
X1332888Y849396D01*
X1332141Y849021D01*
X1330275D01*
G01X1341695D02*
X1337961D01*
Y856521D01*
X1341695D01*
G01X1340201Y852896D02*
X1337961D01*
G01X1345275Y849021D02*
Y856521D01*
X1347141D01*
X1347888Y856146D01*
X1348448Y855646D01*
X1348915Y854896D01*
X1349288Y854021D01*
X1349381Y852771D01*
X1349288Y851521D01*
X1348915Y850646D01*
X1348448Y849896D01*
X1347888Y849396D01*
X1347141Y849021D01*
X1345275D01*
G01X1360275D02*
Y856521D01*
X1362141D01*
X1362888Y856146D01*
X1363448Y855646D01*
X1363915Y854896D01*
X1364288Y854021D01*
X1364381Y852771D01*
X1364288Y851521D01*
X1363915Y850646D01*
X1363448Y849896D01*
X1362888Y849396D01*
X1362141Y849021D01*
X1360275D01*
G01X1367961D02*
Y856521D01*
X1370295D01*
X1371041Y856146D01*
X1371508Y855646D01*
X1371695Y854646D01*
X1371508Y853646D01*
X1370948Y853021D01*
X1370295Y852646D01*
X1367961D01*
G01X1370295D02*
X1371695Y849021D01*
G01X1376208Y856521D02*
X1378448D01*
G01X1377328D02*
Y849021D01*
G01X1376208D02*
X1378448D01*
G01X1382961Y856521D02*
Y849021D01*
X1386695D01*
G01X1390461Y856521D02*
Y849021D01*
X1394195D01*
G01X1405368Y850021D02*
X1406115Y849396D01*
X1406955Y849021D01*
X1407701D01*
X1408448Y849396D01*
X1409008Y850021D01*
X1409288Y850896D01*
X1409101Y851771D01*
X1408635Y852521D01*
X1407795Y853021D01*
X1406675Y853271D01*
X1406021Y853771D01*
X1405741Y854646D01*
X1405928Y855521D01*
X1406395Y856146D01*
X1407048Y856521D01*
X1407701D01*
X1408355Y856271D01*
X1408915Y855646D01*
G01X1413708Y856521D02*
X1415948D01*
G01X1414828D02*
Y849021D01*
G01X1413708D02*
X1415948D01*
G01X1420555Y856521D02*
X1424101D01*
X1420555Y849021D01*
X1424101D01*
G01X1431695D02*
X1427961D01*
Y856521D01*
X1431695D01*
G01X1430201Y852896D02*
X1427961D01*
G01X1443055Y849021D02*
Y856521D01*
X1446601D01*
G01X1445295Y852896D02*
X1443055D01*
G01X1452328Y849021D02*
X1451581Y849146D01*
X1450928Y849646D01*
X1450368Y850396D01*
X1449995Y851271D01*
X1449808Y852271D01*
Y853271D01*
X1449995Y854271D01*
X1450368Y855146D01*
X1450928Y855896D01*
X1451581Y856396D01*
X1452328Y856521D01*
X1453075Y856396D01*
X1453728Y855896D01*
X1454288Y855146D01*
X1454661Y854271D01*
X1454848Y853271D01*
Y852271D01*
X1454661Y851271D01*
X1454288Y850396D01*
X1453728Y849646D01*
X1453075Y849146D01*
X1452328Y849021D01*
G01X1457961D02*
Y856521D01*
X1460295D01*
X1461041Y856146D01*
X1461508Y855646D01*
X1461695Y854646D01*
X1461508Y853646D01*
X1460948Y853021D01*
X1460295Y852646D01*
X1457961D01*
G01X1460295D02*
X1461695Y849021D01*
G01X1474828Y856521D02*
X1474081Y856271D01*
X1473521Y855646D01*
X1473148Y854896D01*
X1472868Y853896D01*
X1472775Y852771D01*
X1472868Y851646D01*
X1473148Y850646D01*
X1473521Y849896D01*
X1474081Y849271D01*
X1474828Y849021D01*
X1475575Y849271D01*
X1476135Y849896D01*
X1476508Y850646D01*
X1476788Y851646D01*
X1476881Y852771D01*
X1476788Y853896D01*
X1476508Y854896D01*
X1476135Y855646D01*
X1475575Y856271D01*
X1474828Y856521D01*
G01X1482328Y848771D02*
X1482141Y848896D01*
Y849146D01*
X1482328Y849271D01*
X1482515Y849146D01*
Y848896D01*
X1482328Y848771D01*
G01X1489641Y849021D02*
X1489828Y850646D01*
X1490108Y852021D01*
X1490481Y853271D01*
X1490948Y854646D01*
X1491695Y856521D01*
X1487961D01*
G01X1495275Y850146D02*
X1495835Y849521D01*
X1496488Y849146D01*
X1497328Y849021D01*
X1498168Y849271D01*
X1498821Y849771D01*
X1499288Y850646D01*
X1499381Y851646D01*
X1499195Y852646D01*
X1498728Y853271D01*
X1498075Y853771D01*
X1497421Y853896D01*
X1496768Y853771D01*
X1495928Y853271D01*
X1496208Y856521D01*
X1498728D01*
G01X1502401Y849021D02*
Y856521D01*
X1504828Y850271D01*
X1507255Y856521D01*
Y849021D01*
G01X1509901D02*
Y856521D01*
X1512328Y850271D01*
X1514755Y856521D01*
Y849021D01*
G01X1525555D02*
Y856521D01*
X1529101D01*
G01X1527795Y852896D02*
X1525555D01*
G01X1533708Y856521D02*
X1535948D01*
G01X1534828D02*
Y849021D01*
G01X1533708D02*
X1535948D01*
G01X1540181D02*
Y856521D01*
X1544475Y849021D01*
Y856521D01*
G01X1548708D02*
X1550948D01*
G01X1549828D02*
Y849021D01*
G01X1548708D02*
X1550948D01*
G01X1555368Y850021D02*
X1556115Y849396D01*
X1556955Y849021D01*
X1557701D01*
X1558448Y849396D01*
X1559008Y850021D01*
X1559288Y850896D01*
X1559101Y851771D01*
X1558635Y852521D01*
X1557795Y853021D01*
X1556675Y853271D01*
X1556021Y853771D01*
X1555741Y854646D01*
X1555928Y855521D01*
X1556395Y856146D01*
X1557048Y856521D01*
X1557701D01*
X1558355Y856271D01*
X1558915Y855646D01*
G01X1562868Y849021D02*
Y856521D01*
G01X1566788D02*
Y849021D01*
G01Y852771D02*
X1562868D01*
G01X1574195Y849021D02*
X1570461D01*
Y856521D01*
X1574195D01*
G01X1572701Y852896D02*
X1570461D01*
G01X1577775Y849021D02*
Y856521D01*
X1579641D01*
X1580388Y856146D01*
X1580948Y855646D01*
X1581415Y854896D01*
X1581788Y854021D01*
X1581881Y852771D01*
X1581788Y851521D01*
X1581415Y850646D01*
X1580948Y849896D01*
X1580388Y849396D01*
X1579641Y849021D01*
X1577775D01*
G01X1592961D02*
Y856521D01*
X1595201D01*
X1595948Y856146D01*
X1596508Y855271D01*
X1596695Y854271D01*
X1596508Y853271D01*
X1596041Y852521D01*
X1595201Y852146D01*
X1592961D01*
G01X1602328Y856521D02*
Y849021D01*
G01X1600181Y856521D02*
X1604475D01*
G01X1607868Y849021D02*
Y856521D01*
G01X1611788D02*
Y849021D01*
G01Y852771D02*
X1607868D01*
G01X1623708Y856521D02*
X1625948D01*
G01X1624828D02*
Y849021D01*
G01X1623708D02*
X1625948D01*
G01X1630368Y850021D02*
X1631115Y849396D01*
X1631955Y849021D01*
X1632701D01*
X1633448Y849396D01*
X1634008Y850021D01*
X1634288Y850896D01*
X1634101Y851771D01*
X1633635Y852521D01*
X1632795Y853021D01*
X1631675Y853271D01*
X1631021Y853771D01*
X1630741Y854646D01*
X1630928Y855521D01*
X1631395Y856146D01*
X1632048Y856521D01*
X1632701D01*
X1633355Y856271D01*
X1633915Y855646D01*
G01X1647328Y856521D02*
X1646581Y856271D01*
X1646021Y855646D01*
X1645648Y854896D01*
X1645368Y853896D01*
X1645275Y852771D01*
X1645368Y851646D01*
X1645648Y850646D01*
X1646021Y849896D01*
X1646581Y849271D01*
X1647328Y849021D01*
X1648075Y849271D01*
X1648635Y849896D01*
X1649008Y850646D01*
X1649288Y851646D01*
X1649381Y852771D01*
X1649288Y853896D01*
X1649008Y854896D01*
X1648635Y855646D01*
X1648075Y856271D01*
X1647328Y856521D01*
G01X1654828Y848771D02*
X1654641Y848896D01*
Y849146D01*
X1654828Y849271D01*
X1655015Y849146D01*
Y848896D01*
X1654828Y848771D01*
G01X1662328Y849021D02*
X1662981Y849146D01*
X1663728Y849521D01*
X1664195Y850146D01*
X1664381Y851021D01*
X1664195Y851896D01*
X1663635Y852646D01*
X1662795Y853021D01*
X1661861D01*
X1661301Y853271D01*
X1660835Y853896D01*
X1660648Y854771D01*
X1660928Y855646D01*
X1661581Y856271D01*
X1662328Y856521D01*
X1663075Y856271D01*
X1663728Y855646D01*
X1664008Y854771D01*
X1663821Y853896D01*
X1663355Y853271D01*
X1662795Y853021D01*
X1661861D01*
X1661021Y852646D01*
X1660461Y851896D01*
X1660275Y851021D01*
X1660461Y850146D01*
X1660928Y849521D01*
X1661675Y849146D01*
X1662328Y849021D01*
G01X1669828D02*
Y856521D01*
X1668708Y855021D01*
G01Y849021D02*
X1670948D01*
G01X1676115Y851521D02*
X1678541D01*
G01X1684828Y856521D02*
X1684081Y856271D01*
X1683521Y855646D01*
X1683148Y854896D01*
X1682868Y853896D01*
X1682775Y852771D01*
X1682868Y851646D01*
X1683148Y850646D01*
X1683521Y849896D01*
X1684081Y849271D01*
X1684828Y849021D01*
X1685575Y849271D01*
X1686135Y849896D01*
X1686508Y850646D01*
X1686788Y851646D01*
X1686881Y852771D01*
X1686788Y853896D01*
X1686508Y854896D01*
X1686135Y855646D01*
X1685575Y856271D01*
X1684828Y856521D01*
G01X1692328Y848771D02*
X1692141Y848896D01*
Y849146D01*
X1692328Y849271D01*
X1692515Y849146D01*
Y848896D01*
X1692328Y848771D01*
G01X1699828Y849021D02*
X1700481Y849146D01*
X1701228Y849521D01*
X1701695Y850146D01*
X1701881Y851021D01*
X1701695Y851896D01*
X1701135Y852646D01*
X1700295Y853021D01*
X1699361D01*
X1698801Y853271D01*
X1698335Y853896D01*
X1698148Y854771D01*
X1698428Y855646D01*
X1699081Y856271D01*
X1699828Y856521D01*
X1700575Y856271D01*
X1701228Y855646D01*
X1701508Y854771D01*
X1701321Y853896D01*
X1700855Y853271D01*
X1700295Y853021D01*
X1699361D01*
X1698521Y852646D01*
X1697961Y851896D01*
X1697775Y851021D01*
X1697961Y850146D01*
X1698428Y849521D01*
X1699175Y849146D01*
X1699828Y849021D01*
G01X1705555Y852146D02*
X1706208Y853021D01*
X1706768Y853521D01*
X1707515Y853771D01*
X1708168Y853521D01*
X1708635Y853021D01*
X1709008Y852271D01*
X1709101Y851396D01*
X1709008Y850646D01*
X1708635Y849896D01*
X1708075Y849271D01*
X1707421Y849021D01*
X1706675Y849271D01*
X1706021Y850021D01*
X1705648Y851146D01*
X1705555Y852396D01*
X1705741Y854021D01*
X1706021Y854896D01*
X1706488Y855771D01*
X1707141Y856396D01*
X1707795Y856521D01*
X1708448Y856271D01*
X1708915Y855646D01*
G01X1712401Y849021D02*
Y856521D01*
X1714828Y850271D01*
X1717255Y856521D01*
Y849021D01*
G01X1719901D02*
Y856521D01*
X1722328Y850271D01*
X1724755Y856521D01*
Y849021D01*
G01X1729361Y846521D02*
X1728428Y847771D01*
X1727961Y849021D01*
Y854021D01*
X1728428Y855271D01*
X1729361Y856521D01*
G01X1737328D02*
X1736581Y856271D01*
X1736021Y855646D01*
X1735648Y854896D01*
X1735368Y853896D01*
X1735275Y852771D01*
X1735368Y851646D01*
X1735648Y850646D01*
X1736021Y849896D01*
X1736581Y849271D01*
X1737328Y849021D01*
X1738075Y849271D01*
X1738635Y849896D01*
X1739008Y850646D01*
X1739288Y851646D01*
X1739381Y852771D01*
X1739288Y853896D01*
X1739008Y854896D01*
X1738635Y855646D01*
X1738075Y856271D01*
X1737328Y856521D01*
G01X1744828Y848771D02*
X1744641Y848896D01*
Y849146D01*
X1744828Y849271D01*
X1745015Y849146D01*
Y848896D01*
X1744828Y848771D01*
G01X1752328Y849021D02*
X1752981Y849146D01*
X1753728Y849521D01*
X1754195Y850146D01*
X1754381Y851021D01*
X1754195Y851896D01*
X1753635Y852646D01*
X1752795Y853021D01*
X1751861D01*
X1751301Y853271D01*
X1750835Y853896D01*
X1750648Y854771D01*
X1750928Y855646D01*
X1751581Y856271D01*
X1752328Y856521D01*
X1753075Y856271D01*
X1753728Y855646D01*
X1754008Y854771D01*
X1753821Y853896D01*
X1753355Y853271D01*
X1752795Y853021D01*
X1751861D01*
X1751021Y852646D01*
X1750461Y851896D01*
X1750275Y851021D01*
X1750461Y850146D01*
X1750928Y849521D01*
X1751675Y849146D01*
X1752328Y849021D01*
G01X1757775Y850146D02*
X1758335Y849521D01*
X1758988Y849146D01*
X1759828Y849021D01*
X1760668Y849271D01*
X1761321Y849771D01*
X1761788Y850646D01*
X1761881Y851646D01*
X1761695Y852646D01*
X1761228Y853271D01*
X1760575Y853771D01*
X1759921Y853896D01*
X1759268Y853771D01*
X1758428Y853271D01*
X1758708Y856521D01*
X1761228D01*
G01X1764901Y849021D02*
Y856521D01*
X1767328Y850271D01*
X1769755Y856521D01*
Y849021D01*
G01X1772401D02*
Y856521D01*
X1774828Y850271D01*
X1777255Y856521D01*
Y849021D01*
G01X1787775D02*
Y856521D01*
X1789641D01*
X1790388Y856146D01*
X1790948Y855646D01*
X1791415Y854896D01*
X1791788Y854021D01*
X1791881Y852771D01*
X1791788Y851521D01*
X1791415Y850646D01*
X1790948Y849896D01*
X1790388Y849396D01*
X1789641Y849021D01*
X1787775D01*
G01X1795461D02*
Y856521D01*
X1797795D01*
X1798541Y856146D01*
X1799008Y855646D01*
X1799195Y854646D01*
X1799008Y853646D01*
X1798448Y853021D01*
X1797795Y852646D01*
X1795461D01*
G01X1797795D02*
X1799195Y849021D01*
G01X1803708Y856521D02*
X1805948D01*
G01X1804828D02*
Y849021D01*
G01X1803708D02*
X1805948D01*
G01X1810461Y856521D02*
Y849021D01*
X1814195D01*
G01X1817961Y856521D02*
Y849021D01*
X1821695D01*
G01X1827795Y846521D02*
X1828728Y847771D01*
X1829195Y849021D01*
Y854021D01*
X1828728Y855271D01*
X1827795Y856521D01*
G01X1834828Y848771D02*
X1834641Y848896D01*
Y849146D01*
X1834828Y849271D01*
X1835015Y849146D01*
Y848896D01*
X1834828Y848771D01*
G01X987328Y868921D02*
Y861421D01*
G01X985181Y868921D02*
X989475D01*
G01X993708D02*
X995948D01*
G01X994828D02*
Y861421D01*
G01X993708D02*
X995948D01*
G01X1000181D02*
Y868921D01*
X1004475Y861421D01*
Y868921D01*
G01X1008615Y863921D02*
X1011041D01*
G01X1015461Y868921D02*
Y861421D01*
X1019195D01*
G01X1026695D02*
X1022961D01*
Y868921D01*
X1026695D01*
G01X1025201Y865296D02*
X1022961D01*
G01X1029995Y861421D02*
X1032328Y868921D01*
X1034661Y861421D01*
G01X1033821Y864046D02*
X1030835D01*
G01X1037775Y861421D02*
Y868921D01*
X1039641D01*
X1040388Y868546D01*
X1040948Y868046D01*
X1041415Y867296D01*
X1041788Y866421D01*
X1041881Y865171D01*
X1041788Y863921D01*
X1041415Y863046D01*
X1040948Y862296D01*
X1040388Y861796D01*
X1039641Y861421D01*
X1037775D01*
G01X1047328Y861171D02*
X1047141Y861296D01*
Y861546D01*
X1047328Y861671D01*
X1047515Y861546D01*
Y861296D01*
X1047328Y861171D01*
G01Y864546D02*
X1047141Y864671D01*
Y864921D01*
X1047328Y865046D01*
X1047515Y864921D01*
Y864671D01*
X1047328Y864546D01*
G01X1052961Y861421D02*
Y868921D01*
X1055295D01*
X1056041Y868546D01*
X1056508Y868046D01*
X1056695Y867046D01*
X1056508Y866046D01*
X1055948Y865421D01*
X1055295Y865046D01*
X1052961D01*
G01X1055295D02*
X1056695Y861421D01*
G01X1064195D02*
X1060461D01*
Y868921D01*
X1064195D01*
G01X1062701Y865296D02*
X1060461D01*
G01X1071881Y868296D02*
X1071321Y868671D01*
X1070668Y868921D01*
X1069921D01*
X1069081Y868546D01*
X1068428Y867921D01*
X1067961Y867171D01*
X1067588Y865921D01*
X1067495Y864796D01*
X1067681Y863671D01*
X1067961Y862921D01*
X1068521Y862171D01*
X1069175Y861671D01*
X1069828Y861421D01*
X1070481D01*
X1071135Y861671D01*
X1071695Y862046D01*
X1072161Y862546D01*
G01X1077328Y861421D02*
X1076581Y861546D01*
X1075928Y862046D01*
X1075368Y862796D01*
X1074995Y863671D01*
X1074808Y864671D01*
Y865671D01*
X1074995Y866671D01*
X1075368Y867546D01*
X1075928Y868296D01*
X1076581Y868796D01*
X1077328Y868921D01*
X1078075Y868796D01*
X1078728Y868296D01*
X1079288Y867546D01*
X1079661Y866671D01*
X1079848Y865671D01*
Y864671D01*
X1079661Y863671D01*
X1079288Y862796D01*
X1078728Y862046D01*
X1078075Y861546D01*
X1077328Y861421D01*
G01X1082401D02*
Y868921D01*
X1084828Y862671D01*
X1087255Y868921D01*
Y861421D01*
G01X1089901D02*
Y868921D01*
X1092328Y862671D01*
X1094755Y868921D01*
Y861421D01*
G01X1101695D02*
X1097961D01*
Y868921D01*
X1101695D01*
G01X1100201Y865296D02*
X1097961D01*
G01X1105181Y861421D02*
Y868921D01*
X1109475Y861421D01*
Y868921D01*
G01X1112775Y861421D02*
Y868921D01*
X1114641D01*
X1115388Y868546D01*
X1115948Y868046D01*
X1116415Y867296D01*
X1116788Y866421D01*
X1116881Y865171D01*
X1116788Y863921D01*
X1116415Y863046D01*
X1115948Y862296D01*
X1115388Y861796D01*
X1114641Y861421D01*
X1112775D01*
G01X1124195D02*
X1120461D01*
Y868921D01*
X1124195D01*
G01X1122701Y865296D02*
X1120461D01*
G01X1127775Y861421D02*
Y868921D01*
X1129641D01*
X1130388Y868546D01*
X1130948Y868046D01*
X1131415Y867296D01*
X1131788Y866421D01*
X1131881Y865171D01*
X1131788Y863921D01*
X1131415Y863046D01*
X1130948Y862296D01*
X1130388Y861796D01*
X1129641Y861421D01*
X1127775D01*
G01X1142775D02*
Y868921D01*
X1144641D01*
X1145388Y868546D01*
X1145948Y868046D01*
X1146415Y867296D01*
X1146788Y866421D01*
X1146881Y865171D01*
X1146788Y863921D01*
X1146415Y863046D01*
X1145948Y862296D01*
X1145388Y861796D01*
X1144641Y861421D01*
X1142775D01*
G01X1150461D02*
Y868921D01*
X1152795D01*
X1153541Y868546D01*
X1154008Y868046D01*
X1154195Y867046D01*
X1154008Y866046D01*
X1153448Y865421D01*
X1152795Y865046D01*
X1150461D01*
G01X1152795D02*
X1154195Y861421D01*
G01X1158708Y868921D02*
X1160948D01*
G01X1159828D02*
Y861421D01*
G01X1158708D02*
X1160948D01*
G01X1165461Y868921D02*
Y861421D01*
X1169195D01*
G01X1172961Y868921D02*
Y861421D01*
X1176695D01*
G01X1187868Y862421D02*
X1188615Y861796D01*
X1189455Y861421D01*
X1190201D01*
X1190948Y861796D01*
X1191508Y862421D01*
X1191788Y863296D01*
X1191601Y864171D01*
X1191135Y864921D01*
X1190295Y865421D01*
X1189175Y865671D01*
X1188521Y866171D01*
X1188241Y867046D01*
X1188428Y867921D01*
X1188895Y868546D01*
X1189548Y868921D01*
X1190201D01*
X1190855Y868671D01*
X1191415Y868046D01*
G01X1196208Y868921D02*
X1198448D01*
G01X1197328D02*
Y861421D01*
G01X1196208D02*
X1198448D01*
G01X1203055Y868921D02*
X1206601D01*
X1203055Y861421D01*
X1206601D01*
G01X1214195D02*
X1210461D01*
Y868921D01*
X1214195D01*
G01X1212701Y865296D02*
X1210461D01*
G01X1225555Y861421D02*
Y868921D01*
X1229101D01*
G01X1227795Y865296D02*
X1225555D01*
G01X1234828Y861421D02*
X1234081Y861546D01*
X1233428Y862046D01*
X1232868Y862796D01*
X1232495Y863671D01*
X1232308Y864671D01*
Y865671D01*
X1232495Y866671D01*
X1232868Y867546D01*
X1233428Y868296D01*
X1234081Y868796D01*
X1234828Y868921D01*
X1235575Y868796D01*
X1236228Y868296D01*
X1236788Y867546D01*
X1237161Y866671D01*
X1237348Y865671D01*
Y864671D01*
X1237161Y863671D01*
X1236788Y862796D01*
X1236228Y862046D01*
X1235575Y861546D01*
X1234828Y861421D01*
G01X1240461D02*
Y868921D01*
X1242795D01*
X1243541Y868546D01*
X1244008Y868046D01*
X1244195Y867046D01*
X1244008Y866046D01*
X1243448Y865421D01*
X1242795Y865046D01*
X1240461D01*
G01X1242795D02*
X1244195Y861421D01*
G01X1257328Y868921D02*
X1256581Y868671D01*
X1256021Y868046D01*
X1255648Y867296D01*
X1255368Y866296D01*
X1255275Y865171D01*
X1255368Y864046D01*
X1255648Y863046D01*
X1256021Y862296D01*
X1256581Y861671D01*
X1257328Y861421D01*
X1258075Y861671D01*
X1258635Y862296D01*
X1259008Y863046D01*
X1259288Y864046D01*
X1259381Y865171D01*
X1259288Y866296D01*
X1259008Y867296D01*
X1258635Y868046D01*
X1258075Y868671D01*
X1257328Y868921D01*
G01X1264828Y861171D02*
X1264641Y861296D01*
Y861546D01*
X1264828Y861671D01*
X1265015Y861546D01*
Y861296D01*
X1264828Y861171D01*
G01X1272141Y861421D02*
X1272328Y863046D01*
X1272608Y864421D01*
X1272981Y865671D01*
X1273448Y867046D01*
X1274195Y868921D01*
X1270461D01*
G01X1278055Y867671D02*
X1278615Y868421D01*
X1279268Y868796D01*
X1280015Y868921D01*
X1280948Y868671D01*
X1281601Y868046D01*
X1281788Y867296D01*
X1281695Y866546D01*
X1281321Y865921D01*
X1279455Y864671D01*
X1278615Y863796D01*
X1278055Y862546D01*
X1277868Y861421D01*
X1281788D01*
G01X1285275Y862546D02*
X1285835Y861921D01*
X1286488Y861546D01*
X1287328Y861421D01*
X1288168Y861671D01*
X1288821Y862171D01*
X1289288Y863046D01*
X1289381Y864046D01*
X1289195Y865046D01*
X1288728Y865671D01*
X1288075Y866171D01*
X1287421Y866296D01*
X1286768Y866171D01*
X1285928Y865671D01*
X1286208Y868921D01*
X1288728D01*
G01X1292401Y861421D02*
Y868921D01*
X1294828Y862671D01*
X1297255Y868921D01*
Y861421D01*
G01X1299901D02*
Y868921D01*
X1302328Y862671D01*
X1304755Y868921D01*
Y861421D01*
G01X1315555D02*
Y868921D01*
X1319101D01*
G01X1317795Y865296D02*
X1315555D01*
G01X1323708Y868921D02*
X1325948D01*
G01X1324828D02*
Y861421D01*
G01X1323708D02*
X1325948D01*
G01X1330181D02*
Y868921D01*
X1334475Y861421D01*
Y868921D01*
G01X1338708D02*
X1340948D01*
G01X1339828D02*
Y861421D01*
G01X1338708D02*
X1340948D01*
G01X1345368Y862421D02*
X1346115Y861796D01*
X1346955Y861421D01*
X1347701D01*
X1348448Y861796D01*
X1349008Y862421D01*
X1349288Y863296D01*
X1349101Y864171D01*
X1348635Y864921D01*
X1347795Y865421D01*
X1346675Y865671D01*
X1346021Y866171D01*
X1345741Y867046D01*
X1345928Y867921D01*
X1346395Y868546D01*
X1347048Y868921D01*
X1347701D01*
X1348355Y868671D01*
X1348915Y868046D01*
G01X1352868Y861421D02*
Y868921D01*
G01X1356788D02*
Y861421D01*
G01Y865171D02*
X1352868D01*
G01X1364195Y861421D02*
X1360461D01*
Y868921D01*
X1364195D01*
G01X1362701Y865296D02*
X1360461D01*
G01X1367775Y861421D02*
Y868921D01*
X1369641D01*
X1370388Y868546D01*
X1370948Y868046D01*
X1371415Y867296D01*
X1371788Y866421D01*
X1371881Y865171D01*
X1371788Y863921D01*
X1371415Y863046D01*
X1370948Y862296D01*
X1370388Y861796D01*
X1369641Y861421D01*
X1367775D01*
G01X1382961D02*
Y868921D01*
X1385201D01*
X1385948Y868546D01*
X1386508Y867671D01*
X1386695Y866671D01*
X1386508Y865671D01*
X1386041Y864921D01*
X1385201Y864546D01*
X1382961D01*
G01X1392328Y868921D02*
Y861421D01*
G01X1390181Y868921D02*
X1394475D01*
G01X1397868Y861421D02*
Y868921D01*
G01X1401788D02*
Y861421D01*
G01Y865171D02*
X1397868D01*
G01X1413708Y868921D02*
X1415948D01*
G01X1414828D02*
Y861421D01*
G01X1413708D02*
X1415948D01*
G01X1420368Y862421D02*
X1421115Y861796D01*
X1421955Y861421D01*
X1422701D01*
X1423448Y861796D01*
X1424008Y862421D01*
X1424288Y863296D01*
X1424101Y864171D01*
X1423635Y864921D01*
X1422795Y865421D01*
X1421675Y865671D01*
X1421021Y866171D01*
X1420741Y867046D01*
X1420928Y867921D01*
X1421395Y868546D01*
X1422048Y868921D01*
X1422701D01*
X1423355Y868671D01*
X1423915Y868046D01*
G01X1437328Y868921D02*
X1436581Y868671D01*
X1436021Y868046D01*
X1435648Y867296D01*
X1435368Y866296D01*
X1435275Y865171D01*
X1435368Y864046D01*
X1435648Y863046D01*
X1436021Y862296D01*
X1436581Y861671D01*
X1437328Y861421D01*
X1438075Y861671D01*
X1438635Y862296D01*
X1439008Y863046D01*
X1439288Y864046D01*
X1439381Y865171D01*
X1439288Y866296D01*
X1439008Y867296D01*
X1438635Y868046D01*
X1438075Y868671D01*
X1437328Y868921D01*
G01X1444828Y861171D02*
X1444641Y861296D01*
Y861546D01*
X1444828Y861671D01*
X1445015Y861546D01*
Y861296D01*
X1444828Y861171D01*
G01X1452328Y861421D02*
X1452981Y861546D01*
X1453728Y861921D01*
X1454195Y862546D01*
X1454381Y863421D01*
X1454195Y864296D01*
X1453635Y865046D01*
X1452795Y865421D01*
X1451861D01*
X1451301Y865671D01*
X1450835Y866296D01*
X1450648Y867171D01*
X1450928Y868046D01*
X1451581Y868671D01*
X1452328Y868921D01*
X1453075Y868671D01*
X1453728Y868046D01*
X1454008Y867171D01*
X1453821Y866296D01*
X1453355Y865671D01*
X1452795Y865421D01*
X1451861D01*
X1451021Y865046D01*
X1450461Y864296D01*
X1450275Y863421D01*
X1450461Y862546D01*
X1450928Y861921D01*
X1451675Y861546D01*
X1452328Y861421D01*
G01X1459828D02*
Y868921D01*
X1458708Y867421D01*
G01Y861421D02*
X1460948D01*
G01X1466115Y863921D02*
X1468541D01*
G01X1474828Y868921D02*
X1474081Y868671D01*
X1473521Y868046D01*
X1473148Y867296D01*
X1472868Y866296D01*
X1472775Y865171D01*
X1472868Y864046D01*
X1473148Y863046D01*
X1473521Y862296D01*
X1474081Y861671D01*
X1474828Y861421D01*
X1475575Y861671D01*
X1476135Y862296D01*
X1476508Y863046D01*
X1476788Y864046D01*
X1476881Y865171D01*
X1476788Y866296D01*
X1476508Y867296D01*
X1476135Y868046D01*
X1475575Y868671D01*
X1474828Y868921D01*
G01X1482328Y861171D02*
X1482141Y861296D01*
Y861546D01*
X1482328Y861671D01*
X1482515Y861546D01*
Y861296D01*
X1482328Y861171D01*
G01X1489828Y861421D02*
X1490481Y861546D01*
X1491228Y861921D01*
X1491695Y862546D01*
X1491881Y863421D01*
X1491695Y864296D01*
X1491135Y865046D01*
X1490295Y865421D01*
X1489361D01*
X1488801Y865671D01*
X1488335Y866296D01*
X1488148Y867171D01*
X1488428Y868046D01*
X1489081Y868671D01*
X1489828Y868921D01*
X1490575Y868671D01*
X1491228Y868046D01*
X1491508Y867171D01*
X1491321Y866296D01*
X1490855Y865671D01*
X1490295Y865421D01*
X1489361D01*
X1488521Y865046D01*
X1487961Y864296D01*
X1487775Y863421D01*
X1487961Y862546D01*
X1488428Y861921D01*
X1489175Y861546D01*
X1489828Y861421D01*
G01X1495555Y864546D02*
X1496208Y865421D01*
X1496768Y865921D01*
X1497515Y866171D01*
X1498168Y865921D01*
X1498635Y865421D01*
X1499008Y864671D01*
X1499101Y863796D01*
X1499008Y863046D01*
X1498635Y862296D01*
X1498075Y861671D01*
X1497421Y861421D01*
X1496675Y861671D01*
X1496021Y862421D01*
X1495648Y863546D01*
X1495555Y864796D01*
X1495741Y866421D01*
X1496021Y867296D01*
X1496488Y868171D01*
X1497141Y868796D01*
X1497795Y868921D01*
X1498448Y868671D01*
X1498915Y868046D01*
G01X1502401Y861421D02*
Y868921D01*
X1504828Y862671D01*
X1507255Y868921D01*
Y861421D01*
G01X1509901D02*
Y868921D01*
X1512328Y862671D01*
X1514755Y868921D01*
Y861421D01*
G01X1519361Y858921D02*
X1518428Y860171D01*
X1517961Y861421D01*
Y866421D01*
X1518428Y867671D01*
X1519361Y868921D01*
G01X1527328D02*
X1526581Y868671D01*
X1526021Y868046D01*
X1525648Y867296D01*
X1525368Y866296D01*
X1525275Y865171D01*
X1525368Y864046D01*
X1525648Y863046D01*
X1526021Y862296D01*
X1526581Y861671D01*
X1527328Y861421D01*
X1528075Y861671D01*
X1528635Y862296D01*
X1529008Y863046D01*
X1529288Y864046D01*
X1529381Y865171D01*
X1529288Y866296D01*
X1529008Y867296D01*
X1528635Y868046D01*
X1528075Y868671D01*
X1527328Y868921D01*
G01X1534828Y861171D02*
X1534641Y861296D01*
Y861546D01*
X1534828Y861671D01*
X1535015Y861546D01*
Y861296D01*
X1534828Y861171D01*
G01X1542328Y861421D02*
X1542981Y861546D01*
X1543728Y861921D01*
X1544195Y862546D01*
X1544381Y863421D01*
X1544195Y864296D01*
X1543635Y865046D01*
X1542795Y865421D01*
X1541861D01*
X1541301Y865671D01*
X1540835Y866296D01*
X1540648Y867171D01*
X1540928Y868046D01*
X1541581Y868671D01*
X1542328Y868921D01*
X1543075Y868671D01*
X1543728Y868046D01*
X1544008Y867171D01*
X1543821Y866296D01*
X1543355Y865671D01*
X1542795Y865421D01*
X1541861D01*
X1541021Y865046D01*
X1540461Y864296D01*
X1540275Y863421D01*
X1540461Y862546D01*
X1540928Y861921D01*
X1541675Y861546D01*
X1542328Y861421D01*
G01X1547775Y862546D02*
X1548335Y861921D01*
X1548988Y861546D01*
X1549828Y861421D01*
X1550668Y861671D01*
X1551321Y862171D01*
X1551788Y863046D01*
X1551881Y864046D01*
X1551695Y865046D01*
X1551228Y865671D01*
X1550575Y866171D01*
X1549921Y866296D01*
X1549268Y866171D01*
X1548428Y865671D01*
X1548708Y868921D01*
X1551228D01*
G01X1554901Y861421D02*
Y868921D01*
X1557328Y862671D01*
X1559755Y868921D01*
Y861421D01*
G01X1562401D02*
Y868921D01*
X1564828Y862671D01*
X1567255Y868921D01*
Y861421D01*
G01X1577775D02*
Y868921D01*
X1579641D01*
X1580388Y868546D01*
X1580948Y868046D01*
X1581415Y867296D01*
X1581788Y866421D01*
X1581881Y865171D01*
X1581788Y863921D01*
X1581415Y863046D01*
X1580948Y862296D01*
X1580388Y861796D01*
X1579641Y861421D01*
X1577775D01*
G01X1585461D02*
Y868921D01*
X1587795D01*
X1588541Y868546D01*
X1589008Y868046D01*
X1589195Y867046D01*
X1589008Y866046D01*
X1588448Y865421D01*
X1587795Y865046D01*
X1585461D01*
G01X1587795D02*
X1589195Y861421D01*
G01X1593708Y868921D02*
X1595948D01*
G01X1594828D02*
Y861421D01*
G01X1593708D02*
X1595948D01*
G01X1600461Y868921D02*
Y861421D01*
X1604195D01*
G01X1607961Y868921D02*
Y861421D01*
X1611695D01*
G01X1617795Y858921D02*
X1618728Y860171D01*
X1619195Y861421D01*
Y866421D01*
X1618728Y867671D01*
X1617795Y868921D01*
G01X1624828Y861171D02*
X1624641Y861296D01*
Y861546D01*
X1624828Y861671D01*
X1625015Y861546D01*
Y861296D01*
X1624828Y861171D01*
G01X1193890Y569148D02*
X1194820Y568106D01*
X1195905Y567481D01*
X1197300Y567273D01*
X1198695Y567690D01*
X1199780Y568523D01*
X1200555Y569981D01*
X1200710Y571648D01*
X1200400Y573315D01*
X1199625Y574356D01*
X1198540Y575190D01*
X1197455Y575398D01*
X1196370Y575190D01*
X1194975Y574356D01*
X1195440Y579773D01*
X1199625D01*
G01X1206755Y572481D02*
X1207840Y573940D01*
X1208770Y574773D01*
X1210010Y575190D01*
X1211095Y574773D01*
X1211870Y573940D01*
X1212490Y572690D01*
X1212645Y571231D01*
X1212490Y569981D01*
X1211870Y568731D01*
X1210940Y567690D01*
X1209855Y567273D01*
X1208615Y567690D01*
X1207530Y568939D01*
X1206910Y570815D01*
X1206755Y572898D01*
X1207065Y575606D01*
X1207530Y577065D01*
X1208305Y578523D01*
X1209390Y579565D01*
X1210475Y579773D01*
X1211560Y579356D01*
X1212335Y578315D01*
G01X1222100Y567273D02*
Y579773D01*
X1220240Y577273D01*
G01Y567273D02*
X1223960D01*
G01X1234500Y579773D02*
X1233260Y579356D01*
X1232330Y578315D01*
X1231710Y577065D01*
X1231245Y575398D01*
X1231090Y573523D01*
X1231245Y571648D01*
X1231710Y569981D01*
X1232330Y568731D01*
X1233260Y567690D01*
X1234500Y567273D01*
X1235740Y567690D01*
X1236670Y568731D01*
X1237290Y569981D01*
X1237755Y571648D01*
X1237910Y573523D01*
X1237755Y575398D01*
X1237290Y577065D01*
X1236670Y578315D01*
X1235740Y579356D01*
X1234500Y579773D01*
G01X1246900Y566856D02*
X1246590Y567065D01*
Y567481D01*
X1246900Y567690D01*
X1247210Y567481D01*
Y567065D01*
X1246900Y566856D01*
G01X1256355Y577690D02*
X1257285Y578939D01*
X1258370Y579565D01*
X1259610Y579773D01*
X1261160Y579356D01*
X1262245Y578315D01*
X1262555Y577065D01*
X1262400Y575814D01*
X1261780Y574773D01*
X1258680Y572690D01*
X1257285Y571231D01*
X1256355Y569148D01*
X1256045Y567273D01*
X1262555D01*
G01X1268290Y569773D02*
X1269220Y568314D01*
X1270460Y567481D01*
X1271855Y567273D01*
X1273095Y567481D01*
X1274335Y568523D01*
X1275110Y569773D01*
X1275265Y571023D01*
X1274955Y572481D01*
X1273870Y573523D01*
X1272785Y573940D01*
X1271390D01*
G01X1272785D02*
X1273715Y574565D01*
X1274490Y575606D01*
X1274800Y576856D01*
X1274490Y578106D01*
X1273715Y579148D01*
X1272320Y579773D01*
X1270925Y579565D01*
X1269530Y578731D01*
G01X1209850Y542273D02*
Y554773D01*
X1207990Y552273D01*
G01Y542273D02*
X1211710D01*
G01X1224110D02*
Y554773D01*
X1218375Y545815D01*
X1226125D01*
G01X1231705Y552690D02*
X1232635Y553939D01*
X1233720Y554565D01*
X1234960Y554773D01*
X1236510Y554356D01*
X1237595Y553315D01*
X1237905Y552065D01*
X1237750Y550814D01*
X1237130Y549773D01*
X1234030Y547690D01*
X1232635Y546231D01*
X1231705Y544148D01*
X1231395Y542273D01*
X1237905D01*
G01X1247050Y541856D02*
X1246740Y542065D01*
Y542481D01*
X1247050Y542690D01*
X1247360Y542481D01*
Y542065D01*
X1247050Y541856D01*
G01X1256040Y544148D02*
X1256970Y543106D01*
X1258055Y542481D01*
X1259450Y542273D01*
X1260845Y542690D01*
X1261930Y543523D01*
X1262705Y544981D01*
X1262860Y546648D01*
X1262550Y548315D01*
X1261775Y549356D01*
X1260690Y550190D01*
X1259605Y550398D01*
X1258520Y550190D01*
X1257125Y549356D01*
X1257590Y554773D01*
X1261775D01*
G01X1328901Y308735D02*
Y316235D01*
X1331141D01*
X1331888Y315860D01*
X1332448Y314985D01*
X1332635Y313985D01*
X1332448Y312985D01*
X1331981Y312235D01*
X1331141Y311860D01*
X1328901D01*
G01X1338268Y316235D02*
Y308735D01*
G01X1336121Y316235D02*
X1340415D01*
G01X1343808Y308735D02*
Y316235D01*
G01X1347728D02*
Y308735D01*
G01Y312485D02*
X1343808D01*
G01X1332334Y455100D02*
X1319834D01*
X1322334Y453240D01*
G01X1332334D02*
Y456960D01*
G01X1329834Y464090D02*
X1331293Y465020D01*
X1332126Y466260D01*
X1332334Y467655D01*
X1332126Y468895D01*
X1331084Y470135D01*
X1329834Y470910D01*
X1328584Y471065D01*
X1327126Y470755D01*
X1326084Y469670D01*
X1325667Y468585D01*
Y467190D01*
G01Y468585D02*
X1325042Y469515D01*
X1324001Y470290D01*
X1322751Y470600D01*
X1321501Y470290D01*
X1320459Y469515D01*
X1319834Y468120D01*
X1320042Y466725D01*
X1320876Y465330D01*
G01X1329834Y476490D02*
X1331293Y477420D01*
X1332126Y478660D01*
X1332334Y480055D01*
X1332126Y481295D01*
X1331084Y482535D01*
X1329834Y483310D01*
X1328584Y483465D01*
X1327126Y483155D01*
X1326084Y482070D01*
X1325667Y480985D01*
Y479590D01*
G01Y480985D02*
X1325042Y481915D01*
X1324001Y482690D01*
X1322751Y483000D01*
X1321501Y482690D01*
X1320459Y481915D01*
X1319834Y480520D01*
X1320042Y479125D01*
X1320876Y477730D01*
G01X1332334Y492300D02*
X1332126Y493385D01*
X1331501Y494625D01*
X1330459Y495400D01*
X1329001Y495710D01*
X1327543Y495400D01*
X1326292Y494470D01*
X1325667Y493075D01*
Y491525D01*
X1325251Y490595D01*
X1324209Y489820D01*
X1322751Y489510D01*
X1321292Y489975D01*
X1320251Y491060D01*
X1319834Y492300D01*
X1320251Y493540D01*
X1321292Y494625D01*
X1322751Y495090D01*
X1324209Y494780D01*
X1325251Y494005D01*
X1325667Y493075D01*
Y491525D01*
X1326292Y490130D01*
X1327543Y489200D01*
X1329001Y488890D01*
X1330459Y489200D01*
X1331501Y489975D01*
X1332126Y491215D01*
X1332334Y492300D01*
G01X1330459Y501290D02*
X1331501Y502220D01*
X1332126Y503305D01*
X1332334Y504700D01*
X1331917Y506095D01*
X1331084Y507180D01*
X1329626Y507955D01*
X1327959Y508110D01*
X1326292Y507800D01*
X1325251Y507025D01*
X1324417Y505940D01*
X1324209Y504855D01*
X1324417Y503770D01*
X1325251Y502375D01*
X1319834Y502840D01*
Y507025D01*
G01X1332751Y517100D02*
X1332542Y516790D01*
X1332126D01*
X1331917Y517100D01*
X1332126Y517410D01*
X1332542D01*
X1332751Y517100D01*
G01X1332334Y529500D02*
X1332126Y530585D01*
X1331501Y531825D01*
X1330459Y532600D01*
X1329001Y532910D01*
X1327543Y532600D01*
X1326292Y531670D01*
X1325667Y530275D01*
Y528725D01*
X1325251Y527795D01*
X1324209Y527020D01*
X1322751Y526710D01*
X1321292Y527175D01*
X1320251Y528260D01*
X1319834Y529500D01*
X1320251Y530740D01*
X1321292Y531825D01*
X1322751Y532290D01*
X1324209Y531980D01*
X1325251Y531205D01*
X1325667Y530275D01*
Y528725D01*
X1326292Y527330D01*
X1327543Y526400D01*
X1329001Y526090D01*
X1330459Y526400D01*
X1331501Y527175D01*
X1332126Y528415D01*
X1332334Y529500D01*
G01Y543760D02*
X1319834D01*
X1328792Y538025D01*
Y545775D01*
G01X1354834Y482840D02*
X1356293Y483770D01*
X1357126Y485010D01*
X1357334Y486405D01*
X1357126Y487645D01*
X1356084Y488885D01*
X1354834Y489660D01*
X1353584Y489815D01*
X1352126Y489505D01*
X1351084Y488420D01*
X1350667Y487335D01*
Y485940D01*
G01Y487335D02*
X1350042Y488265D01*
X1349001Y489040D01*
X1347751Y489350D01*
X1346501Y489040D01*
X1345459Y488265D01*
X1344834Y486870D01*
X1345042Y485475D01*
X1345876Y484080D01*
G01X1357334Y500510D02*
X1344834D01*
X1353792Y494775D01*
Y502525D01*
G01X1344834Y511050D02*
X1345251Y509810D01*
X1346292Y508880D01*
X1347542Y508260D01*
X1349209Y507795D01*
X1351084Y507640D01*
X1352959Y507795D01*
X1354626Y508260D01*
X1355876Y508880D01*
X1356917Y509810D01*
X1357334Y511050D01*
X1356917Y512290D01*
X1355876Y513220D01*
X1354626Y513840D01*
X1352959Y514305D01*
X1351084Y514460D01*
X1349209Y514305D01*
X1347542Y513840D01*
X1346292Y513220D01*
X1345251Y512290D01*
X1344834Y511050D01*
G01X1411074Y709100D02*
X1398574D01*
X1401074Y707240D01*
G01X1411074D02*
Y710960D01*
G01Y723360D02*
X1398574D01*
X1407532Y717625D01*
Y725375D01*
G01X1411074Y733900D02*
X1398574D01*
X1401074Y732040D01*
G01X1411074D02*
Y735760D01*
G01Y745990D02*
X1408366Y746300D01*
X1406074Y746765D01*
X1403991Y747385D01*
X1401699Y748160D01*
X1398574Y749400D01*
Y743200D01*
G01X1408574Y755290D02*
X1410033Y756220D01*
X1410866Y757460D01*
X1411074Y758855D01*
X1410866Y760095D01*
X1409824Y761335D01*
X1408574Y762110D01*
X1407324Y762265D01*
X1405866Y761955D01*
X1404824Y760870D01*
X1404407Y759785D01*
Y758390D01*
G01Y759785D02*
X1403782Y760715D01*
X1402741Y761490D01*
X1401491Y761800D01*
X1400241Y761490D01*
X1399199Y760715D01*
X1398574Y759320D01*
X1398782Y757925D01*
X1399616Y756530D01*
G01X1411491Y771100D02*
X1411282Y770790D01*
X1410866D01*
X1410657Y771100D01*
X1410866Y771410D01*
X1411282D01*
X1411491Y771100D01*
G01X1400657Y780555D02*
X1399408Y781485D01*
X1398782Y782570D01*
X1398574Y783810D01*
X1398991Y785360D01*
X1400032Y786445D01*
X1401282Y786755D01*
X1402533Y786600D01*
X1403574Y785980D01*
X1405657Y782880D01*
X1407116Y781485D01*
X1409199Y780555D01*
X1411074Y780245D01*
Y786755D01*
G01Y797760D02*
X1398574D01*
X1407532Y792025D01*
Y799775D01*
G01X1446506Y-171400D02*
X1434006D01*
X1436506Y-173260D01*
G01X1446506D02*
Y-169540D01*
G01Y-157140D02*
X1434006D01*
X1442964Y-162875D01*
Y-155125D01*
G01X1444631Y-150010D02*
X1445673Y-149080D01*
X1446298Y-147995D01*
X1446506Y-146600D01*
X1446089Y-145205D01*
X1445256Y-144120D01*
X1443798Y-143345D01*
X1442131Y-143190D01*
X1440464Y-143500D01*
X1439423Y-144275D01*
X1438589Y-145360D01*
X1438381Y-146445D01*
X1438589Y-147530D01*
X1439423Y-148925D01*
X1434006Y-148460D01*
Y-144275D01*
G01X1436089Y-137145D02*
X1434840Y-136215D01*
X1434214Y-135130D01*
X1434006Y-133890D01*
X1434423Y-132340D01*
X1435464Y-131255D01*
X1436714Y-130945D01*
X1437965Y-131100D01*
X1439006Y-131720D01*
X1441089Y-134820D01*
X1442548Y-136215D01*
X1444631Y-137145D01*
X1446506Y-137455D01*
Y-130945D01*
G01Y-122110D02*
X1443798Y-121800D01*
X1441506Y-121335D01*
X1439423Y-120715D01*
X1437131Y-119940D01*
X1434006Y-118700D01*
Y-124900D01*
G01X1446923Y-109400D02*
X1446714Y-109710D01*
X1446298D01*
X1446089Y-109400D01*
X1446298Y-109090D01*
X1446714D01*
X1446923Y-109400D01*
G01X1444631Y-100410D02*
X1445673Y-99480D01*
X1446298Y-98395D01*
X1446506Y-97000D01*
X1446089Y-95605D01*
X1445256Y-94520D01*
X1443798Y-93745D01*
X1442131Y-93590D01*
X1440464Y-93900D01*
X1439423Y-94675D01*
X1438589Y-95760D01*
X1438381Y-96845D01*
X1438589Y-97930D01*
X1439423Y-99325D01*
X1434006Y-98860D01*
Y-94675D01*
G01X1441298Y-87545D02*
X1439839Y-86460D01*
X1439006Y-85530D01*
X1438589Y-84290D01*
X1439006Y-83205D01*
X1439839Y-82430D01*
X1441089Y-81810D01*
X1442548Y-81655D01*
X1443798Y-81810D01*
X1445048Y-82430D01*
X1446089Y-83360D01*
X1446506Y-84445D01*
X1446089Y-85685D01*
X1444840Y-86770D01*
X1442964Y-87390D01*
X1440881Y-87545D01*
X1438173Y-87235D01*
X1436714Y-86770D01*
X1435256Y-85995D01*
X1434214Y-84910D01*
X1434006Y-83825D01*
X1434423Y-82740D01*
X1435464Y-81965D01*
G01X1406874Y526641D02*
Y534141D01*
X1409114D01*
X1409861Y533766D01*
X1410421Y532891D01*
X1410608Y531891D01*
X1410421Y530891D01*
X1409954Y530141D01*
X1409114Y529766D01*
X1406874D01*
G01X1416241Y534141D02*
Y526641D01*
G01X1414094Y534141D02*
X1418388D01*
G01X1421781Y526641D02*
Y534141D01*
G01X1425701D02*
Y526641D01*
G01Y530391D02*
X1421781D01*
G01X1433574Y736840D02*
X1435033Y737770D01*
X1435866Y739010D01*
X1436074Y740405D01*
X1435866Y741645D01*
X1434824Y742885D01*
X1433574Y743660D01*
X1432324Y743815D01*
X1430866Y743505D01*
X1429824Y742420D01*
X1429407Y741335D01*
Y739940D01*
G01Y741335D02*
X1428782Y742265D01*
X1427741Y743040D01*
X1426491Y743350D01*
X1425241Y743040D01*
X1424199Y742265D01*
X1423574Y740870D01*
X1423782Y739475D01*
X1424616Y738080D01*
G01X1430866Y749705D02*
X1429407Y750790D01*
X1428574Y751720D01*
X1428157Y752960D01*
X1428574Y754045D01*
X1429407Y754820D01*
X1430657Y755440D01*
X1432116Y755595D01*
X1433366Y755440D01*
X1434616Y754820D01*
X1435657Y753890D01*
X1436074Y752805D01*
X1435657Y751565D01*
X1434408Y750480D01*
X1432532Y749860D01*
X1430449Y749705D01*
X1427741Y750015D01*
X1426282Y750480D01*
X1424824Y751255D01*
X1423782Y752340D01*
X1423574Y753425D01*
X1423991Y754510D01*
X1425032Y755285D01*
G01X1423574Y765050D02*
X1423991Y763810D01*
X1425032Y762880D01*
X1426282Y762260D01*
X1427949Y761795D01*
X1429824Y761640D01*
X1431699Y761795D01*
X1433366Y762260D01*
X1434616Y762880D01*
X1435657Y763810D01*
X1436074Y765050D01*
X1435657Y766290D01*
X1434616Y767220D01*
X1433366Y767840D01*
X1431699Y768305D01*
X1429824Y768460D01*
X1427949Y768305D01*
X1426282Y767840D01*
X1425032Y767220D01*
X1423991Y766290D01*
X1423574Y765050D01*
G01X1469006Y-143660D02*
X1470465Y-142730D01*
X1471298Y-141490D01*
X1471506Y-140095D01*
X1471298Y-138855D01*
X1470256Y-137615D01*
X1469006Y-136840D01*
X1467756Y-136685D01*
X1466298Y-136995D01*
X1465256Y-138080D01*
X1464839Y-139165D01*
Y-140560D01*
G01Y-139165D02*
X1464214Y-138235D01*
X1463173Y-137460D01*
X1461923Y-137150D01*
X1460673Y-137460D01*
X1459631Y-138235D01*
X1459006Y-139630D01*
X1459214Y-141025D01*
X1460048Y-142420D01*
G01X1466298Y-130795D02*
X1464839Y-129710D01*
X1464006Y-128780D01*
X1463589Y-127540D01*
X1464006Y-126455D01*
X1464839Y-125680D01*
X1466089Y-125060D01*
X1467548Y-124905D01*
X1468798Y-125060D01*
X1470048Y-125680D01*
X1471089Y-126610D01*
X1471506Y-127695D01*
X1471089Y-128935D01*
X1469840Y-130020D01*
X1467964Y-130640D01*
X1465881Y-130795D01*
X1463173Y-130485D01*
X1461714Y-130020D01*
X1460256Y-129245D01*
X1459214Y-128160D01*
X1459006Y-127075D01*
X1459423Y-125990D01*
X1460464Y-125215D01*
G01X1470048Y-118085D02*
X1471089Y-117000D01*
X1471506Y-115760D01*
X1471089Y-114520D01*
X1469840Y-113435D01*
X1467964Y-112660D01*
X1466089Y-112350D01*
X1463798D01*
X1461923Y-112660D01*
X1460256Y-113435D01*
X1459423Y-114365D01*
X1459006Y-115450D01*
X1459423Y-116690D01*
X1460256Y-117620D01*
X1461506Y-118240D01*
X1463173Y-118550D01*
X1464631Y-118240D01*
X1466089Y-117465D01*
X1466923Y-116535D01*
X1467131Y-115450D01*
X1466715Y-114210D01*
X1465673Y-113280D01*
X1463798Y-112350D01*
G01X1462875Y-57841D02*
X1465115D01*
G01X1463995D02*
Y-65341D01*
G01X1462875D02*
X1465115D01*
G01X1469068D02*
Y-57841D01*
X1471495Y-64091D01*
X1473922Y-57841D01*
Y-65341D01*
G01X1476568D02*
Y-57841D01*
X1478995Y-64091D01*
X1481422Y-57841D01*
Y-65341D01*
G01X1488362D02*
X1484628D01*
Y-57841D01*
X1488362D01*
G01X1486868Y-61466D02*
X1484628D01*
G01X1492128Y-65341D02*
Y-57841D01*
X1494462D01*
X1495208Y-58216D01*
X1495675Y-58716D01*
X1495862Y-59716D01*
X1495675Y-60716D01*
X1495115Y-61341D01*
X1494462Y-61716D01*
X1492128D01*
G01X1494462D02*
X1495862Y-65341D01*
G01X1499535Y-64341D02*
X1500282Y-64966D01*
X1501122Y-65341D01*
X1501868D01*
X1502615Y-64966D01*
X1503175Y-64341D01*
X1503455Y-63466D01*
X1503268Y-62591D01*
X1502802Y-61841D01*
X1501962Y-61341D01*
X1500842Y-61091D01*
X1500188Y-60591D01*
X1499908Y-59716D01*
X1500095Y-58841D01*
X1500562Y-58216D01*
X1501215Y-57841D01*
X1501868D01*
X1502522Y-58091D01*
X1503082Y-58716D01*
G01X1507875Y-57841D02*
X1510115D01*
G01X1508995D02*
Y-65341D01*
G01X1507875D02*
X1510115D01*
G01X1516495D02*
X1515748Y-65216D01*
X1515095Y-64716D01*
X1514535Y-63966D01*
X1514162Y-63091D01*
X1513975Y-62091D01*
Y-61091D01*
X1514162Y-60091D01*
X1514535Y-59216D01*
X1515095Y-58466D01*
X1515748Y-57966D01*
X1516495Y-57841D01*
X1517242Y-57966D01*
X1517895Y-58466D01*
X1518455Y-59216D01*
X1518828Y-60091D01*
X1519015Y-61091D01*
Y-62091D01*
X1518828Y-63091D01*
X1518455Y-63966D01*
X1517895Y-64716D01*
X1517242Y-65216D01*
X1516495Y-65341D01*
G01X1521848D02*
Y-57841D01*
X1526142Y-65341D01*
Y-57841D01*
G01X1538995D02*
Y-65341D01*
G01X1536848Y-57841D02*
X1541142D01*
G01X1545375D02*
X1547615D01*
G01X1546495D02*
Y-65341D01*
G01X1545375D02*
X1547615D01*
G01X1551848D02*
Y-57841D01*
X1556142Y-65341D01*
Y-57841D01*
G01X1559815Y-65591D02*
X1563175Y-57841D01*
G01X1571048Y-58466D02*
X1570488Y-58091D01*
X1569835Y-57841D01*
X1569088D01*
X1568248Y-58216D01*
X1567595Y-58841D01*
X1567128Y-59591D01*
X1566755Y-60841D01*
X1566662Y-61966D01*
X1566848Y-63091D01*
X1567128Y-63841D01*
X1567688Y-64591D01*
X1568342Y-65091D01*
X1568995Y-65341D01*
X1569648D01*
X1570302Y-65091D01*
X1570862Y-64716D01*
X1571328Y-64216D01*
G01X1576495Y-65341D02*
X1575748Y-65216D01*
X1575095Y-64716D01*
X1574535Y-63966D01*
X1574162Y-63091D01*
X1573975Y-62091D01*
Y-61091D01*
X1574162Y-60091D01*
X1574535Y-59216D01*
X1575095Y-58466D01*
X1575748Y-57966D01*
X1576495Y-57841D01*
X1577242Y-57966D01*
X1577895Y-58466D01*
X1578455Y-59216D01*
X1578828Y-60091D01*
X1579015Y-61091D01*
Y-62091D01*
X1578828Y-63091D01*
X1578455Y-63966D01*
X1577895Y-64716D01*
X1577242Y-65216D01*
X1576495Y-65341D01*
G01X1582128D02*
Y-57841D01*
X1584368D01*
X1585115Y-58216D01*
X1585675Y-59091D01*
X1585862Y-60091D01*
X1585675Y-61091D01*
X1585208Y-61841D01*
X1584368Y-62216D01*
X1582128D01*
G01X1589628Y-65341D02*
Y-57841D01*
X1591868D01*
X1592615Y-58216D01*
X1593175Y-59091D01*
X1593362Y-60091D01*
X1593175Y-61091D01*
X1592708Y-61841D01*
X1591868Y-62216D01*
X1589628D01*
G01X1600862Y-65341D02*
X1597128D01*
Y-57841D01*
X1600862D01*
G01X1599368Y-61466D02*
X1597128D01*
G01X1604628Y-65341D02*
Y-57841D01*
X1606962D01*
X1607708Y-58216D01*
X1608175Y-58716D01*
X1608362Y-59716D01*
X1608175Y-60716D01*
X1607615Y-61341D01*
X1606962Y-61716D01*
X1604628D01*
G01X1606962D02*
X1608362Y-65341D01*
G01X1613995Y-65591D02*
X1613808Y-65466D01*
Y-65216D01*
X1613995Y-65091D01*
X1614182Y-65216D01*
Y-65466D01*
X1613995Y-65591D01*
G01Y-62216D02*
X1613808Y-62091D01*
Y-61841D01*
X1613995Y-61716D01*
X1614182Y-61841D01*
Y-62091D01*
X1613995Y-62216D01*
G01X1619628Y-65341D02*
Y-57841D01*
X1621962D01*
X1622708Y-58216D01*
X1623175Y-58716D01*
X1623362Y-59716D01*
X1623175Y-60716D01*
X1622615Y-61341D01*
X1621962Y-61716D01*
X1619628D01*
G01X1621962D02*
X1623362Y-65341D01*
G01X1630862D02*
X1627128D01*
Y-57841D01*
X1630862D01*
G01X1629368Y-61466D02*
X1627128D01*
G01X1638548Y-58466D02*
X1637988Y-58091D01*
X1637335Y-57841D01*
X1636588D01*
X1635748Y-58216D01*
X1635095Y-58841D01*
X1634628Y-59591D01*
X1634255Y-60841D01*
X1634162Y-61966D01*
X1634348Y-63091D01*
X1634628Y-63841D01*
X1635188Y-64591D01*
X1635842Y-65091D01*
X1636495Y-65341D01*
X1637148D01*
X1637802Y-65091D01*
X1638362Y-64716D01*
X1638828Y-64216D01*
G01X1643995Y-65341D02*
X1643248Y-65216D01*
X1642595Y-64716D01*
X1642035Y-63966D01*
X1641662Y-63091D01*
X1641475Y-62091D01*
Y-61091D01*
X1641662Y-60091D01*
X1642035Y-59216D01*
X1642595Y-58466D01*
X1643248Y-57966D01*
X1643995Y-57841D01*
X1644742Y-57966D01*
X1645395Y-58466D01*
X1645955Y-59216D01*
X1646328Y-60091D01*
X1646515Y-61091D01*
Y-62091D01*
X1646328Y-63091D01*
X1645955Y-63966D01*
X1645395Y-64716D01*
X1644742Y-65216D01*
X1643995Y-65341D01*
G01X1649068D02*
Y-57841D01*
X1651495Y-64091D01*
X1653922Y-57841D01*
Y-65341D01*
G01X1656568D02*
Y-57841D01*
X1658995Y-64091D01*
X1661422Y-57841D01*
Y-65341D01*
G01X1668362D02*
X1664628D01*
Y-57841D01*
X1668362D01*
G01X1666868Y-61466D02*
X1664628D01*
G01X1671848Y-65341D02*
Y-57841D01*
X1676142Y-65341D01*
Y-57841D01*
G01X1679442Y-65341D02*
Y-57841D01*
X1681308D01*
X1682055Y-58216D01*
X1682615Y-58716D01*
X1683082Y-59466D01*
X1683455Y-60341D01*
X1683548Y-61591D01*
X1683455Y-62841D01*
X1683082Y-63716D01*
X1682615Y-64466D01*
X1682055Y-64966D01*
X1681308Y-65341D01*
X1679442D01*
G01X1690862D02*
X1687128D01*
Y-57841D01*
X1690862D01*
G01X1689368Y-61466D02*
X1687128D01*
G01X1694442Y-65341D02*
Y-57841D01*
X1696308D01*
X1697055Y-58216D01*
X1697615Y-58716D01*
X1698082Y-59466D01*
X1698455Y-60341D01*
X1698548Y-61591D01*
X1698455Y-62841D01*
X1698082Y-63716D01*
X1697615Y-64466D01*
X1697055Y-64966D01*
X1696308Y-65341D01*
X1694442D01*
G01X1709442D02*
Y-57841D01*
X1711308D01*
X1712055Y-58216D01*
X1712615Y-58716D01*
X1713082Y-59466D01*
X1713455Y-60341D01*
X1713548Y-61591D01*
X1713455Y-62841D01*
X1713082Y-63716D01*
X1712615Y-64466D01*
X1712055Y-64966D01*
X1711308Y-65341D01*
X1709442D01*
G01X1717128D02*
Y-57841D01*
X1719462D01*
X1720208Y-58216D01*
X1720675Y-58716D01*
X1720862Y-59716D01*
X1720675Y-60716D01*
X1720115Y-61341D01*
X1719462Y-61716D01*
X1717128D01*
G01X1719462D02*
X1720862Y-65341D01*
G01X1725375Y-57841D02*
X1727615D01*
G01X1726495D02*
Y-65341D01*
G01X1725375D02*
X1727615D01*
G01X1732128Y-57841D02*
Y-65341D01*
X1735862D01*
G01X1739628Y-57841D02*
Y-65341D01*
X1743362D01*
G01X1754535Y-64341D02*
X1755282Y-64966D01*
X1756122Y-65341D01*
X1756868D01*
X1757615Y-64966D01*
X1758175Y-64341D01*
X1758455Y-63466D01*
X1758268Y-62591D01*
X1757802Y-61841D01*
X1756962Y-61341D01*
X1755842Y-61091D01*
X1755188Y-60591D01*
X1754908Y-59716D01*
X1755095Y-58841D01*
X1755562Y-58216D01*
X1756215Y-57841D01*
X1756868D01*
X1757522Y-58091D01*
X1758082Y-58716D01*
G01X1762875Y-57841D02*
X1765115D01*
G01X1763995D02*
Y-65341D01*
G01X1762875D02*
X1765115D01*
G01X1769722Y-57841D02*
X1773268D01*
X1769722Y-65341D01*
X1773268D01*
G01X1780862D02*
X1777128D01*
Y-57841D01*
X1780862D01*
G01X1779368Y-61466D02*
X1777128D01*
G01X1792222Y-65341D02*
Y-57841D01*
X1795768D01*
G01X1794462Y-61466D02*
X1792222D01*
G01X1801495Y-65341D02*
X1800748Y-65216D01*
X1800095Y-64716D01*
X1799535Y-63966D01*
X1799162Y-63091D01*
X1798975Y-62091D01*
Y-61091D01*
X1799162Y-60091D01*
X1799535Y-59216D01*
X1800095Y-58466D01*
X1800748Y-57966D01*
X1801495Y-57841D01*
X1802242Y-57966D01*
X1802895Y-58466D01*
X1803455Y-59216D01*
X1803828Y-60091D01*
X1804015Y-61091D01*
Y-62091D01*
X1803828Y-63091D01*
X1803455Y-63966D01*
X1802895Y-64716D01*
X1802242Y-65216D01*
X1801495Y-65341D01*
G01X1807128D02*
Y-57841D01*
X1809462D01*
X1810208Y-58216D01*
X1810675Y-58716D01*
X1810862Y-59716D01*
X1810675Y-60716D01*
X1810115Y-61341D01*
X1809462Y-61716D01*
X1807128D01*
G01X1809462D02*
X1810862Y-65341D01*
G01X1823995Y-57841D02*
X1823248Y-58091D01*
X1822688Y-58716D01*
X1822315Y-59466D01*
X1822035Y-60466D01*
X1821942Y-61591D01*
X1822035Y-62716D01*
X1822315Y-63716D01*
X1822688Y-64466D01*
X1823248Y-65091D01*
X1823995Y-65341D01*
X1824742Y-65091D01*
X1825302Y-64466D01*
X1825675Y-63716D01*
X1825955Y-62716D01*
X1826048Y-61591D01*
X1825955Y-60466D01*
X1825675Y-59466D01*
X1825302Y-58716D01*
X1824742Y-58091D01*
X1823995Y-57841D01*
G01X1831495Y-65591D02*
X1831308Y-65466D01*
Y-65216D01*
X1831495Y-65091D01*
X1831682Y-65216D01*
Y-65466D01*
X1831495Y-65591D01*
G01X1838808Y-65341D02*
X1838995Y-63716D01*
X1839275Y-62341D01*
X1839648Y-61091D01*
X1840115Y-59716D01*
X1840862Y-57841D01*
X1837128D01*
G01X1844442Y-64216D02*
X1845002Y-64841D01*
X1845655Y-65216D01*
X1846495Y-65341D01*
X1847335Y-65091D01*
X1847988Y-64591D01*
X1848455Y-63716D01*
X1848548Y-62716D01*
X1848362Y-61716D01*
X1847895Y-61091D01*
X1847242Y-60591D01*
X1846588Y-60466D01*
X1845935Y-60591D01*
X1845095Y-61091D01*
X1845375Y-57841D01*
X1847895D01*
G01X1851568Y-65341D02*
Y-57841D01*
X1853995Y-64091D01*
X1856422Y-57841D01*
Y-65341D01*
G01X1859068D02*
Y-57841D01*
X1861495Y-64091D01*
X1863922Y-57841D01*
Y-65341D01*
G01X1874722D02*
Y-57841D01*
X1878268D01*
G01X1876962Y-61466D02*
X1874722D01*
G01X1882875Y-57841D02*
X1885115D01*
G01X1883995D02*
Y-65341D01*
G01X1882875D02*
X1885115D01*
G01X1889348D02*
Y-57841D01*
X1893642Y-65341D01*
Y-57841D01*
G01X1897875D02*
X1900115D01*
G01X1898995D02*
Y-65341D01*
G01X1897875D02*
X1900115D01*
G01X1904535Y-64341D02*
X1905282Y-64966D01*
X1906122Y-65341D01*
X1906868D01*
X1907615Y-64966D01*
X1908175Y-64341D01*
X1908455Y-63466D01*
X1908268Y-62591D01*
X1907802Y-61841D01*
X1906962Y-61341D01*
X1905842Y-61091D01*
X1905188Y-60591D01*
X1904908Y-59716D01*
X1905095Y-58841D01*
X1905562Y-58216D01*
X1906215Y-57841D01*
X1906868D01*
X1907522Y-58091D01*
X1908082Y-58716D01*
G01X1912035Y-65341D02*
Y-57841D01*
G01X1915955D02*
Y-65341D01*
G01Y-61591D02*
X1912035D01*
G01X1923362Y-65341D02*
X1919628D01*
Y-57841D01*
X1923362D01*
G01X1921868Y-61466D02*
X1919628D01*
G01X1926942Y-65341D02*
Y-57841D01*
X1928808D01*
X1929555Y-58216D01*
X1930115Y-58716D01*
X1930582Y-59466D01*
X1930955Y-60341D01*
X1931048Y-61591D01*
X1930955Y-62841D01*
X1930582Y-63716D01*
X1930115Y-64466D01*
X1929555Y-64966D01*
X1928808Y-65341D01*
X1926942D01*
G01X1942128D02*
Y-57841D01*
X1944368D01*
X1945115Y-58216D01*
X1945675Y-59091D01*
X1945862Y-60091D01*
X1945675Y-61091D01*
X1945208Y-61841D01*
X1944368Y-62216D01*
X1942128D01*
G01X1951495Y-57841D02*
Y-65341D01*
G01X1949348Y-57841D02*
X1953642D01*
G01X1957035Y-65341D02*
Y-57841D01*
G01X1960955D02*
Y-65341D01*
G01Y-61591D02*
X1957035D01*
G01X1972875Y-57841D02*
X1975115D01*
G01X1973995D02*
Y-65341D01*
G01X1972875D02*
X1975115D01*
G01X1979535Y-64341D02*
X1980282Y-64966D01*
X1981122Y-65341D01*
X1981868D01*
X1982615Y-64966D01*
X1983175Y-64341D01*
X1983455Y-63466D01*
X1983268Y-62591D01*
X1982802Y-61841D01*
X1981962Y-61341D01*
X1980842Y-61091D01*
X1980188Y-60591D01*
X1979908Y-59716D01*
X1980095Y-58841D01*
X1980562Y-58216D01*
X1981215Y-57841D01*
X1981868D01*
X1982522Y-58091D01*
X1983082Y-58716D01*
G01X1996495Y-57841D02*
X1995748Y-58091D01*
X1995188Y-58716D01*
X1994815Y-59466D01*
X1994535Y-60466D01*
X1994442Y-61591D01*
X1994535Y-62716D01*
X1994815Y-63716D01*
X1995188Y-64466D01*
X1995748Y-65091D01*
X1996495Y-65341D01*
X1997242Y-65091D01*
X1997802Y-64466D01*
X1998175Y-63716D01*
X1998455Y-62716D01*
X1998548Y-61591D01*
X1998455Y-60466D01*
X1998175Y-59466D01*
X1997802Y-58716D01*
X1997242Y-58091D01*
X1996495Y-57841D01*
G01X2003995Y-65591D02*
X2003808Y-65466D01*
Y-65216D01*
X2003995Y-65091D01*
X2004182Y-65216D01*
Y-65466D01*
X2003995Y-65591D01*
G01X2011495Y-65341D02*
X2012148Y-65216D01*
X2012895Y-64841D01*
X2013362Y-64216D01*
X2013548Y-63341D01*
X2013362Y-62466D01*
X2012802Y-61716D01*
X2011962Y-61341D01*
X2011028D01*
X2010468Y-61091D01*
X2010002Y-60466D01*
X2009815Y-59591D01*
X2010095Y-58716D01*
X2010748Y-58091D01*
X2011495Y-57841D01*
X2012242Y-58091D01*
X2012895Y-58716D01*
X2013175Y-59591D01*
X2012988Y-60466D01*
X2012522Y-61091D01*
X2011962Y-61341D01*
X2011028D01*
X2010188Y-61716D01*
X2009628Y-62466D01*
X2009442Y-63341D01*
X2009628Y-64216D01*
X2010095Y-64841D01*
X2010842Y-65216D01*
X2011495Y-65341D01*
G01X2018995D02*
Y-57841D01*
X2017875Y-59341D01*
G01Y-65341D02*
X2020115D01*
G01X2025282Y-62841D02*
X2027708D01*
G01X2033995Y-57841D02*
X2033248Y-58091D01*
X2032688Y-58716D01*
X2032315Y-59466D01*
X2032035Y-60466D01*
X2031942Y-61591D01*
X2032035Y-62716D01*
X2032315Y-63716D01*
X2032688Y-64466D01*
X2033248Y-65091D01*
X2033995Y-65341D01*
X2034742Y-65091D01*
X2035302Y-64466D01*
X2035675Y-63716D01*
X2035955Y-62716D01*
X2036048Y-61591D01*
X2035955Y-60466D01*
X2035675Y-59466D01*
X2035302Y-58716D01*
X2034742Y-58091D01*
X2033995Y-57841D01*
G01X2041495Y-65591D02*
X2041308Y-65466D01*
Y-65216D01*
X2041495Y-65091D01*
X2041682Y-65216D01*
Y-65466D01*
X2041495Y-65591D01*
G01X2048995Y-65341D02*
X2049648Y-65216D01*
X2050395Y-64841D01*
X2050862Y-64216D01*
X2051048Y-63341D01*
X2050862Y-62466D01*
X2050302Y-61716D01*
X2049462Y-61341D01*
X2048528D01*
X2047968Y-61091D01*
X2047502Y-60466D01*
X2047315Y-59591D01*
X2047595Y-58716D01*
X2048248Y-58091D01*
X2048995Y-57841D01*
X2049742Y-58091D01*
X2050395Y-58716D01*
X2050675Y-59591D01*
X2050488Y-60466D01*
X2050022Y-61091D01*
X2049462Y-61341D01*
X2048528D01*
X2047688Y-61716D01*
X2047128Y-62466D01*
X2046942Y-63341D01*
X2047128Y-64216D01*
X2047595Y-64841D01*
X2048342Y-65216D01*
X2048995Y-65341D01*
G01X2054722Y-62216D02*
X2055375Y-61341D01*
X2055935Y-60841D01*
X2056682Y-60591D01*
X2057335Y-60841D01*
X2057802Y-61341D01*
X2058175Y-62091D01*
X2058268Y-62966D01*
X2058175Y-63716D01*
X2057802Y-64466D01*
X2057242Y-65091D01*
X2056588Y-65341D01*
X2055842Y-65091D01*
X2055188Y-64341D01*
X2054815Y-63216D01*
X2054722Y-61966D01*
X2054908Y-60341D01*
X2055188Y-59466D01*
X2055655Y-58591D01*
X2056308Y-57966D01*
X2056962Y-57841D01*
X2057615Y-58091D01*
X2058082Y-58716D01*
G01X2061568Y-65341D02*
Y-57841D01*
X2063995Y-64091D01*
X2066422Y-57841D01*
Y-65341D01*
G01X2069068D02*
Y-57841D01*
X2071495Y-64091D01*
X2073922Y-57841D01*
Y-65341D01*
G01X2078528Y-67841D02*
X2077595Y-66591D01*
X2077128Y-65341D01*
Y-60341D01*
X2077595Y-59091D01*
X2078528Y-57841D01*
G01X2086495D02*
X2085748Y-58091D01*
X2085188Y-58716D01*
X2084815Y-59466D01*
X2084535Y-60466D01*
X2084442Y-61591D01*
X2084535Y-62716D01*
X2084815Y-63716D01*
X2085188Y-64466D01*
X2085748Y-65091D01*
X2086495Y-65341D01*
X2087242Y-65091D01*
X2087802Y-64466D01*
X2088175Y-63716D01*
X2088455Y-62716D01*
X2088548Y-61591D01*
X2088455Y-60466D01*
X2088175Y-59466D01*
X2087802Y-58716D01*
X2087242Y-58091D01*
X2086495Y-57841D01*
G01X2093995Y-65591D02*
X2093808Y-65466D01*
Y-65216D01*
X2093995Y-65091D01*
X2094182Y-65216D01*
Y-65466D01*
X2093995Y-65591D01*
G01X2101495Y-65341D02*
X2102148Y-65216D01*
X2102895Y-64841D01*
X2103362Y-64216D01*
X2103548Y-63341D01*
X2103362Y-62466D01*
X2102802Y-61716D01*
X2101962Y-61341D01*
X2101028D01*
X2100468Y-61091D01*
X2100002Y-60466D01*
X2099815Y-59591D01*
X2100095Y-58716D01*
X2100748Y-58091D01*
X2101495Y-57841D01*
X2102242Y-58091D01*
X2102895Y-58716D01*
X2103175Y-59591D01*
X2102988Y-60466D01*
X2102522Y-61091D01*
X2101962Y-61341D01*
X2101028D01*
X2100188Y-61716D01*
X2099628Y-62466D01*
X2099442Y-63341D01*
X2099628Y-64216D01*
X2100095Y-64841D01*
X2100842Y-65216D01*
X2101495Y-65341D01*
G01X2106942Y-64216D02*
X2107502Y-64841D01*
X2108155Y-65216D01*
X2108995Y-65341D01*
X2109835Y-65091D01*
X2110488Y-64591D01*
X2110955Y-63716D01*
X2111048Y-62716D01*
X2110862Y-61716D01*
X2110395Y-61091D01*
X2109742Y-60591D01*
X2109088Y-60466D01*
X2108435Y-60591D01*
X2107595Y-61091D01*
X2107875Y-57841D01*
X2110395D01*
G01X2114068Y-65341D02*
Y-57841D01*
X2116495Y-64091D01*
X2118922Y-57841D01*
Y-65341D01*
G01X2121568D02*
Y-57841D01*
X2123995Y-64091D01*
X2126422Y-57841D01*
Y-65341D01*
G01X2136942D02*
Y-57841D01*
X2138808D01*
X2139555Y-58216D01*
X2140115Y-58716D01*
X2140582Y-59466D01*
X2140955Y-60341D01*
X2141048Y-61591D01*
X2140955Y-62841D01*
X2140582Y-63716D01*
X2140115Y-64466D01*
X2139555Y-64966D01*
X2138808Y-65341D01*
X2136942D01*
G01X2144628D02*
Y-57841D01*
X2146962D01*
X2147708Y-58216D01*
X2148175Y-58716D01*
X2148362Y-59716D01*
X2148175Y-60716D01*
X2147615Y-61341D01*
X2146962Y-61716D01*
X2144628D01*
G01X2146962D02*
X2148362Y-65341D01*
G01X2152875Y-57841D02*
X2155115D01*
G01X2153995D02*
Y-65341D01*
G01X2152875D02*
X2155115D01*
G01X2159628Y-57841D02*
Y-65341D01*
X2163362D01*
G01X2167128Y-57841D02*
Y-65341D01*
X2170862D01*
G01X2176962Y-67841D02*
X2177895Y-66591D01*
X2178362Y-65341D01*
Y-60341D01*
X2177895Y-59091D01*
X2176962Y-57841D01*
G01X1463295Y-45441D02*
Y-52941D01*
G01X1461148Y-45441D02*
X1465442D01*
G01X1469675D02*
X1471915D01*
G01X1470795D02*
Y-52941D01*
G01X1469675D02*
X1471915D01*
G01X1476148D02*
Y-45441D01*
X1480442Y-52941D01*
Y-45441D01*
G01X1484582Y-50441D02*
X1487008D01*
G01X1491428Y-45441D02*
Y-52941D01*
X1495162D01*
G01X1502662D02*
X1498928D01*
Y-45441D01*
X1502662D01*
G01X1501168Y-49066D02*
X1498928D01*
G01X1505962Y-52941D02*
X1508295Y-45441D01*
X1510628Y-52941D01*
G01X1509788Y-50316D02*
X1506802D01*
G01X1513742Y-52941D02*
Y-45441D01*
X1515608D01*
X1516355Y-45816D01*
X1516915Y-46316D01*
X1517382Y-47066D01*
X1517755Y-47941D01*
X1517848Y-49191D01*
X1517755Y-50441D01*
X1517382Y-51316D01*
X1516915Y-52066D01*
X1516355Y-52566D01*
X1515608Y-52941D01*
X1513742D01*
G01X1523295Y-53191D02*
X1523108Y-53066D01*
Y-52816D01*
X1523295Y-52691D01*
X1523482Y-52816D01*
Y-53066D01*
X1523295Y-53191D01*
G01Y-49816D02*
X1523108Y-49691D01*
Y-49441D01*
X1523295Y-49316D01*
X1523482Y-49441D01*
Y-49691D01*
X1523295Y-49816D01*
G01X1528928Y-52941D02*
Y-45441D01*
X1531262D01*
X1532008Y-45816D01*
X1532475Y-46316D01*
X1532662Y-47316D01*
X1532475Y-48316D01*
X1531915Y-48941D01*
X1531262Y-49316D01*
X1528928D01*
G01X1531262D02*
X1532662Y-52941D01*
G01X1540162D02*
X1536428D01*
Y-45441D01*
X1540162D01*
G01X1538668Y-49066D02*
X1536428D01*
G01X1547848Y-46066D02*
X1547288Y-45691D01*
X1546635Y-45441D01*
X1545888D01*
X1545048Y-45816D01*
X1544395Y-46441D01*
X1543928Y-47191D01*
X1543555Y-48441D01*
X1543462Y-49566D01*
X1543648Y-50691D01*
X1543928Y-51441D01*
X1544488Y-52191D01*
X1545142Y-52691D01*
X1545795Y-52941D01*
X1546448D01*
X1547102Y-52691D01*
X1547662Y-52316D01*
X1548128Y-51816D01*
G01X1553295Y-52941D02*
X1552548Y-52816D01*
X1551895Y-52316D01*
X1551335Y-51566D01*
X1550962Y-50691D01*
X1550775Y-49691D01*
Y-48691D01*
X1550962Y-47691D01*
X1551335Y-46816D01*
X1551895Y-46066D01*
X1552548Y-45566D01*
X1553295Y-45441D01*
X1554042Y-45566D01*
X1554695Y-46066D01*
X1555255Y-46816D01*
X1555628Y-47691D01*
X1555815Y-48691D01*
Y-49691D01*
X1555628Y-50691D01*
X1555255Y-51566D01*
X1554695Y-52316D01*
X1554042Y-52816D01*
X1553295Y-52941D01*
G01X1558368D02*
Y-45441D01*
X1560795Y-51691D01*
X1563222Y-45441D01*
Y-52941D01*
G01X1565868D02*
Y-45441D01*
X1568295Y-51691D01*
X1570722Y-45441D01*
Y-52941D01*
G01X1577662D02*
X1573928D01*
Y-45441D01*
X1577662D01*
G01X1576168Y-49066D02*
X1573928D01*
G01X1581148Y-52941D02*
Y-45441D01*
X1585442Y-52941D01*
Y-45441D01*
G01X1588742Y-52941D02*
Y-45441D01*
X1590608D01*
X1591355Y-45816D01*
X1591915Y-46316D01*
X1592382Y-47066D01*
X1592755Y-47941D01*
X1592848Y-49191D01*
X1592755Y-50441D01*
X1592382Y-51316D01*
X1591915Y-52066D01*
X1591355Y-52566D01*
X1590608Y-52941D01*
X1588742D01*
G01X1600162D02*
X1596428D01*
Y-45441D01*
X1600162D01*
G01X1598668Y-49066D02*
X1596428D01*
G01X1603742Y-52941D02*
Y-45441D01*
X1605608D01*
X1606355Y-45816D01*
X1606915Y-46316D01*
X1607382Y-47066D01*
X1607755Y-47941D01*
X1607848Y-49191D01*
X1607755Y-50441D01*
X1607382Y-51316D01*
X1606915Y-52066D01*
X1606355Y-52566D01*
X1605608Y-52941D01*
X1603742D01*
G01X1618742D02*
Y-45441D01*
X1620608D01*
X1621355Y-45816D01*
X1621915Y-46316D01*
X1622382Y-47066D01*
X1622755Y-47941D01*
X1622848Y-49191D01*
X1622755Y-50441D01*
X1622382Y-51316D01*
X1621915Y-52066D01*
X1621355Y-52566D01*
X1620608Y-52941D01*
X1618742D01*
G01X1626428D02*
Y-45441D01*
X1628762D01*
X1629508Y-45816D01*
X1629975Y-46316D01*
X1630162Y-47316D01*
X1629975Y-48316D01*
X1629415Y-48941D01*
X1628762Y-49316D01*
X1626428D01*
G01X1628762D02*
X1630162Y-52941D01*
G01X1634675Y-45441D02*
X1636915D01*
G01X1635795D02*
Y-52941D01*
G01X1634675D02*
X1636915D01*
G01X1641428Y-45441D02*
Y-52941D01*
X1645162D01*
G01X1648928Y-45441D02*
Y-52941D01*
X1652662D01*
G01X1663835Y-51941D02*
X1664582Y-52566D01*
X1665422Y-52941D01*
X1666168D01*
X1666915Y-52566D01*
X1667475Y-51941D01*
X1667755Y-51066D01*
X1667568Y-50191D01*
X1667102Y-49441D01*
X1666262Y-48941D01*
X1665142Y-48691D01*
X1664488Y-48191D01*
X1664208Y-47316D01*
X1664395Y-46441D01*
X1664862Y-45816D01*
X1665515Y-45441D01*
X1666168D01*
X1666822Y-45691D01*
X1667382Y-46316D01*
G01X1672175Y-45441D02*
X1674415D01*
G01X1673295D02*
Y-52941D01*
G01X1672175D02*
X1674415D01*
G01X1679022Y-45441D02*
X1682568D01*
X1679022Y-52941D01*
X1682568D01*
G01X1690162D02*
X1686428D01*
Y-45441D01*
X1690162D01*
G01X1688668Y-49066D02*
X1686428D01*
G01X1701522Y-52941D02*
Y-45441D01*
X1705068D01*
G01X1703762Y-49066D02*
X1701522D01*
G01X1710795Y-52941D02*
X1710048Y-52816D01*
X1709395Y-52316D01*
X1708835Y-51566D01*
X1708462Y-50691D01*
X1708275Y-49691D01*
Y-48691D01*
X1708462Y-47691D01*
X1708835Y-46816D01*
X1709395Y-46066D01*
X1710048Y-45566D01*
X1710795Y-45441D01*
X1711542Y-45566D01*
X1712195Y-46066D01*
X1712755Y-46816D01*
X1713128Y-47691D01*
X1713315Y-48691D01*
Y-49691D01*
X1713128Y-50691D01*
X1712755Y-51566D01*
X1712195Y-52316D01*
X1711542Y-52816D01*
X1710795Y-52941D01*
G01X1716428D02*
Y-45441D01*
X1718762D01*
X1719508Y-45816D01*
X1719975Y-46316D01*
X1720162Y-47316D01*
X1719975Y-48316D01*
X1719415Y-48941D01*
X1718762Y-49316D01*
X1716428D01*
G01X1718762D02*
X1720162Y-52941D01*
G01X1733295Y-45441D02*
X1732548Y-45691D01*
X1731988Y-46316D01*
X1731615Y-47066D01*
X1731335Y-48066D01*
X1731242Y-49191D01*
X1731335Y-50316D01*
X1731615Y-51316D01*
X1731988Y-52066D01*
X1732548Y-52691D01*
X1733295Y-52941D01*
X1734042Y-52691D01*
X1734602Y-52066D01*
X1734975Y-51316D01*
X1735255Y-50316D01*
X1735348Y-49191D01*
X1735255Y-48066D01*
X1734975Y-47066D01*
X1734602Y-46316D01*
X1734042Y-45691D01*
X1733295Y-45441D01*
G01X1740795Y-53191D02*
X1740608Y-53066D01*
Y-52816D01*
X1740795Y-52691D01*
X1740982Y-52816D01*
Y-53066D01*
X1740795Y-53191D01*
G01X1748108Y-52941D02*
X1748295Y-51316D01*
X1748575Y-49941D01*
X1748948Y-48691D01*
X1749415Y-47316D01*
X1750162Y-45441D01*
X1746428D01*
G01X1754022Y-46691D02*
X1754582Y-45941D01*
X1755235Y-45566D01*
X1755982Y-45441D01*
X1756915Y-45691D01*
X1757568Y-46316D01*
X1757755Y-47066D01*
X1757662Y-47816D01*
X1757288Y-48441D01*
X1755422Y-49691D01*
X1754582Y-50566D01*
X1754022Y-51816D01*
X1753835Y-52941D01*
X1757755D01*
G01X1761242Y-51816D02*
X1761802Y-52441D01*
X1762455Y-52816D01*
X1763295Y-52941D01*
X1764135Y-52691D01*
X1764788Y-52191D01*
X1765255Y-51316D01*
X1765348Y-50316D01*
X1765162Y-49316D01*
X1764695Y-48691D01*
X1764042Y-48191D01*
X1763388Y-48066D01*
X1762735Y-48191D01*
X1761895Y-48691D01*
X1762175Y-45441D01*
X1764695D01*
G01X1768368Y-52941D02*
Y-45441D01*
X1770795Y-51691D01*
X1773222Y-45441D01*
Y-52941D01*
G01X1775868D02*
Y-45441D01*
X1778295Y-51691D01*
X1780722Y-45441D01*
Y-52941D01*
G01X1791522D02*
Y-45441D01*
X1795068D01*
G01X1793762Y-49066D02*
X1791522D01*
G01X1799675Y-45441D02*
X1801915D01*
G01X1800795D02*
Y-52941D01*
G01X1799675D02*
X1801915D01*
G01X1806148D02*
Y-45441D01*
X1810442Y-52941D01*
Y-45441D01*
G01X1814675D02*
X1816915D01*
G01X1815795D02*
Y-52941D01*
G01X1814675D02*
X1816915D01*
G01X1821335Y-51941D02*
X1822082Y-52566D01*
X1822922Y-52941D01*
X1823668D01*
X1824415Y-52566D01*
X1824975Y-51941D01*
X1825255Y-51066D01*
X1825068Y-50191D01*
X1824602Y-49441D01*
X1823762Y-48941D01*
X1822642Y-48691D01*
X1821988Y-48191D01*
X1821708Y-47316D01*
X1821895Y-46441D01*
X1822362Y-45816D01*
X1823015Y-45441D01*
X1823668D01*
X1824322Y-45691D01*
X1824882Y-46316D01*
G01X1828835Y-52941D02*
Y-45441D01*
G01X1832755D02*
Y-52941D01*
G01Y-49191D02*
X1828835D01*
G01X1840162Y-52941D02*
X1836428D01*
Y-45441D01*
X1840162D01*
G01X1838668Y-49066D02*
X1836428D01*
G01X1843742Y-52941D02*
Y-45441D01*
X1845608D01*
X1846355Y-45816D01*
X1846915Y-46316D01*
X1847382Y-47066D01*
X1847755Y-47941D01*
X1847848Y-49191D01*
X1847755Y-50441D01*
X1847382Y-51316D01*
X1846915Y-52066D01*
X1846355Y-52566D01*
X1845608Y-52941D01*
X1843742D01*
G01X1858928D02*
Y-45441D01*
X1861168D01*
X1861915Y-45816D01*
X1862475Y-46691D01*
X1862662Y-47691D01*
X1862475Y-48691D01*
X1862008Y-49441D01*
X1861168Y-49816D01*
X1858928D01*
G01X1868295Y-45441D02*
Y-52941D01*
G01X1866148Y-45441D02*
X1870442D01*
G01X1873835Y-52941D02*
Y-45441D01*
G01X1877755D02*
Y-52941D01*
G01Y-49191D02*
X1873835D01*
G01X1889675Y-45441D02*
X1891915D01*
G01X1890795D02*
Y-52941D01*
G01X1889675D02*
X1891915D01*
G01X1896335Y-51941D02*
X1897082Y-52566D01*
X1897922Y-52941D01*
X1898668D01*
X1899415Y-52566D01*
X1899975Y-51941D01*
X1900255Y-51066D01*
X1900068Y-50191D01*
X1899602Y-49441D01*
X1898762Y-48941D01*
X1897642Y-48691D01*
X1896988Y-48191D01*
X1896708Y-47316D01*
X1896895Y-46441D01*
X1897362Y-45816D01*
X1898015Y-45441D01*
X1898668D01*
X1899322Y-45691D01*
X1899882Y-46316D01*
G01X1913295Y-45441D02*
X1912548Y-45691D01*
X1911988Y-46316D01*
X1911615Y-47066D01*
X1911335Y-48066D01*
X1911242Y-49191D01*
X1911335Y-50316D01*
X1911615Y-51316D01*
X1911988Y-52066D01*
X1912548Y-52691D01*
X1913295Y-52941D01*
X1914042Y-52691D01*
X1914602Y-52066D01*
X1914975Y-51316D01*
X1915255Y-50316D01*
X1915348Y-49191D01*
X1915255Y-48066D01*
X1914975Y-47066D01*
X1914602Y-46316D01*
X1914042Y-45691D01*
X1913295Y-45441D01*
G01X1920795Y-53191D02*
X1920608Y-53066D01*
Y-52816D01*
X1920795Y-52691D01*
X1920982Y-52816D01*
Y-53066D01*
X1920795Y-53191D01*
G01X1928295Y-52941D02*
X1928948Y-52816D01*
X1929695Y-52441D01*
X1930162Y-51816D01*
X1930348Y-50941D01*
X1930162Y-50066D01*
X1929602Y-49316D01*
X1928762Y-48941D01*
X1927828D01*
X1927268Y-48691D01*
X1926802Y-48066D01*
X1926615Y-47191D01*
X1926895Y-46316D01*
X1927548Y-45691D01*
X1928295Y-45441D01*
X1929042Y-45691D01*
X1929695Y-46316D01*
X1929975Y-47191D01*
X1929788Y-48066D01*
X1929322Y-48691D01*
X1928762Y-48941D01*
X1927828D01*
X1926988Y-49316D01*
X1926428Y-50066D01*
X1926242Y-50941D01*
X1926428Y-51816D01*
X1926895Y-52441D01*
X1927642Y-52816D01*
X1928295Y-52941D01*
G01X1935795D02*
Y-45441D01*
X1934675Y-46941D01*
G01Y-52941D02*
X1936915D01*
G01X1942082Y-50441D02*
X1944508D01*
G01X1950795Y-45441D02*
X1950048Y-45691D01*
X1949488Y-46316D01*
X1949115Y-47066D01*
X1948835Y-48066D01*
X1948742Y-49191D01*
X1948835Y-50316D01*
X1949115Y-51316D01*
X1949488Y-52066D01*
X1950048Y-52691D01*
X1950795Y-52941D01*
X1951542Y-52691D01*
X1952102Y-52066D01*
X1952475Y-51316D01*
X1952755Y-50316D01*
X1952848Y-49191D01*
X1952755Y-48066D01*
X1952475Y-47066D01*
X1952102Y-46316D01*
X1951542Y-45691D01*
X1950795Y-45441D01*
G01X1958295Y-53191D02*
X1958108Y-53066D01*
Y-52816D01*
X1958295Y-52691D01*
X1958482Y-52816D01*
Y-53066D01*
X1958295Y-53191D01*
G01X1965795Y-52941D02*
X1966448Y-52816D01*
X1967195Y-52441D01*
X1967662Y-51816D01*
X1967848Y-50941D01*
X1967662Y-50066D01*
X1967102Y-49316D01*
X1966262Y-48941D01*
X1965328D01*
X1964768Y-48691D01*
X1964302Y-48066D01*
X1964115Y-47191D01*
X1964395Y-46316D01*
X1965048Y-45691D01*
X1965795Y-45441D01*
X1966542Y-45691D01*
X1967195Y-46316D01*
X1967475Y-47191D01*
X1967288Y-48066D01*
X1966822Y-48691D01*
X1966262Y-48941D01*
X1965328D01*
X1964488Y-49316D01*
X1963928Y-50066D01*
X1963742Y-50941D01*
X1963928Y-51816D01*
X1964395Y-52441D01*
X1965142Y-52816D01*
X1965795Y-52941D01*
G01X1971522Y-49816D02*
X1972175Y-48941D01*
X1972735Y-48441D01*
X1973482Y-48191D01*
X1974135Y-48441D01*
X1974602Y-48941D01*
X1974975Y-49691D01*
X1975068Y-50566D01*
X1974975Y-51316D01*
X1974602Y-52066D01*
X1974042Y-52691D01*
X1973388Y-52941D01*
X1972642Y-52691D01*
X1971988Y-51941D01*
X1971615Y-50816D01*
X1971522Y-49566D01*
X1971708Y-47941D01*
X1971988Y-47066D01*
X1972455Y-46191D01*
X1973108Y-45566D01*
X1973762Y-45441D01*
X1974415Y-45691D01*
X1974882Y-46316D01*
G01X1978368Y-52941D02*
Y-45441D01*
X1980795Y-51691D01*
X1983222Y-45441D01*
Y-52941D01*
G01X1985868D02*
Y-45441D01*
X1988295Y-51691D01*
X1990722Y-45441D01*
Y-52941D01*
G01X1995328Y-55441D02*
X1994395Y-54191D01*
X1993928Y-52941D01*
Y-47941D01*
X1994395Y-46691D01*
X1995328Y-45441D01*
G01X2003295D02*
X2002548Y-45691D01*
X2001988Y-46316D01*
X2001615Y-47066D01*
X2001335Y-48066D01*
X2001242Y-49191D01*
X2001335Y-50316D01*
X2001615Y-51316D01*
X2001988Y-52066D01*
X2002548Y-52691D01*
X2003295Y-52941D01*
X2004042Y-52691D01*
X2004602Y-52066D01*
X2004975Y-51316D01*
X2005255Y-50316D01*
X2005348Y-49191D01*
X2005255Y-48066D01*
X2004975Y-47066D01*
X2004602Y-46316D01*
X2004042Y-45691D01*
X2003295Y-45441D01*
G01X2010795Y-53191D02*
X2010608Y-53066D01*
Y-52816D01*
X2010795Y-52691D01*
X2010982Y-52816D01*
Y-53066D01*
X2010795Y-53191D01*
G01X2018295Y-52941D02*
X2018948Y-52816D01*
X2019695Y-52441D01*
X2020162Y-51816D01*
X2020348Y-50941D01*
X2020162Y-50066D01*
X2019602Y-49316D01*
X2018762Y-48941D01*
X2017828D01*
X2017268Y-48691D01*
X2016802Y-48066D01*
X2016615Y-47191D01*
X2016895Y-46316D01*
X2017548Y-45691D01*
X2018295Y-45441D01*
X2019042Y-45691D01*
X2019695Y-46316D01*
X2019975Y-47191D01*
X2019788Y-48066D01*
X2019322Y-48691D01*
X2018762Y-48941D01*
X2017828D01*
X2016988Y-49316D01*
X2016428Y-50066D01*
X2016242Y-50941D01*
X2016428Y-51816D01*
X2016895Y-52441D01*
X2017642Y-52816D01*
X2018295Y-52941D01*
G01X2023742Y-51816D02*
X2024302Y-52441D01*
X2024955Y-52816D01*
X2025795Y-52941D01*
X2026635Y-52691D01*
X2027288Y-52191D01*
X2027755Y-51316D01*
X2027848Y-50316D01*
X2027662Y-49316D01*
X2027195Y-48691D01*
X2026542Y-48191D01*
X2025888Y-48066D01*
X2025235Y-48191D01*
X2024395Y-48691D01*
X2024675Y-45441D01*
X2027195D01*
G01X2030868Y-52941D02*
Y-45441D01*
X2033295Y-51691D01*
X2035722Y-45441D01*
Y-52941D01*
G01X2038368D02*
Y-45441D01*
X2040795Y-51691D01*
X2043222Y-45441D01*
Y-52941D01*
G01X2053742D02*
Y-45441D01*
X2055608D01*
X2056355Y-45816D01*
X2056915Y-46316D01*
X2057382Y-47066D01*
X2057755Y-47941D01*
X2057848Y-49191D01*
X2057755Y-50441D01*
X2057382Y-51316D01*
X2056915Y-52066D01*
X2056355Y-52566D01*
X2055608Y-52941D01*
X2053742D01*
G01X2061428D02*
Y-45441D01*
X2063762D01*
X2064508Y-45816D01*
X2064975Y-46316D01*
X2065162Y-47316D01*
X2064975Y-48316D01*
X2064415Y-48941D01*
X2063762Y-49316D01*
X2061428D01*
G01X2063762D02*
X2065162Y-52941D01*
G01X2069675Y-45441D02*
X2071915D01*
G01X2070795D02*
Y-52941D01*
G01X2069675D02*
X2071915D01*
G01X2076428Y-45441D02*
Y-52941D01*
X2080162D01*
G01X2083928Y-45441D02*
Y-52941D01*
X2087662D01*
G01X2093762Y-55441D02*
X2094695Y-54191D01*
X2095162Y-52941D01*
Y-47941D01*
X2094695Y-46691D01*
X2093762Y-45441D01*
G01X1470009Y32453D02*
Y39953D01*
X1472249D01*
X1472996Y39578D01*
X1473556Y38703D01*
X1473743Y37703D01*
X1473556Y36703D01*
X1473089Y35953D01*
X1472249Y35578D01*
X1470009D01*
G01X1479376Y39953D02*
Y32453D01*
G01X1477229Y39953D02*
X1481523D01*
G01X1484916Y32453D02*
Y39953D01*
G01X1488836D02*
Y32453D01*
G01Y36203D02*
X1484916D01*
G01X1669767Y-16086D02*
Y-8586D01*
X1672007D01*
X1672754Y-8961D01*
X1673314Y-9836D01*
X1673501Y-10836D01*
X1673314Y-11836D01*
X1672847Y-12586D01*
X1672007Y-12961D01*
X1669767D01*
G01X1679134Y-8586D02*
Y-16086D01*
G01X1676987Y-8586D02*
X1681281D01*
G01X1684674Y-16086D02*
Y-8586D01*
G01X1688594D02*
Y-16086D01*
G01Y-12336D02*
X1684674D01*
G01X1676471Y295301D02*
Y302801D01*
X1678711D01*
X1679458Y302426D01*
X1680018Y301551D01*
X1680205Y300551D01*
X1680018Y299551D01*
X1679551Y298801D01*
X1678711Y298426D01*
X1676471D01*
G01X1685838Y302801D02*
Y295301D01*
G01X1683691Y302801D02*
X1687985D01*
G01X1691378Y295301D02*
Y302801D01*
G01X1695298D02*
Y295301D01*
G01Y299051D02*
X1691378D01*
G01X1770250Y742100D02*
X1757750D01*
X1760250Y740240D01*
G01X1770250D02*
Y743960D01*
G01X1765042Y751555D02*
X1763583Y752640D01*
X1762750Y753570D01*
X1762333Y754810D01*
X1762750Y755895D01*
X1763583Y756670D01*
X1764833Y757290D01*
X1766292Y757445D01*
X1767542Y757290D01*
X1768792Y756670D01*
X1769833Y755740D01*
X1770250Y754655D01*
X1769833Y753415D01*
X1768584Y752330D01*
X1766708Y751710D01*
X1764625Y751555D01*
X1761917Y751865D01*
X1760458Y752330D01*
X1759000Y753105D01*
X1757958Y754190D01*
X1757750Y755275D01*
X1758167Y756360D01*
X1759208Y757135D01*
G01X1770250Y766900D02*
X1770042Y767985D01*
X1769417Y769225D01*
X1768375Y770000D01*
X1766917Y770310D01*
X1765459Y770000D01*
X1764208Y769070D01*
X1763583Y767675D01*
Y766125D01*
X1763167Y765195D01*
X1762125Y764420D01*
X1760667Y764110D01*
X1759208Y764575D01*
X1758167Y765660D01*
X1757750Y766900D01*
X1758167Y768140D01*
X1759208Y769225D01*
X1760667Y769690D01*
X1762125Y769380D01*
X1763167Y768605D01*
X1763583Y767675D01*
Y766125D01*
X1764208Y764730D01*
X1765459Y763800D01*
X1766917Y763490D01*
X1768375Y763800D01*
X1769417Y764575D01*
X1770042Y765815D01*
X1770250Y766900D01*
G01X1768375Y775890D02*
X1769417Y776820D01*
X1770042Y777905D01*
X1770250Y779300D01*
X1769833Y780695D01*
X1769000Y781780D01*
X1767542Y782555D01*
X1765875Y782710D01*
X1764208Y782400D01*
X1763167Y781625D01*
X1762333Y780540D01*
X1762125Y779455D01*
X1762333Y778370D01*
X1763167Y776975D01*
X1757750Y777440D01*
Y781625D01*
G01Y791700D02*
X1758167Y790460D01*
X1759208Y789530D01*
X1760458Y788910D01*
X1762125Y788445D01*
X1764000Y788290D01*
X1765875Y788445D01*
X1767542Y788910D01*
X1768792Y789530D01*
X1769833Y790460D01*
X1770250Y791700D01*
X1769833Y792940D01*
X1768792Y793870D01*
X1767542Y794490D01*
X1765875Y794955D01*
X1764000Y795110D01*
X1762125Y794955D01*
X1760458Y794490D01*
X1759208Y793870D01*
X1758167Y792940D01*
X1757750Y791700D01*
G01X1770667Y804100D02*
X1770458Y803790D01*
X1770042D01*
X1769833Y804100D01*
X1770042Y804410D01*
X1770458D01*
X1770667Y804100D01*
G01X1770250Y818360D02*
X1757750D01*
X1766708Y812625D01*
Y820375D01*
G01X1757750Y828900D02*
X1758167Y827660D01*
X1759208Y826730D01*
X1760458Y826110D01*
X1762125Y825645D01*
X1764000Y825490D01*
X1765875Y825645D01*
X1767542Y826110D01*
X1768792Y826730D01*
X1769833Y827660D01*
X1770250Y828900D01*
X1769833Y830140D01*
X1768792Y831070D01*
X1767542Y831690D01*
X1765875Y832155D01*
X1764000Y832310D01*
X1762125Y832155D01*
X1760458Y831690D01*
X1759208Y831070D01*
X1758167Y830140D01*
X1757750Y828900D01*
G01X1783007Y51427D02*
Y58927D01*
X1785247D01*
X1785994Y58552D01*
X1786554Y57677D01*
X1786741Y56677D01*
X1786554Y55677D01*
X1786087Y54927D01*
X1785247Y54552D01*
X1783007D01*
G01X1792374Y58927D02*
Y51427D01*
G01X1790227Y58927D02*
X1794521D01*
G01X1797914Y51427D02*
Y58927D01*
G01X1801834D02*
Y51427D01*
G01Y55177D02*
X1797914D01*
G01X1783551Y443110D02*
Y450610D01*
X1785791D01*
X1786538Y450235D01*
X1787098Y449360D01*
X1787285Y448360D01*
X1787098Y447360D01*
X1786631Y446610D01*
X1785791Y446235D01*
X1783551D01*
G01X1792918Y450610D02*
Y443110D01*
G01X1790771Y450610D02*
X1795065D01*
G01X1798458Y443110D02*
Y450610D01*
G01X1802378D02*
Y443110D01*
G01Y446860D02*
X1798458D01*
G01X1795250Y775110D02*
X1782750D01*
X1791708Y769375D01*
Y777125D01*
G01X1784833Y782705D02*
X1783584Y783635D01*
X1782958Y784720D01*
X1782750Y785960D01*
X1783167Y787510D01*
X1784208Y788595D01*
X1785458Y788905D01*
X1786709Y788750D01*
X1787750Y788130D01*
X1789833Y785030D01*
X1791292Y783635D01*
X1793375Y782705D01*
X1795250Y782395D01*
Y788905D01*
G01Y798050D02*
X1795042Y799135D01*
X1794417Y800375D01*
X1793375Y801150D01*
X1791917Y801460D01*
X1790459Y801150D01*
X1789208Y800220D01*
X1788583Y798825D01*
Y797275D01*
X1788167Y796345D01*
X1787125Y795570D01*
X1785667Y795260D01*
X1784208Y795725D01*
X1783167Y796810D01*
X1782750Y798050D01*
X1783167Y799290D01*
X1784208Y800375D01*
X1785667Y800840D01*
X1787125Y800530D01*
X1788167Y799755D01*
X1788583Y798825D01*
Y797275D01*
X1789208Y795880D01*
X1790459Y794950D01*
X1791917Y794640D01*
X1793375Y794950D01*
X1794417Y795725D01*
X1795042Y796965D01*
X1795250Y798050D01*
G01X1822337Y125016D02*
Y132516D01*
X1824577D01*
X1825324Y132141D01*
X1825884Y131266D01*
X1826071Y130266D01*
X1825884Y129266D01*
X1825417Y128516D01*
X1824577Y128141D01*
X1822337D01*
G01X1831704Y132516D02*
Y125016D01*
G01X1829557Y132516D02*
X1833851D01*
G01X1837244Y125016D02*
Y132516D01*
G01X1841164D02*
Y125016D01*
G01Y128766D02*
X1837244D01*
G01X1821117Y503436D02*
Y510936D01*
X1823357D01*
X1824104Y510561D01*
X1824664Y509686D01*
X1824851Y508686D01*
X1824664Y507686D01*
X1824197Y506936D01*
X1823357Y506561D01*
X1821117D01*
G01X1830484Y510936D02*
Y503436D01*
G01X1828337Y510936D02*
X1832631D01*
G01X1836024Y503436D02*
Y510936D01*
G01X1839944D02*
Y503436D01*
G01Y507186D02*
X1836024D01*
G01X1827250Y734100D02*
X1814750D01*
X1817250Y732240D01*
G01X1827250D02*
Y735960D01*
G01Y746190D02*
X1824542Y746500D01*
X1822250Y746965D01*
X1820167Y747585D01*
X1817875Y748360D01*
X1814750Y749600D01*
Y743400D01*
G01X1825792Y756265D02*
X1826833Y757350D01*
X1827250Y758590D01*
X1826833Y759830D01*
X1825584Y760915D01*
X1823708Y761690D01*
X1821833Y762000D01*
X1819542D01*
X1817667Y761690D01*
X1816000Y760915D01*
X1815167Y759985D01*
X1814750Y758900D01*
X1815167Y757660D01*
X1816000Y756730D01*
X1817250Y756110D01*
X1818917Y755800D01*
X1820375Y756110D01*
X1821833Y756885D01*
X1822667Y757815D01*
X1822875Y758900D01*
X1822459Y760140D01*
X1821417Y761070D01*
X1819542Y762000D01*
G01X1825792Y768665D02*
X1826833Y769750D01*
X1827250Y770990D01*
X1826833Y772230D01*
X1825584Y773315D01*
X1823708Y774090D01*
X1821833Y774400D01*
X1819542D01*
X1817667Y774090D01*
X1816000Y773315D01*
X1815167Y772385D01*
X1814750Y771300D01*
X1815167Y770060D01*
X1816000Y769130D01*
X1817250Y768510D01*
X1818917Y768200D01*
X1820375Y768510D01*
X1821833Y769285D01*
X1822667Y770215D01*
X1822875Y771300D01*
X1822459Y772540D01*
X1821417Y773470D01*
X1819542Y774400D01*
G01X1816833Y780755D02*
X1815584Y781685D01*
X1814958Y782770D01*
X1814750Y784010D01*
X1815167Y785560D01*
X1816208Y786645D01*
X1817458Y786955D01*
X1818709Y786800D01*
X1819750Y786180D01*
X1821833Y783080D01*
X1823292Y781685D01*
X1825375Y780755D01*
X1827250Y780445D01*
Y786955D01*
G01X1827667Y796100D02*
X1827458Y795790D01*
X1827042D01*
X1826833Y796100D01*
X1827042Y796410D01*
X1827458D01*
X1827667Y796100D01*
G01X1827250Y808500D02*
X1814750D01*
X1817250Y806640D01*
G01X1827250D02*
Y810360D01*
G01X1816833Y817955D02*
X1815584Y818885D01*
X1814958Y819970D01*
X1814750Y821210D01*
X1815167Y822760D01*
X1816208Y823845D01*
X1817458Y824155D01*
X1818709Y824000D01*
X1819750Y823380D01*
X1821833Y820280D01*
X1823292Y818885D01*
X1825375Y817955D01*
X1827250Y817645D01*
Y824155D01*
G01X1852250Y767110D02*
X1839750D01*
X1848708Y761375D01*
Y769125D01*
G01X1850375Y774240D02*
X1851417Y775170D01*
X1852042Y776255D01*
X1852250Y777650D01*
X1851833Y779045D01*
X1851000Y780130D01*
X1849542Y780905D01*
X1847875Y781060D01*
X1846208Y780750D01*
X1845167Y779975D01*
X1844333Y778890D01*
X1844125Y777805D01*
X1844333Y776720D01*
X1845167Y775325D01*
X1839750Y775790D01*
Y779975D01*
G01X1852250Y789740D02*
X1849542Y790050D01*
X1847250Y790515D01*
X1845167Y791135D01*
X1842875Y791910D01*
X1839750Y793150D01*
Y786950D01*
G01X1883390Y310750D02*
X1884320Y309291D01*
X1885560Y308458D01*
X1886955Y308250D01*
X1888195Y308458D01*
X1889435Y309500D01*
X1890210Y310750D01*
X1890365Y312000D01*
X1890055Y313458D01*
X1888970Y314500D01*
X1887885Y314917D01*
X1886490D01*
G01X1887885D02*
X1888815Y315542D01*
X1889590Y316583D01*
X1889900Y317833D01*
X1889590Y319083D01*
X1888815Y320125D01*
X1887420Y320750D01*
X1886025Y320542D01*
X1884630Y319708D01*
G01X1895790Y310750D02*
X1896720Y309291D01*
X1897960Y308458D01*
X1899355Y308250D01*
X1900595Y308458D01*
X1901835Y309500D01*
X1902610Y310750D01*
X1902765Y312000D01*
X1902455Y313458D01*
X1901370Y314500D01*
X1900285Y314917D01*
X1898890D01*
G01X1900285D02*
X1901215Y315542D01*
X1901990Y316583D01*
X1902300Y317833D01*
X1901990Y319083D01*
X1901215Y320125D01*
X1899820Y320750D01*
X1898425Y320542D01*
X1897030Y319708D01*
G01X1911600Y320750D02*
X1910360Y320333D01*
X1909430Y319292D01*
X1908810Y318042D01*
X1908345Y316375D01*
X1908190Y314500D01*
X1908345Y312625D01*
X1908810Y310958D01*
X1909430Y309708D01*
X1910360Y308667D01*
X1911600Y308250D01*
X1912840Y308667D01*
X1913770Y309708D01*
X1914390Y310958D01*
X1914855Y312625D01*
X1915010Y314500D01*
X1914855Y316375D01*
X1914390Y318042D01*
X1913770Y319292D01*
X1912840Y320333D01*
X1911600Y320750D01*
G01X1923690Y308250D02*
X1924000Y310958D01*
X1924465Y313250D01*
X1925085Y315333D01*
X1925860Y317625D01*
X1927100Y320750D01*
X1920900D01*
G01X1936400Y307833D02*
X1936090Y308042D01*
Y308458D01*
X1936400Y308667D01*
X1936710Y308458D01*
Y308042D01*
X1936400Y307833D01*
G01X1948800Y320750D02*
X1947560Y320333D01*
X1946630Y319292D01*
X1946010Y318042D01*
X1945545Y316375D01*
X1945390Y314500D01*
X1945545Y312625D01*
X1946010Y310958D01*
X1946630Y309708D01*
X1947560Y308667D01*
X1948800Y308250D01*
X1950040Y308667D01*
X1950970Y309708D01*
X1951590Y310958D01*
X1952055Y312625D01*
X1952210Y314500D01*
X1952055Y316375D01*
X1951590Y318042D01*
X1950970Y319292D01*
X1950040Y320333D01*
X1948800Y320750D01*
G01X1961200Y308250D02*
X1962285Y308458D01*
X1963525Y309083D01*
X1964300Y310125D01*
X1964610Y311583D01*
X1964300Y313041D01*
X1963370Y314292D01*
X1961975Y314917D01*
X1960425D01*
X1959495Y315333D01*
X1958720Y316375D01*
X1958410Y317833D01*
X1958875Y319292D01*
X1959960Y320333D01*
X1961200Y320750D01*
X1962440Y320333D01*
X1963525Y319292D01*
X1963990Y317833D01*
X1963680Y316375D01*
X1962905Y315333D01*
X1961975Y314917D01*
X1960425D01*
X1959030Y314292D01*
X1958100Y313041D01*
X1957790Y311583D01*
X1958100Y310125D01*
X1958875Y309083D01*
X1960115Y308458D01*
X1961200Y308250D01*
G01X1890250Y767600D02*
X1877750D01*
X1880250Y765740D01*
G01X1890250D02*
Y769460D01*
G01Y780000D02*
X1890042Y781085D01*
X1889417Y782325D01*
X1888375Y783100D01*
X1886917Y783410D01*
X1885459Y783100D01*
X1884208Y782170D01*
X1883583Y780775D01*
Y779225D01*
X1883167Y778295D01*
X1882125Y777520D01*
X1880667Y777210D01*
X1879208Y777675D01*
X1878167Y778760D01*
X1877750Y780000D01*
X1878167Y781240D01*
X1879208Y782325D01*
X1880667Y782790D01*
X1882125Y782480D01*
X1883167Y781705D01*
X1883583Y780775D01*
Y779225D01*
X1884208Y777830D01*
X1885459Y776900D01*
X1886917Y776590D01*
X1888375Y776900D01*
X1889417Y777675D01*
X1890042Y778915D01*
X1890250Y780000D01*
G01Y794260D02*
X1877750D01*
X1886708Y788525D01*
Y796275D01*
G01X1890250Y804800D02*
X1890042Y805885D01*
X1889417Y807125D01*
X1888375Y807900D01*
X1886917Y808210D01*
X1885459Y807900D01*
X1884208Y806970D01*
X1883583Y805575D01*
Y804025D01*
X1883167Y803095D01*
X1882125Y802320D01*
X1880667Y802010D01*
X1879208Y802475D01*
X1878167Y803560D01*
X1877750Y804800D01*
X1878167Y806040D01*
X1879208Y807125D01*
X1880667Y807590D01*
X1882125Y807280D01*
X1883167Y806505D01*
X1883583Y805575D01*
Y804025D01*
X1884208Y802630D01*
X1885459Y801700D01*
X1886917Y801390D01*
X1888375Y801700D01*
X1889417Y802475D01*
X1890042Y803715D01*
X1890250Y804800D01*
G01X1888375Y813790D02*
X1889417Y814720D01*
X1890042Y815805D01*
X1890250Y817200D01*
X1889833Y818595D01*
X1889000Y819680D01*
X1887542Y820455D01*
X1885875Y820610D01*
X1884208Y820300D01*
X1883167Y819525D01*
X1882333Y818440D01*
X1882125Y817355D01*
X1882333Y816270D01*
X1883167Y814875D01*
X1877750Y815340D01*
Y819525D01*
G01X1890667Y829600D02*
X1890458Y829290D01*
X1890042D01*
X1889833Y829600D01*
X1890042Y829910D01*
X1890458D01*
X1890667Y829600D01*
G01X1890250Y842000D02*
X1890042Y843085D01*
X1889417Y844325D01*
X1888375Y845100D01*
X1886917Y845410D01*
X1885459Y845100D01*
X1884208Y844170D01*
X1883583Y842775D01*
Y841225D01*
X1883167Y840295D01*
X1882125Y839520D01*
X1880667Y839210D01*
X1879208Y839675D01*
X1878167Y840760D01*
X1877750Y842000D01*
X1878167Y843240D01*
X1879208Y844325D01*
X1880667Y844790D01*
X1882125Y844480D01*
X1883167Y843705D01*
X1883583Y842775D01*
Y841225D01*
X1884208Y839830D01*
X1885459Y838900D01*
X1886917Y838590D01*
X1888375Y838900D01*
X1889417Y839675D01*
X1890042Y840915D01*
X1890250Y842000D01*
G01X1879833Y851455D02*
X1878584Y852385D01*
X1877958Y853470D01*
X1877750Y854710D01*
X1878167Y856260D01*
X1879208Y857345D01*
X1880458Y857655D01*
X1881709Y857500D01*
X1882750Y856880D01*
X1884833Y853780D01*
X1886292Y852385D01*
X1888375Y851455D01*
X1890250Y851145D01*
Y857655D01*
G01X1906105Y88124D02*
X1907035Y89373D01*
X1908120Y89999D01*
X1909360Y90207D01*
X1910910Y89790D01*
X1911995Y88749D01*
X1912305Y87499D01*
X1912150Y86248D01*
X1911530Y85207D01*
X1908430Y83124D01*
X1907035Y81665D01*
X1906105Y79582D01*
X1905795Y77707D01*
X1912305D01*
G01X1923310D02*
Y90207D01*
X1917575Y81249D01*
X1925325D01*
G01X1933850Y77290D02*
X1933540Y77499D01*
Y77915D01*
X1933850Y78124D01*
X1934160Y77915D01*
Y77499D01*
X1933850Y77290D01*
G01X1942840Y79582D02*
X1943770Y78540D01*
X1944855Y77915D01*
X1946250Y77707D01*
X1947645Y78124D01*
X1948730Y78957D01*
X1949505Y80415D01*
X1949660Y82082D01*
X1949350Y83749D01*
X1948575Y84790D01*
X1947490Y85624D01*
X1946405Y85832D01*
X1945320Y85624D01*
X1943925Y84790D01*
X1944390Y90207D01*
X1948575D01*
G01X1893865Y104165D02*
X1894950Y103124D01*
X1896190Y102707D01*
X1897430Y103124D01*
X1898515Y104373D01*
X1899290Y106249D01*
X1899600Y108124D01*
Y110415D01*
X1899290Y112290D01*
X1898515Y113957D01*
X1897585Y114790D01*
X1896500Y115207D01*
X1895260Y114790D01*
X1894330Y113957D01*
X1893710Y112707D01*
X1893400Y111040D01*
X1893710Y109582D01*
X1894485Y108124D01*
X1895415Y107290D01*
X1896500Y107082D01*
X1897740Y107498D01*
X1898670Y108540D01*
X1899600Y110415D01*
G01X1905955Y107915D02*
X1907040Y109374D01*
X1907970Y110207D01*
X1909210Y110624D01*
X1910295Y110207D01*
X1911070Y109374D01*
X1911690Y108124D01*
X1911845Y106665D01*
X1911690Y105415D01*
X1911070Y104165D01*
X1910140Y103124D01*
X1909055Y102707D01*
X1907815Y103124D01*
X1906730Y104373D01*
X1906110Y106249D01*
X1905955Y108332D01*
X1906265Y111040D01*
X1906730Y112499D01*
X1907505Y113957D01*
X1908590Y114999D01*
X1909675Y115207D01*
X1910760Y114790D01*
X1911535Y113749D01*
G01X1923160Y102707D02*
Y115207D01*
X1917425Y106249D01*
X1925175D01*
G01X1933700Y102290D02*
X1933390Y102499D01*
Y102915D01*
X1933700Y103124D01*
X1934010Y102915D01*
Y102499D01*
X1933700Y102290D01*
G01X1942690Y104582D02*
X1943620Y103540D01*
X1944705Y102915D01*
X1946100Y102707D01*
X1947495Y103124D01*
X1948580Y103957D01*
X1949355Y105415D01*
X1949510Y107082D01*
X1949200Y108749D01*
X1948425Y109790D01*
X1947340Y110624D01*
X1946255Y110832D01*
X1945170Y110624D01*
X1943775Y109790D01*
X1944240Y115207D01*
X1948425D01*
G01X1958190Y102707D02*
X1958500Y105415D01*
X1958965Y107707D01*
X1959585Y109790D01*
X1960360Y112082D01*
X1961600Y115207D01*
X1955400D01*
G01X1894365Y151208D02*
X1895450Y150167D01*
X1896690Y149750D01*
X1897930Y150167D01*
X1899015Y151416D01*
X1899790Y153292D01*
X1900100Y155167D01*
Y157458D01*
X1899790Y159333D01*
X1899015Y161000D01*
X1898085Y161833D01*
X1897000Y162250D01*
X1895760Y161833D01*
X1894830Y161000D01*
X1894210Y159750D01*
X1893900Y158083D01*
X1894210Y156625D01*
X1894985Y155167D01*
X1895915Y154333D01*
X1897000Y154125D01*
X1898240Y154541D01*
X1899170Y155583D01*
X1900100Y157458D01*
G01X1906765Y151208D02*
X1907850Y150167D01*
X1909090Y149750D01*
X1910330Y150167D01*
X1911415Y151416D01*
X1912190Y153292D01*
X1912500Y155167D01*
Y157458D01*
X1912190Y159333D01*
X1911415Y161000D01*
X1910485Y161833D01*
X1909400Y162250D01*
X1908160Y161833D01*
X1907230Y161000D01*
X1906610Y159750D01*
X1906300Y158083D01*
X1906610Y156625D01*
X1907385Y155167D01*
X1908315Y154333D01*
X1909400Y154125D01*
X1910640Y154541D01*
X1911570Y155583D01*
X1912500Y157458D01*
G01X1918855Y160167D02*
X1919785Y161416D01*
X1920870Y162042D01*
X1922110Y162250D01*
X1923660Y161833D01*
X1924745Y160792D01*
X1925055Y159542D01*
X1924900Y158291D01*
X1924280Y157250D01*
X1921180Y155167D01*
X1919785Y153708D01*
X1918855Y151625D01*
X1918545Y149750D01*
X1925055D01*
G01X1934200Y149333D02*
X1933890Y149542D01*
Y149958D01*
X1934200Y150167D01*
X1934510Y149958D01*
Y149542D01*
X1934200Y149333D01*
G01X1946600Y149750D02*
Y162250D01*
X1944740Y159750D01*
G01Y149750D02*
X1948460D01*
G01X1956055Y160167D02*
X1956985Y161416D01*
X1958070Y162042D01*
X1959310Y162250D01*
X1960860Y161833D01*
X1961945Y160792D01*
X1962255Y159542D01*
X1962100Y158291D01*
X1961480Y157250D01*
X1958380Y155167D01*
X1956985Y153708D01*
X1956055Y151625D01*
X1955745Y149750D01*
X1962255D01*
G01X1906605Y135167D02*
X1907535Y136416D01*
X1908620Y137042D01*
X1909860Y137250D01*
X1911410Y136833D01*
X1912495Y135792D01*
X1912805Y134542D01*
X1912650Y133291D01*
X1912030Y132250D01*
X1908930Y130167D01*
X1907535Y128708D01*
X1906605Y126625D01*
X1906295Y124750D01*
X1912805D01*
G01X1918540Y126625D02*
X1919470Y125583D01*
X1920555Y124958D01*
X1921950Y124750D01*
X1923345Y125167D01*
X1924430Y126000D01*
X1925205Y127458D01*
X1925360Y129125D01*
X1925050Y130792D01*
X1924275Y131833D01*
X1923190Y132667D01*
X1922105Y132875D01*
X1921020Y132667D01*
X1919625Y131833D01*
X1920090Y137250D01*
X1924275D01*
G01X1934350Y124333D02*
X1934040Y124542D01*
Y124958D01*
X1934350Y125167D01*
X1934660Y124958D01*
Y124542D01*
X1934350Y124333D01*
G01X1943805Y135167D02*
X1944735Y136416D01*
X1945820Y137042D01*
X1947060Y137250D01*
X1948610Y136833D01*
X1949695Y135792D01*
X1950005Y134542D01*
X1949850Y133291D01*
X1949230Y132250D01*
X1946130Y130167D01*
X1944735Y128708D01*
X1943805Y126625D01*
X1943495Y124750D01*
X1950005D01*
G01X1917950Y283250D02*
X1919035Y283458D01*
X1920275Y284083D01*
X1921050Y285125D01*
X1921360Y286583D01*
X1921050Y288041D01*
X1920120Y289292D01*
X1918725Y289917D01*
X1917175D01*
X1916245Y290333D01*
X1915470Y291375D01*
X1915160Y292833D01*
X1915625Y294292D01*
X1916710Y295333D01*
X1917950Y295750D01*
X1919190Y295333D01*
X1920275Y294292D01*
X1920740Y292833D01*
X1920430Y291375D01*
X1919655Y290333D01*
X1918725Y289917D01*
X1917175D01*
X1915780Y289292D01*
X1914850Y288041D01*
X1914540Y286583D01*
X1914850Y285125D01*
X1915625Y284083D01*
X1916865Y283458D01*
X1917950Y283250D01*
G01X1932210D02*
Y295750D01*
X1926475Y286792D01*
X1934225D01*
G01X1909660Y484596D02*
Y497096D01*
X1903925Y488138D01*
X1911675D01*
G01X1919890Y484596D02*
X1920200Y487304D01*
X1920665Y489596D01*
X1921285Y491679D01*
X1922060Y493971D01*
X1923300Y497096D01*
X1917100D01*
G01X1932600Y484596D02*
X1933685Y484804D01*
X1934925Y485429D01*
X1935700Y486471D01*
X1936010Y487929D01*
X1935700Y489387D01*
X1934770Y490638D01*
X1933375Y491263D01*
X1931825D01*
X1930895Y491679D01*
X1930120Y492721D01*
X1929810Y494179D01*
X1930275Y495638D01*
X1931360Y496679D01*
X1932600Y497096D01*
X1933840Y496679D01*
X1934925Y495638D01*
X1935390Y494179D01*
X1935080Y492721D01*
X1934305Y491679D01*
X1933375Y491263D01*
X1931825D01*
X1930430Y490638D01*
X1929500Y489387D01*
X1929190Y487929D01*
X1929500Y486471D01*
X1930275Y485429D01*
X1931515Y484804D01*
X1932600Y484596D01*
G01X1941590Y487096D02*
X1942520Y485637D01*
X1943760Y484804D01*
X1945155Y484596D01*
X1946395Y484804D01*
X1947635Y485846D01*
X1948410Y487096D01*
X1948565Y488346D01*
X1948255Y489804D01*
X1947170Y490846D01*
X1946085Y491263D01*
X1944690D01*
G01X1946085D02*
X1947015Y491888D01*
X1947790Y492929D01*
X1948100Y494179D01*
X1947790Y495429D01*
X1947015Y496471D01*
X1945620Y497096D01*
X1944225Y496888D01*
X1942830Y496054D01*
G01X1957400Y484179D02*
X1957090Y484388D01*
Y484804D01*
X1957400Y485013D01*
X1957710Y484804D01*
Y484388D01*
X1957400Y484179D01*
G01X1971660Y484596D02*
Y497096D01*
X1965925Y488138D01*
X1973675D01*
G01X1979255Y489804D02*
X1980340Y491263D01*
X1981270Y492096D01*
X1982510Y492513D01*
X1983595Y492096D01*
X1984370Y491263D01*
X1984990Y490013D01*
X1985145Y488554D01*
X1984990Y487304D01*
X1984370Y486054D01*
X1983440Y485013D01*
X1982355Y484596D01*
X1981115Y485013D01*
X1980030Y486262D01*
X1979410Y488138D01*
X1979255Y490221D01*
X1979565Y492929D01*
X1980030Y494388D01*
X1980805Y495846D01*
X1981890Y496888D01*
X1982975Y497096D01*
X1984060Y496679D01*
X1984835Y495638D01*
G01X1920350Y459596D02*
Y472096D01*
X1918490Y469596D01*
G01Y459596D02*
X1922210D01*
G01X1929805Y470013D02*
X1930735Y471262D01*
X1931820Y471888D01*
X1933060Y472096D01*
X1934610Y471679D01*
X1935695Y470638D01*
X1936005Y469388D01*
X1935850Y468137D01*
X1935230Y467096D01*
X1932130Y465013D01*
X1930735Y463554D01*
X1929805Y461471D01*
X1929495Y459596D01*
X1936005D01*
G01X1945150D02*
Y472096D01*
X1943290Y469596D01*
G01Y459596D02*
X1947010D01*
G01X1957550Y459179D02*
X1957240Y459388D01*
Y459804D01*
X1957550Y460013D01*
X1957860Y459804D01*
Y459388D01*
X1957550Y459179D01*
G01X1966540Y461471D02*
X1967470Y460429D01*
X1968555Y459804D01*
X1969950Y459596D01*
X1971345Y460013D01*
X1972430Y460846D01*
X1973205Y462304D01*
X1973360Y463971D01*
X1973050Y465638D01*
X1972275Y466679D01*
X1971190Y467513D01*
X1970105Y467721D01*
X1969020Y467513D01*
X1967625Y466679D01*
X1968090Y472096D01*
X1972275D01*
G01X1911000Y507750D02*
Y520250D01*
X1909140Y517750D01*
G01Y507750D02*
X1912860D01*
G01X1920455Y518167D02*
X1921385Y519416D01*
X1922470Y520042D01*
X1923710Y520250D01*
X1925260Y519833D01*
X1926345Y518792D01*
X1926655Y517542D01*
X1926500Y516291D01*
X1925880Y515250D01*
X1922780Y513167D01*
X1921385Y511708D01*
X1920455Y509625D01*
X1920145Y507750D01*
X1926655D01*
G01X1932855Y518167D02*
X1933785Y519416D01*
X1934870Y520042D01*
X1936110Y520250D01*
X1937660Y519833D01*
X1938745Y518792D01*
X1939055Y517542D01*
X1938900Y516291D01*
X1938280Y515250D01*
X1935180Y513167D01*
X1933785Y511708D01*
X1932855Y509625D01*
X1932545Y507750D01*
X1939055D01*
G01X1948200Y507333D02*
X1947890Y507542D01*
Y507958D01*
X1948200Y508167D01*
X1948510Y507958D01*
Y507542D01*
X1948200Y507333D01*
G01X1957190Y510250D02*
X1958120Y508791D01*
X1959360Y507958D01*
X1960755Y507750D01*
X1961995Y507958D01*
X1963235Y509000D01*
X1964010Y510250D01*
X1964165Y511500D01*
X1963855Y512958D01*
X1962770Y514000D01*
X1961685Y514417D01*
X1960290D01*
G01X1961685D02*
X1962615Y515042D01*
X1963390Y516083D01*
X1963700Y517333D01*
X1963390Y518583D01*
X1962615Y519625D01*
X1961220Y520250D01*
X1959825Y520042D01*
X1958430Y519208D01*
G01X1969590Y509625D02*
X1970520Y508583D01*
X1971605Y507958D01*
X1973000Y507750D01*
X1974395Y508167D01*
X1975480Y509000D01*
X1976255Y510458D01*
X1976410Y512125D01*
X1976100Y513792D01*
X1975325Y514833D01*
X1974240Y515667D01*
X1973155Y515875D01*
X1972070Y515667D01*
X1970675Y514833D01*
X1971140Y520250D01*
X1975325D01*
G01X1906510Y532750D02*
Y545250D01*
X1900775Y536292D01*
X1908525D01*
G01X1917050Y532750D02*
X1918135Y532958D01*
X1919375Y533583D01*
X1920150Y534625D01*
X1920460Y536083D01*
X1920150Y537541D01*
X1919220Y538792D01*
X1917825Y539417D01*
X1916275D01*
X1915345Y539833D01*
X1914570Y540875D01*
X1914260Y542333D01*
X1914725Y543792D01*
X1915810Y544833D01*
X1917050Y545250D01*
X1918290Y544833D01*
X1919375Y543792D01*
X1919840Y542333D01*
X1919530Y540875D01*
X1918755Y539833D01*
X1917825Y539417D01*
X1916275D01*
X1914880Y538792D01*
X1913950Y537541D01*
X1913640Y536083D01*
X1913950Y534625D01*
X1914725Y533583D01*
X1915965Y532958D01*
X1917050Y532750D01*
G01X1929450D02*
Y545250D01*
X1927590Y542750D01*
G01Y532750D02*
X1931310D01*
G01X1938905Y537958D02*
X1939990Y539417D01*
X1940920Y540250D01*
X1942160Y540667D01*
X1943245Y540250D01*
X1944020Y539417D01*
X1944640Y538167D01*
X1944795Y536708D01*
X1944640Y535458D01*
X1944020Y534208D01*
X1943090Y533167D01*
X1942005Y532750D01*
X1940765Y533167D01*
X1939680Y534416D01*
X1939060Y536292D01*
X1938905Y538375D01*
X1939215Y541083D01*
X1939680Y542542D01*
X1940455Y544000D01*
X1941540Y545042D01*
X1942625Y545250D01*
X1943710Y544833D01*
X1944485Y543792D01*
G01X1954250Y532333D02*
X1953940Y532542D01*
Y532958D01*
X1954250Y533167D01*
X1954560Y532958D01*
Y532542D01*
X1954250Y532333D01*
G01X1964015Y534208D02*
X1965100Y533167D01*
X1966340Y532750D01*
X1967580Y533167D01*
X1968665Y534416D01*
X1969440Y536292D01*
X1969750Y538167D01*
Y540458D01*
X1969440Y542333D01*
X1968665Y544000D01*
X1967735Y544833D01*
X1966650Y545250D01*
X1965410Y544833D01*
X1964480Y544000D01*
X1963860Y542750D01*
X1963550Y541083D01*
X1963860Y539625D01*
X1964635Y538167D01*
X1965565Y537333D01*
X1966650Y537125D01*
X1967890Y537541D01*
X1968820Y538583D01*
X1969750Y540458D01*
G01X1975640Y535250D02*
X1976570Y533791D01*
X1977810Y532958D01*
X1979205Y532750D01*
X1980445Y532958D01*
X1981685Y534000D01*
X1982460Y535250D01*
X1982615Y536500D01*
X1982305Y537958D01*
X1981220Y539000D01*
X1980135Y539417D01*
X1978740D01*
G01X1980135D02*
X1981065Y540042D01*
X1981840Y541083D01*
X1982150Y542333D01*
X1981840Y543583D01*
X1981065Y544625D01*
X1979670Y545250D01*
X1978275Y545042D01*
X1976880Y544208D01*
G01X1915250Y782010D02*
X1902750D01*
X1911708Y776275D01*
Y784025D01*
G01X1910042Y789605D02*
X1908583Y790690D01*
X1907750Y791620D01*
X1907333Y792860D01*
X1907750Y793945D01*
X1908583Y794720D01*
X1909833Y795340D01*
X1911292Y795495D01*
X1912542Y795340D01*
X1913792Y794720D01*
X1914833Y793790D01*
X1915250Y792705D01*
X1914833Y791465D01*
X1913584Y790380D01*
X1911708Y789760D01*
X1909625Y789605D01*
X1906917Y789915D01*
X1905458Y790380D01*
X1904000Y791155D01*
X1902958Y792240D01*
X1902750Y793325D01*
X1903167Y794410D01*
X1904208Y795185D01*
G01X1913792Y802315D02*
X1914833Y803400D01*
X1915250Y804640D01*
X1914833Y805880D01*
X1913584Y806965D01*
X1911708Y807740D01*
X1909833Y808050D01*
X1907542D01*
X1905667Y807740D01*
X1904000Y806965D01*
X1903167Y806035D01*
X1902750Y804950D01*
X1903167Y803710D01*
X1904000Y802780D01*
X1905250Y802160D01*
X1906917Y801850D01*
X1908375Y802160D01*
X1909833Y802935D01*
X1910667Y803865D01*
X1910875Y804950D01*
X1910459Y806190D01*
X1909417Y807120D01*
X1907542Y808050D01*
G01X1915667Y817350D02*
X1915458Y817040D01*
X1915042D01*
X1914833Y817350D01*
X1915042Y817660D01*
X1915458D01*
X1915667Y817350D01*
G01X1913375Y826340D02*
X1914417Y827270D01*
X1915042Y828355D01*
X1915250Y829750D01*
X1914833Y831145D01*
X1914000Y832230D01*
X1912542Y833005D01*
X1910875Y833160D01*
X1909208Y832850D01*
X1908167Y832075D01*
X1907333Y830990D01*
X1907125Y829905D01*
X1907333Y828820D01*
X1908167Y827425D01*
X1902750Y827890D01*
Y832075D01*
G01X1915250Y844010D02*
X1902750D01*
X1911708Y838275D01*
Y846025D01*
G01X2058642Y343705D02*
X2057183Y344790D01*
X2056350Y345720D01*
X2055933Y346960D01*
X2056350Y348045D01*
X2057183Y348820D01*
X2058433Y349440D01*
X2059892Y349595D01*
X2061142Y349440D01*
X2062392Y348820D01*
X2063433Y347890D01*
X2063850Y346805D01*
X2063433Y345565D01*
X2062184Y344480D01*
X2060308Y343860D01*
X2058225Y343705D01*
X2055517Y344015D01*
X2054058Y344480D01*
X2052600Y345255D01*
X2051558Y346340D01*
X2051350Y347425D01*
X2051767Y348510D01*
X2052808Y349285D01*
G01X2063850Y358740D02*
X2061142Y359050D01*
X2058850Y359515D01*
X2056767Y360135D01*
X2054475Y360910D01*
X2051350Y362150D01*
Y355950D01*
G01X2061975Y368040D02*
X2063017Y368970D01*
X2063642Y370055D01*
X2063850Y371450D01*
X2063433Y372845D01*
X2062600Y373930D01*
X2061142Y374705D01*
X2059475Y374860D01*
X2057808Y374550D01*
X2056767Y373775D01*
X2055933Y372690D01*
X2055725Y371605D01*
X2055933Y370520D01*
X2056767Y369125D01*
X2051350Y369590D01*
Y373775D01*
G01X2063850Y383540D02*
X2061142Y383850D01*
X2058850Y384315D01*
X2056767Y384935D01*
X2054475Y385710D01*
X2051350Y386950D01*
Y380750D01*
G01X2064267Y396250D02*
X2064058Y395940D01*
X2063642D01*
X2063433Y396250D01*
X2063642Y396560D01*
X2064058D01*
X2064267Y396250D01*
G01X2063850Y408650D02*
X2063642Y409735D01*
X2063017Y410975D01*
X2061975Y411750D01*
X2060517Y412060D01*
X2059059Y411750D01*
X2057808Y410820D01*
X2057183Y409425D01*
Y407875D01*
X2056767Y406945D01*
X2055725Y406170D01*
X2054267Y405860D01*
X2052808Y406325D01*
X2051767Y407410D01*
X2051350Y408650D01*
X2051767Y409890D01*
X2052808Y410975D01*
X2054267Y411440D01*
X2055725Y411130D01*
X2056767Y410355D01*
X2057183Y409425D01*
Y407875D01*
X2057808Y406480D01*
X2059059Y405550D01*
X2060517Y405240D01*
X2061975Y405550D01*
X2063017Y406325D01*
X2063642Y407565D01*
X2063850Y408650D01*
G01Y420740D02*
X2061142Y421050D01*
X2058850Y421515D01*
X2056767Y422135D01*
X2054475Y422910D01*
X2051350Y424150D01*
Y417950D01*
G01X2088850Y353000D02*
X2076350D01*
X2078850Y351140D01*
G01X2088850D02*
Y354860D01*
G01Y365090D02*
X2086142Y365400D01*
X2083850Y365865D01*
X2081767Y366485D01*
X2079475Y367260D01*
X2076350Y368500D01*
Y362300D01*
G01X2088850Y377800D02*
X2076350D01*
X2078850Y375940D01*
G01X2088850D02*
Y379660D01*
G01X2089267Y390200D02*
X2089058Y389890D01*
X2088642D01*
X2088433Y390200D01*
X2088642Y390510D01*
X2089058D01*
X2089267Y390200D01*
G01X2083642Y399655D02*
X2082183Y400740D01*
X2081350Y401670D01*
X2080933Y402910D01*
X2081350Y403995D01*
X2082183Y404770D01*
X2083433Y405390D01*
X2084892Y405545D01*
X2086142Y405390D01*
X2087392Y404770D01*
X2088433Y403840D01*
X2088850Y402755D01*
X2088433Y401515D01*
X2087184Y400430D01*
X2085308Y399810D01*
X2083225Y399655D01*
X2080517Y399965D01*
X2079058Y400430D01*
X2077600Y401205D01*
X2076558Y402290D01*
X2076350Y403375D01*
X2076767Y404460D01*
X2077808Y405235D01*
G01X2086975Y411590D02*
X2088017Y412520D01*
X2088642Y413605D01*
X2088850Y415000D01*
X2088433Y416395D01*
X2087600Y417480D01*
X2086142Y418255D01*
X2084475Y418410D01*
X2082808Y418100D01*
X2081767Y417325D01*
X2080933Y416240D01*
X2080725Y415155D01*
X2080933Y414070D01*
X2081767Y412675D01*
X2076350Y413140D01*
Y417325D01*
G01X2429439Y741212D02*
Y753712D01*
X2435329D01*
G01X2433159Y747670D02*
X2429439D01*
G01X2442924Y753712D02*
X2446644D01*
G01X2444784D02*
Y741212D01*
G01X2442924D02*
X2446644D01*
G01X2458114Y747462D02*
X2461214D01*
Y743712D01*
X2460284Y742462D01*
X2459199Y741629D01*
X2457649Y741212D01*
X2456099Y741629D01*
X2455014Y742462D01*
X2454084Y743712D01*
X2453464Y745170D01*
X2453154Y746837D01*
Y748295D01*
X2453464Y749545D01*
X2454084Y751004D01*
X2455014Y752254D01*
X2455944Y753087D01*
X2457184Y753712D01*
X2458269D01*
X2459509Y753295D01*
X2460439Y752462D01*
G01X2466174Y753712D02*
Y744754D01*
X2466794Y742878D01*
X2468034Y741629D01*
X2469584Y741212D01*
X2471134Y741629D01*
X2472374Y742878D01*
X2472994Y744754D01*
Y753712D01*
G01X2478884Y741212D02*
Y753712D01*
X2482759D01*
X2483999Y753087D01*
X2484774Y752254D01*
X2485084Y750587D01*
X2484774Y748920D01*
X2483844Y747879D01*
X2482759Y747254D01*
X2478884D01*
G01X2482759D02*
X2485084Y741212D01*
G01X2497484D02*
X2491284D01*
Y753712D01*
X2497484D01*
G01X2495004Y747670D02*
X2491284D01*
G01X2553284Y-46188D02*
Y-33688D01*
X2551424Y-36188D01*
G01Y-46188D02*
X2555144D01*
G01X2565684D02*
Y-33688D01*
X2563824Y-36188D01*
G01Y-46188D02*
X2567544D01*
G01X2574674Y-43688D02*
X2575604Y-45147D01*
X2576844Y-45980D01*
X2578239Y-46188D01*
X2579479Y-45980D01*
X2580719Y-44938D01*
X2581494Y-43688D01*
X2581649Y-42438D01*
X2581339Y-40980D01*
X2580254Y-39938D01*
X2579169Y-39521D01*
X2577774D01*
G01X2579169D02*
X2580099Y-38896D01*
X2580874Y-37855D01*
X2581184Y-36605D01*
X2580874Y-35355D01*
X2580099Y-34313D01*
X2578704Y-33688D01*
X2577309Y-33896D01*
X2575914Y-34730D01*
G01X2590484Y-46605D02*
X2590174Y-46396D01*
Y-45980D01*
X2590484Y-45771D01*
X2590794Y-45980D01*
Y-46396D01*
X2590484Y-46605D01*
G01X2602884Y-33688D02*
X2601644Y-34105D01*
X2600714Y-35146D01*
X2600094Y-36396D01*
X2599629Y-38063D01*
X2599474Y-39938D01*
X2599629Y-41813D01*
X2600094Y-43480D01*
X2600714Y-44730D01*
X2601644Y-45771D01*
X2602884Y-46188D01*
X2604124Y-45771D01*
X2605054Y-44730D01*
X2605674Y-43480D01*
X2606139Y-41813D01*
X2606294Y-39938D01*
X2606139Y-38063D01*
X2605674Y-36396D01*
X2605054Y-35146D01*
X2604124Y-34105D01*
X2602884Y-33688D01*
G01X2612959Y-37855D02*
X2617609Y-46188D01*
G01Y-37855D02*
X2612959Y-46188D01*
G01X2624739Y-40980D02*
X2625824Y-39521D01*
X2626754Y-38688D01*
X2627994Y-38271D01*
X2629079Y-38688D01*
X2629854Y-39521D01*
X2630474Y-40771D01*
X2630629Y-42230D01*
X2630474Y-43480D01*
X2629854Y-44730D01*
X2628924Y-45771D01*
X2627839Y-46188D01*
X2626599Y-45771D01*
X2625514Y-44522D01*
X2624894Y-42646D01*
X2624739Y-40563D01*
X2625049Y-37855D01*
X2625514Y-36396D01*
X2626289Y-34938D01*
X2627374Y-33896D01*
X2628459Y-33688D01*
X2629544Y-34105D01*
X2630319Y-35146D01*
G01X2641944Y-46188D02*
Y-33688D01*
X2636209Y-42646D01*
X2643959D01*
G01X2652484Y-46605D02*
X2652174Y-46396D01*
Y-45980D01*
X2652484Y-45771D01*
X2652794Y-45980D01*
Y-46396D01*
X2652484Y-46605D01*
G01X2664884Y-33688D02*
X2663644Y-34105D01*
X2662714Y-35146D01*
X2662094Y-36396D01*
X2661629Y-38063D01*
X2661474Y-39938D01*
X2661629Y-41813D01*
X2662094Y-43480D01*
X2662714Y-44730D01*
X2663644Y-45771D01*
X2664884Y-46188D01*
X2666124Y-45771D01*
X2667054Y-44730D01*
X2667674Y-43480D01*
X2668139Y-41813D01*
X2668294Y-39938D01*
X2668139Y-38063D01*
X2667674Y-36396D01*
X2667054Y-35146D01*
X2666124Y-34105D01*
X2664884Y-33688D01*
G01X2531739Y741212D02*
Y753712D01*
X2537629D01*
G01X2535459Y747670D02*
X2531739D01*
G01X2545224Y753712D02*
X2548944D01*
G01X2547084D02*
Y741212D01*
G01X2545224D02*
X2548944D01*
G01X2555919D02*
Y753712D01*
X2563049Y741212D01*
Y753712D01*
G01X2570024D02*
X2573744D01*
G01X2571884D02*
Y741212D01*
G01X2570024D02*
X2573744D01*
G01X2581029Y742878D02*
X2582269Y741837D01*
X2583664Y741212D01*
X2584904D01*
X2586144Y741837D01*
X2587074Y742878D01*
X2587539Y744337D01*
X2587229Y745795D01*
X2586454Y747045D01*
X2585059Y747879D01*
X2583199Y748295D01*
X2582114Y749129D01*
X2581649Y750587D01*
X2581959Y752045D01*
X2582734Y753087D01*
X2583819Y753712D01*
X2584904D01*
X2585989Y753295D01*
X2586919Y752254D01*
G01X2593429Y741212D02*
Y753712D01*
G01X2599939D02*
Y741212D01*
G01Y747462D02*
X2593429D01*
G01X2612184Y741212D02*
X2605984D01*
Y753712D01*
X2612184D01*
G01X2609704Y747670D02*
X2605984D01*
G01X2618074Y741212D02*
Y753712D01*
X2621174D01*
X2622414Y753087D01*
X2623344Y752254D01*
X2624119Y751004D01*
X2624739Y749545D01*
X2624894Y747462D01*
X2624739Y745379D01*
X2624119Y743920D01*
X2623344Y742670D01*
X2622414Y741837D01*
X2621174Y741212D01*
X2618074D01*
G01X2629234Y737045D02*
X2638534D01*
G01X2643029Y742878D02*
X2644269Y741837D01*
X2645664Y741212D01*
X2646904D01*
X2648144Y741837D01*
X2649074Y742878D01*
X2649539Y744337D01*
X2649229Y745795D01*
X2648454Y747045D01*
X2647059Y747879D01*
X2645199Y748295D01*
X2644114Y749129D01*
X2643649Y750587D01*
X2643959Y752045D01*
X2644734Y753087D01*
X2645819Y753712D01*
X2646904D01*
X2647989Y753295D01*
X2648919Y752254D01*
G01X2656824Y753712D02*
X2660544D01*
G01X2658684D02*
Y741212D01*
G01X2656824D02*
X2660544D01*
G01X2668139Y753712D02*
X2674029D01*
X2668139Y741212D01*
X2674029D01*
G01X2686584D02*
X2680384D01*
Y753712D01*
X2686584D01*
G01X2684104Y747670D02*
X2680384D01*
G01X2584284Y-8388D02*
Y4112D01*
X2582424Y1612D01*
G01Y-8388D02*
X2586144D01*
G01X2593274Y-6513D02*
X2594204Y-7555D01*
X2595289Y-8180D01*
X2596684Y-8388D01*
X2598079Y-7971D01*
X2599164Y-7138D01*
X2599939Y-5680D01*
X2600094Y-4013D01*
X2599784Y-2346D01*
X2599009Y-1305D01*
X2597924Y-471D01*
X2596839Y-263D01*
X2595754Y-471D01*
X2594359Y-1305D01*
X2594824Y4112D01*
X2599009D01*
G01X2609084Y-8388D02*
X2610169Y-8180D01*
X2611409Y-7555D01*
X2612184Y-6513D01*
X2612494Y-5055D01*
X2612184Y-3597D01*
X2611254Y-2346D01*
X2609859Y-1721D01*
X2608309D01*
X2607379Y-1305D01*
X2606604Y-263D01*
X2606294Y1195D01*
X2606759Y2654D01*
X2607844Y3695D01*
X2609084Y4112D01*
X2610324Y3695D01*
X2611409Y2654D01*
X2611874Y1195D01*
X2611564Y-263D01*
X2610789Y-1305D01*
X2609859Y-1721D01*
X2608309D01*
X2606914Y-2346D01*
X2605984Y-3597D01*
X2605674Y-5055D01*
X2605984Y-6513D01*
X2606759Y-7555D01*
X2607999Y-8180D01*
X2609084Y-8388D01*
G01X2621484Y-8805D02*
X2621174Y-8596D01*
Y-8180D01*
X2621484Y-7971D01*
X2621794Y-8180D01*
Y-8596D01*
X2621484Y-8805D01*
G01X2633884Y4112D02*
X2632644Y3695D01*
X2631714Y2654D01*
X2631094Y1404D01*
X2630629Y-263D01*
X2630474Y-2138D01*
X2630629Y-4013D01*
X2631094Y-5680D01*
X2631714Y-6930D01*
X2632644Y-7971D01*
X2633884Y-8388D01*
X2635124Y-7971D01*
X2636054Y-6930D01*
X2636674Y-5680D01*
X2637139Y-4013D01*
X2637294Y-2138D01*
X2637139Y-263D01*
X2636674Y1404D01*
X2636054Y2654D01*
X2635124Y3695D01*
X2633884Y4112D01*
G01X2584284Y29412D02*
Y41912D01*
X2582424Y39412D01*
G01Y29412D02*
X2586144D01*
G01X2593739Y39829D02*
X2594669Y41078D01*
X2595754Y41704D01*
X2596994Y41912D01*
X2598544Y41495D01*
X2599629Y40454D01*
X2599939Y39204D01*
X2599784Y37953D01*
X2599164Y36912D01*
X2596064Y34829D01*
X2594669Y33370D01*
X2593739Y31287D01*
X2593429Y29412D01*
X2599939D01*
G01X2606139Y34620D02*
X2607224Y36079D01*
X2608154Y36912D01*
X2609394Y37329D01*
X2610479Y36912D01*
X2611254Y36079D01*
X2611874Y34829D01*
X2612029Y33370D01*
X2611874Y32120D01*
X2611254Y30870D01*
X2610324Y29829D01*
X2609239Y29412D01*
X2607999Y29829D01*
X2606914Y31078D01*
X2606294Y32954D01*
X2606139Y35037D01*
X2606449Y37745D01*
X2606914Y39204D01*
X2607689Y40662D01*
X2608774Y41704D01*
X2609859Y41912D01*
X2610944Y41495D01*
X2611719Y40454D01*
G01X2621484Y28995D02*
X2621174Y29204D01*
Y29620D01*
X2621484Y29829D01*
X2621794Y29620D01*
Y29204D01*
X2621484Y28995D01*
G01X2633884Y41912D02*
X2632644Y41495D01*
X2631714Y40454D01*
X2631094Y39204D01*
X2630629Y37537D01*
X2630474Y35662D01*
X2630629Y33787D01*
X2631094Y32120D01*
X2631714Y30870D01*
X2632644Y29829D01*
X2633884Y29412D01*
X2635124Y29829D01*
X2636054Y30870D01*
X2636674Y32120D01*
X2637139Y33787D01*
X2637294Y35662D01*
X2637139Y37537D01*
X2636674Y39204D01*
X2636054Y40454D01*
X2635124Y41495D01*
X2633884Y41912D01*
G01X2584284Y67212D02*
Y79712D01*
X2582424Y77212D01*
G01Y67212D02*
X2586144D01*
G01X2593739Y77629D02*
X2594669Y78878D01*
X2595754Y79504D01*
X2596994Y79712D01*
X2598544Y79295D01*
X2599629Y78254D01*
X2599939Y77004D01*
X2599784Y75753D01*
X2599164Y74712D01*
X2596064Y72629D01*
X2594669Y71170D01*
X2593739Y69087D01*
X2593429Y67212D01*
X2599939D01*
G01X2605674Y69087D02*
X2606604Y68045D01*
X2607689Y67420D01*
X2609084Y67212D01*
X2610479Y67629D01*
X2611564Y68462D01*
X2612339Y69920D01*
X2612494Y71587D01*
X2612184Y73254D01*
X2611409Y74295D01*
X2610324Y75129D01*
X2609239Y75337D01*
X2608154Y75129D01*
X2606759Y74295D01*
X2607224Y79712D01*
X2611409D01*
G01X2621484Y66795D02*
X2621174Y67004D01*
Y67420D01*
X2621484Y67629D01*
X2621794Y67420D01*
Y67004D01*
X2621484Y66795D01*
G01X2633884Y79712D02*
X2632644Y79295D01*
X2631714Y78254D01*
X2631094Y77004D01*
X2630629Y75337D01*
X2630474Y73462D01*
X2630629Y71587D01*
X2631094Y69920D01*
X2631714Y68670D01*
X2632644Y67629D01*
X2633884Y67212D01*
X2635124Y67629D01*
X2636054Y68670D01*
X2636674Y69920D01*
X2637139Y71587D01*
X2637294Y73462D01*
X2637139Y75337D01*
X2636674Y77004D01*
X2636054Y78254D01*
X2635124Y79295D01*
X2633884Y79712D01*
G01X2581339Y266629D02*
X2582269Y267878D01*
X2583354Y268504D01*
X2584594Y268712D01*
X2586144Y268295D01*
X2587229Y267254D01*
X2587539Y266004D01*
X2587384Y264753D01*
X2586764Y263712D01*
X2583664Y261629D01*
X2582269Y260170D01*
X2581339Y258087D01*
X2581029Y256212D01*
X2587539D01*
G01X2593274Y258087D02*
X2594204Y257045D01*
X2595289Y256420D01*
X2596684Y256212D01*
X2598079Y256629D01*
X2599164Y257462D01*
X2599939Y258920D01*
X2600094Y260587D01*
X2599784Y262254D01*
X2599009Y263295D01*
X2597924Y264129D01*
X2596839Y264337D01*
X2595754Y264129D01*
X2594359Y263295D01*
X2594824Y268712D01*
X2599009D01*
G01X2606139Y266629D02*
X2607069Y267878D01*
X2608154Y268504D01*
X2609394Y268712D01*
X2610944Y268295D01*
X2612029Y267254D01*
X2612339Y266004D01*
X2612184Y264753D01*
X2611564Y263712D01*
X2608464Y261629D01*
X2607069Y260170D01*
X2606139Y258087D01*
X2605829Y256212D01*
X2612339D01*
G01X2621484Y255795D02*
X2621174Y256004D01*
Y256420D01*
X2621484Y256629D01*
X2621794Y256420D01*
Y256004D01*
X2621484Y255795D01*
G01X2633884Y268712D02*
X2632644Y268295D01*
X2631714Y267254D01*
X2631094Y266004D01*
X2630629Y264337D01*
X2630474Y262462D01*
X2630629Y260587D01*
X2631094Y258920D01*
X2631714Y257670D01*
X2632644Y256629D01*
X2633884Y256212D01*
X2635124Y256629D01*
X2636054Y257670D01*
X2636674Y258920D01*
X2637139Y260587D01*
X2637294Y262462D01*
X2637139Y264337D01*
X2636674Y266004D01*
X2636054Y267254D01*
X2635124Y268295D01*
X2633884Y268712D01*
G01X2581339Y304429D02*
X2582269Y305678D01*
X2583354Y306304D01*
X2584594Y306512D01*
X2586144Y306095D01*
X2587229Y305054D01*
X2587539Y303804D01*
X2587384Y302553D01*
X2586764Y301512D01*
X2583664Y299429D01*
X2582269Y297970D01*
X2581339Y295887D01*
X2581029Y294012D01*
X2587539D01*
G01X2596684Y306512D02*
X2595444Y306095D01*
X2594514Y305054D01*
X2593894Y303804D01*
X2593429Y302137D01*
X2593274Y300262D01*
X2593429Y298387D01*
X2593894Y296720D01*
X2594514Y295470D01*
X2595444Y294429D01*
X2596684Y294012D01*
X2597924Y294429D01*
X2598854Y295470D01*
X2599474Y296720D01*
X2599939Y298387D01*
X2600094Y300262D01*
X2599939Y302137D01*
X2599474Y303804D01*
X2598854Y305054D01*
X2597924Y306095D01*
X2596684Y306512D01*
G01X2605674Y296512D02*
X2606604Y295053D01*
X2607844Y294220D01*
X2609239Y294012D01*
X2610479Y294220D01*
X2611719Y295262D01*
X2612494Y296512D01*
X2612649Y297762D01*
X2612339Y299220D01*
X2611254Y300262D01*
X2610169Y300679D01*
X2608774D01*
G01X2610169D02*
X2611099Y301304D01*
X2611874Y302345D01*
X2612184Y303595D01*
X2611874Y304845D01*
X2611099Y305887D01*
X2609704Y306512D01*
X2608309Y306304D01*
X2606914Y305470D01*
G01X2621484Y293595D02*
X2621174Y293804D01*
Y294220D01*
X2621484Y294429D01*
X2621794Y294220D01*
Y293804D01*
X2621484Y293595D01*
G01X2633884Y306512D02*
X2632644Y306095D01*
X2631714Y305054D01*
X2631094Y303804D01*
X2630629Y302137D01*
X2630474Y300262D01*
X2630629Y298387D01*
X2631094Y296720D01*
X2631714Y295470D01*
X2632644Y294429D01*
X2633884Y294012D01*
X2635124Y294429D01*
X2636054Y295470D01*
X2636674Y296720D01*
X2637139Y298387D01*
X2637294Y300262D01*
X2637139Y302137D01*
X2636674Y303804D01*
X2636054Y305054D01*
X2635124Y306095D01*
X2633884Y306512D01*
G01X2584284Y331812D02*
Y344312D01*
X2582424Y341812D01*
G01Y331812D02*
X2586144D01*
G01X2593739Y337020D02*
X2594824Y338479D01*
X2595754Y339312D01*
X2596994Y339729D01*
X2598079Y339312D01*
X2598854Y338479D01*
X2599474Y337229D01*
X2599629Y335770D01*
X2599474Y334520D01*
X2598854Y333270D01*
X2597924Y332229D01*
X2596839Y331812D01*
X2595599Y332229D01*
X2594514Y333478D01*
X2593894Y335354D01*
X2593739Y337437D01*
X2594049Y340145D01*
X2594514Y341604D01*
X2595289Y343062D01*
X2596374Y344104D01*
X2597459Y344312D01*
X2598544Y343895D01*
X2599319Y342854D01*
G01X2608774Y331812D02*
X2609084Y334520D01*
X2609549Y336812D01*
X2610169Y338895D01*
X2610944Y341187D01*
X2612184Y344312D01*
X2605984D01*
G01X2621484Y331395D02*
X2621174Y331604D01*
Y332020D01*
X2621484Y332229D01*
X2621794Y332020D01*
Y331604D01*
X2621484Y331395D01*
G01X2633884Y344312D02*
X2632644Y343895D01*
X2631714Y342854D01*
X2631094Y341604D01*
X2630629Y339937D01*
X2630474Y338062D01*
X2630629Y336187D01*
X2631094Y334520D01*
X2631714Y333270D01*
X2632644Y332229D01*
X2633884Y331812D01*
X2635124Y332229D01*
X2636054Y333270D01*
X2636674Y334520D01*
X2637139Y336187D01*
X2637294Y338062D01*
X2637139Y339937D01*
X2636674Y341604D01*
X2636054Y342854D01*
X2635124Y343895D01*
X2633884Y344312D01*
G01X2584284Y369612D02*
Y382112D01*
X2582424Y379612D01*
G01Y369612D02*
X2586144D01*
G01X2596684D02*
Y382112D01*
X2594824Y379612D01*
G01Y369612D02*
X2598544D01*
G01X2606449Y371070D02*
X2607534Y370029D01*
X2608774Y369612D01*
X2610014Y370029D01*
X2611099Y371278D01*
X2611874Y373154D01*
X2612184Y375029D01*
Y377320D01*
X2611874Y379195D01*
X2611099Y380862D01*
X2610169Y381695D01*
X2609084Y382112D01*
X2607844Y381695D01*
X2606914Y380862D01*
X2606294Y379612D01*
X2605984Y377945D01*
X2606294Y376487D01*
X2607069Y375029D01*
X2607999Y374195D01*
X2609084Y373987D01*
X2610324Y374403D01*
X2611254Y375445D01*
X2612184Y377320D01*
G01X2621484Y369195D02*
X2621174Y369404D01*
Y369820D01*
X2621484Y370029D01*
X2621794Y369820D01*
Y369404D01*
X2621484Y369195D01*
G01X2633884Y382112D02*
X2632644Y381695D01*
X2631714Y380654D01*
X2631094Y379404D01*
X2630629Y377737D01*
X2630474Y375862D01*
X2630629Y373987D01*
X2631094Y372320D01*
X2631714Y371070D01*
X2632644Y370029D01*
X2633884Y369612D01*
X2635124Y370029D01*
X2636054Y371070D01*
X2636674Y372320D01*
X2637139Y373987D01*
X2637294Y375862D01*
X2637139Y377737D01*
X2636674Y379404D01*
X2636054Y380654D01*
X2635124Y381695D01*
X2633884Y382112D01*
G01X2586144Y558612D02*
Y571112D01*
X2580409Y562154D01*
X2588159D01*
G01X2596684Y571112D02*
X2595444Y570695D01*
X2594514Y569654D01*
X2593894Y568404D01*
X2593429Y566737D01*
X2593274Y564862D01*
X2593429Y562987D01*
X2593894Y561320D01*
X2594514Y560070D01*
X2595444Y559029D01*
X2596684Y558612D01*
X2597924Y559029D01*
X2598854Y560070D01*
X2599474Y561320D01*
X2599939Y562987D01*
X2600094Y564862D01*
X2599939Y566737D01*
X2599474Y568404D01*
X2598854Y569654D01*
X2597924Y570695D01*
X2596684Y571112D01*
G01X2609084Y558195D02*
X2608774Y558404D01*
Y558820D01*
X2609084Y559029D01*
X2609394Y558820D01*
Y558404D01*
X2609084Y558195D01*
G01X2621484Y558612D02*
Y571112D01*
X2619624Y568612D01*
G01Y558612D02*
X2623344D01*
G01X2630474Y560487D02*
X2631404Y559445D01*
X2632489Y558820D01*
X2633884Y558612D01*
X2635279Y559029D01*
X2636364Y559862D01*
X2637139Y561320D01*
X2637294Y562987D01*
X2636984Y564654D01*
X2636209Y565695D01*
X2635124Y566529D01*
X2634039Y566737D01*
X2632954Y566529D01*
X2631559Y565695D01*
X2632024Y571112D01*
X2636209D01*
G01X2581339Y606829D02*
X2582269Y608078D01*
X2583354Y608704D01*
X2584594Y608912D01*
X2586144Y608495D01*
X2587229Y607454D01*
X2587539Y606204D01*
X2587384Y604953D01*
X2586764Y603912D01*
X2583664Y601829D01*
X2582269Y600370D01*
X2581339Y598287D01*
X2581029Y596412D01*
X2587539D01*
G01X2594049Y597870D02*
X2595134Y596829D01*
X2596374Y596412D01*
X2597614Y596829D01*
X2598699Y598078D01*
X2599474Y599954D01*
X2599784Y601829D01*
Y604120D01*
X2599474Y605995D01*
X2598699Y607662D01*
X2597769Y608495D01*
X2596684Y608912D01*
X2595444Y608495D01*
X2594514Y607662D01*
X2593894Y606412D01*
X2593584Y604745D01*
X2593894Y603287D01*
X2594669Y601829D01*
X2595599Y600995D01*
X2596684Y600787D01*
X2597924Y601203D01*
X2598854Y602245D01*
X2599784Y604120D01*
G01X2609084Y595995D02*
X2608774Y596204D01*
Y596620D01*
X2609084Y596829D01*
X2609394Y596620D01*
Y596204D01*
X2609084Y595995D01*
G01X2618074Y598287D02*
X2619004Y597245D01*
X2620089Y596620D01*
X2621484Y596412D01*
X2622879Y596829D01*
X2623964Y597662D01*
X2624739Y599120D01*
X2624894Y600787D01*
X2624584Y602454D01*
X2623809Y603495D01*
X2622724Y604329D01*
X2621639Y604537D01*
X2620554Y604329D01*
X2619159Y603495D01*
X2619624Y608912D01*
X2623809D01*
G01X2630939Y606829D02*
X2631869Y608078D01*
X2632954Y608704D01*
X2634194Y608912D01*
X2635744Y608495D01*
X2636829Y607454D01*
X2637139Y606204D01*
X2636984Y604953D01*
X2636364Y603912D01*
X2633264Y601829D01*
X2631869Y600370D01*
X2630939Y598287D01*
X2630629Y596412D01*
X2637139D01*
G01X2587849Y106470D02*
X2588934Y105429D01*
X2590174Y105012D01*
X2591414Y105429D01*
X2592499Y106678D01*
X2593274Y108554D01*
X2593584Y110429D01*
Y112720D01*
X2593274Y114595D01*
X2592499Y116262D01*
X2591569Y117095D01*
X2590484Y117512D01*
X2589244Y117095D01*
X2588314Y116262D01*
X2587694Y115012D01*
X2587384Y113345D01*
X2587694Y111887D01*
X2588469Y110429D01*
X2589399Y109595D01*
X2590484Y109387D01*
X2591724Y109803D01*
X2592654Y110845D01*
X2593584Y112720D01*
G01X2599474Y106887D02*
X2600404Y105845D01*
X2601489Y105220D01*
X2602884Y105012D01*
X2604279Y105429D01*
X2605364Y106262D01*
X2606139Y107720D01*
X2606294Y109387D01*
X2605984Y111054D01*
X2605209Y112095D01*
X2604124Y112929D01*
X2603039Y113137D01*
X2601954Y112929D01*
X2600559Y112095D01*
X2601024Y117512D01*
X2605209D01*
G01X2615284Y104595D02*
X2614974Y104804D01*
Y105220D01*
X2615284Y105429D01*
X2615594Y105220D01*
Y104804D01*
X2615284Y104595D01*
G01X2627684Y117512D02*
X2626444Y117095D01*
X2625514Y116054D01*
X2624894Y114804D01*
X2624429Y113137D01*
X2624274Y111262D01*
X2624429Y109387D01*
X2624894Y107720D01*
X2625514Y106470D01*
X2626444Y105429D01*
X2627684Y105012D01*
X2628924Y105429D01*
X2629854Y106470D01*
X2630474Y107720D01*
X2630939Y109387D01*
X2631094Y111262D01*
X2630939Y113137D01*
X2630474Y114804D01*
X2629854Y116054D01*
X2628924Y117095D01*
X2627684Y117512D01*
G01X2590484Y142812D02*
X2591569Y143020D01*
X2592809Y143645D01*
X2593584Y144687D01*
X2593894Y146145D01*
X2593584Y147603D01*
X2592654Y148854D01*
X2591259Y149479D01*
X2589709D01*
X2588779Y149895D01*
X2588004Y150937D01*
X2587694Y152395D01*
X2588159Y153854D01*
X2589244Y154895D01*
X2590484Y155312D01*
X2591724Y154895D01*
X2592809Y153854D01*
X2593274Y152395D01*
X2592964Y150937D01*
X2592189Y149895D01*
X2591259Y149479D01*
X2589709D01*
X2588314Y148854D01*
X2587384Y147603D01*
X2587074Y146145D01*
X2587384Y144687D01*
X2588159Y143645D01*
X2589399Y143020D01*
X2590484Y142812D01*
G01X2599939Y148020D02*
X2601024Y149479D01*
X2601954Y150312D01*
X2603194Y150729D01*
X2604279Y150312D01*
X2605054Y149479D01*
X2605674Y148229D01*
X2605829Y146770D01*
X2605674Y145520D01*
X2605054Y144270D01*
X2604124Y143229D01*
X2603039Y142812D01*
X2601799Y143229D01*
X2600714Y144478D01*
X2600094Y146354D01*
X2599939Y148437D01*
X2600249Y151145D01*
X2600714Y152604D01*
X2601489Y154062D01*
X2602574Y155104D01*
X2603659Y155312D01*
X2604744Y154895D01*
X2605519Y153854D01*
G01X2615284Y142395D02*
X2614974Y142604D01*
Y143020D01*
X2615284Y143229D01*
X2615594Y143020D01*
Y142604D01*
X2615284Y142395D01*
G01X2627684Y155312D02*
X2626444Y154895D01*
X2625514Y153854D01*
X2624894Y152604D01*
X2624429Y150937D01*
X2624274Y149062D01*
X2624429Y147187D01*
X2624894Y145520D01*
X2625514Y144270D01*
X2626444Y143229D01*
X2627684Y142812D01*
X2628924Y143229D01*
X2629854Y144270D01*
X2630474Y145520D01*
X2630939Y147187D01*
X2631094Y149062D01*
X2630939Y150937D01*
X2630474Y152604D01*
X2629854Y153854D01*
X2628924Y154895D01*
X2627684Y155312D01*
G01X2590484Y180612D02*
X2591569Y180820D01*
X2592809Y181445D01*
X2593584Y182487D01*
X2593894Y183945D01*
X2593584Y185403D01*
X2592654Y186654D01*
X2591259Y187279D01*
X2589709D01*
X2588779Y187695D01*
X2588004Y188737D01*
X2587694Y190195D01*
X2588159Y191654D01*
X2589244Y192695D01*
X2590484Y193112D01*
X2591724Y192695D01*
X2592809Y191654D01*
X2593274Y190195D01*
X2592964Y188737D01*
X2592189Y187695D01*
X2591259Y187279D01*
X2589709D01*
X2588314Y186654D01*
X2587384Y185403D01*
X2587074Y183945D01*
X2587384Y182487D01*
X2588159Y181445D01*
X2589399Y180820D01*
X2590484Y180612D01*
G01X2599474Y182487D02*
X2600404Y181445D01*
X2601489Y180820D01*
X2602884Y180612D01*
X2604279Y181029D01*
X2605364Y181862D01*
X2606139Y183320D01*
X2606294Y184987D01*
X2605984Y186654D01*
X2605209Y187695D01*
X2604124Y188529D01*
X2603039Y188737D01*
X2601954Y188529D01*
X2600559Y187695D01*
X2601024Y193112D01*
X2605209D01*
G01X2615284Y180195D02*
X2614974Y180404D01*
Y180820D01*
X2615284Y181029D01*
X2615594Y180820D01*
Y180404D01*
X2615284Y180195D01*
G01X2627684Y193112D02*
X2626444Y192695D01*
X2625514Y191654D01*
X2624894Y190404D01*
X2624429Y188737D01*
X2624274Y186862D01*
X2624429Y184987D01*
X2624894Y183320D01*
X2625514Y182070D01*
X2626444Y181029D01*
X2627684Y180612D01*
X2628924Y181029D01*
X2629854Y182070D01*
X2630474Y183320D01*
X2630939Y184987D01*
X2631094Y186862D01*
X2630939Y188737D01*
X2630474Y190404D01*
X2629854Y191654D01*
X2628924Y192695D01*
X2627684Y193112D01*
G01X2590484Y218412D02*
X2591569Y218620D01*
X2592809Y219245D01*
X2593584Y220287D01*
X2593894Y221745D01*
X2593584Y223203D01*
X2592654Y224454D01*
X2591259Y225079D01*
X2589709D01*
X2588779Y225495D01*
X2588004Y226537D01*
X2587694Y227995D01*
X2588159Y229454D01*
X2589244Y230495D01*
X2590484Y230912D01*
X2591724Y230495D01*
X2592809Y229454D01*
X2593274Y227995D01*
X2592964Y226537D01*
X2592189Y225495D01*
X2591259Y225079D01*
X2589709D01*
X2588314Y224454D01*
X2587384Y223203D01*
X2587074Y221745D01*
X2587384Y220287D01*
X2588159Y219245D01*
X2589399Y218620D01*
X2590484Y218412D01*
G01X2599474Y220912D02*
X2600404Y219453D01*
X2601644Y218620D01*
X2603039Y218412D01*
X2604279Y218620D01*
X2605519Y219662D01*
X2606294Y220912D01*
X2606449Y222162D01*
X2606139Y223620D01*
X2605054Y224662D01*
X2603969Y225079D01*
X2602574D01*
G01X2603969D02*
X2604899Y225704D01*
X2605674Y226745D01*
X2605984Y227995D01*
X2605674Y229245D01*
X2604899Y230287D01*
X2603504Y230912D01*
X2602109Y230704D01*
X2600714Y229870D01*
G01X2615284Y217995D02*
X2614974Y218204D01*
Y218620D01*
X2615284Y218829D01*
X2615594Y218620D01*
Y218204D01*
X2615284Y217995D01*
G01X2627684Y230912D02*
X2626444Y230495D01*
X2625514Y229454D01*
X2624894Y228204D01*
X2624429Y226537D01*
X2624274Y224662D01*
X2624429Y222787D01*
X2624894Y221120D01*
X2625514Y219870D01*
X2626444Y218829D01*
X2627684Y218412D01*
X2628924Y218829D01*
X2629854Y219870D01*
X2630474Y221120D01*
X2630939Y222787D01*
X2631094Y224662D01*
X2630939Y226537D01*
X2630474Y228204D01*
X2629854Y229454D01*
X2628924Y230495D01*
X2627684Y230912D01*
G01X2587539Y412620D02*
X2588624Y414079D01*
X2589554Y414912D01*
X2590794Y415329D01*
X2591879Y414912D01*
X2592654Y414079D01*
X2593274Y412829D01*
X2593429Y411370D01*
X2593274Y410120D01*
X2592654Y408870D01*
X2591724Y407829D01*
X2590639Y407412D01*
X2589399Y407829D01*
X2588314Y409078D01*
X2587694Y410954D01*
X2587539Y413037D01*
X2587849Y415745D01*
X2588314Y417204D01*
X2589089Y418662D01*
X2590174Y419704D01*
X2591259Y419912D01*
X2592344Y419495D01*
X2593119Y418454D01*
G01X2602574Y407412D02*
X2602884Y410120D01*
X2603349Y412412D01*
X2603969Y414495D01*
X2604744Y416787D01*
X2605984Y419912D01*
X2599784D01*
G01X2615284Y406995D02*
X2614974Y407204D01*
Y407620D01*
X2615284Y407829D01*
X2615594Y407620D01*
Y407204D01*
X2615284Y406995D01*
G01X2627684Y419912D02*
X2626444Y419495D01*
X2625514Y418454D01*
X2624894Y417204D01*
X2624429Y415537D01*
X2624274Y413662D01*
X2624429Y411787D01*
X2624894Y410120D01*
X2625514Y408870D01*
X2626444Y407829D01*
X2627684Y407412D01*
X2628924Y407829D01*
X2629854Y408870D01*
X2630474Y410120D01*
X2630939Y411787D01*
X2631094Y413662D01*
X2630939Y415537D01*
X2630474Y417204D01*
X2629854Y418454D01*
X2628924Y419495D01*
X2627684Y419912D01*
G01X2587074Y447087D02*
X2588004Y446045D01*
X2589089Y445420D01*
X2590484Y445212D01*
X2591879Y445629D01*
X2592964Y446462D01*
X2593739Y447920D01*
X2593894Y449587D01*
X2593584Y451254D01*
X2592809Y452295D01*
X2591724Y453129D01*
X2590639Y453337D01*
X2589554Y453129D01*
X2588159Y452295D01*
X2588624Y457712D01*
X2592809D01*
G01X2602884D02*
X2601644Y457295D01*
X2600714Y456254D01*
X2600094Y455004D01*
X2599629Y453337D01*
X2599474Y451462D01*
X2599629Y449587D01*
X2600094Y447920D01*
X2600714Y446670D01*
X2601644Y445629D01*
X2602884Y445212D01*
X2604124Y445629D01*
X2605054Y446670D01*
X2605674Y447920D01*
X2606139Y449587D01*
X2606294Y451462D01*
X2606139Y453337D01*
X2605674Y455004D01*
X2605054Y456254D01*
X2604124Y457295D01*
X2602884Y457712D01*
G01X2615284Y444795D02*
X2614974Y445004D01*
Y445420D01*
X2615284Y445629D01*
X2615594Y445420D01*
Y445004D01*
X2615284Y444795D01*
G01X2627684Y457712D02*
X2626444Y457295D01*
X2625514Y456254D01*
X2624894Y455004D01*
X2624429Y453337D01*
X2624274Y451462D01*
X2624429Y449587D01*
X2624894Y447920D01*
X2625514Y446670D01*
X2626444Y445629D01*
X2627684Y445212D01*
X2628924Y445629D01*
X2629854Y446670D01*
X2630474Y447920D01*
X2630939Y449587D01*
X2631094Y451462D01*
X2630939Y453337D01*
X2630474Y455004D01*
X2629854Y456254D01*
X2628924Y457295D01*
X2627684Y457712D01*
G01X2592344Y483012D02*
Y495512D01*
X2586609Y486554D01*
X2594359D01*
G01X2599939Y488220D02*
X2601024Y489679D01*
X2601954Y490512D01*
X2603194Y490929D01*
X2604279Y490512D01*
X2605054Y489679D01*
X2605674Y488429D01*
X2605829Y486970D01*
X2605674Y485720D01*
X2605054Y484470D01*
X2604124Y483429D01*
X2603039Y483012D01*
X2601799Y483429D01*
X2600714Y484678D01*
X2600094Y486554D01*
X2599939Y488637D01*
X2600249Y491345D01*
X2600714Y492804D01*
X2601489Y494262D01*
X2602574Y495304D01*
X2603659Y495512D01*
X2604744Y495095D01*
X2605519Y494054D01*
G01X2615284Y482595D02*
X2614974Y482804D01*
Y483220D01*
X2615284Y483429D01*
X2615594Y483220D01*
Y482804D01*
X2615284Y482595D01*
G01X2627684Y495512D02*
X2626444Y495095D01*
X2625514Y494054D01*
X2624894Y492804D01*
X2624429Y491137D01*
X2624274Y489262D01*
X2624429Y487387D01*
X2624894Y485720D01*
X2625514Y484470D01*
X2626444Y483429D01*
X2627684Y483012D01*
X2628924Y483429D01*
X2629854Y484470D01*
X2630474Y485720D01*
X2630939Y487387D01*
X2631094Y489262D01*
X2630939Y491137D01*
X2630474Y492804D01*
X2629854Y494054D01*
X2628924Y495095D01*
X2627684Y495512D01*
G01X2592344Y520812D02*
Y533312D01*
X2586609Y524354D01*
X2594359D01*
G01X2602884Y520812D02*
Y533312D01*
X2601024Y530812D01*
G01Y520812D02*
X2604744D01*
G01X2615284Y520395D02*
X2614974Y520604D01*
Y521020D01*
X2615284Y521229D01*
X2615594Y521020D01*
Y520604D01*
X2615284Y520395D01*
G01X2627684Y533312D02*
X2626444Y532895D01*
X2625514Y531854D01*
X2624894Y530604D01*
X2624429Y528937D01*
X2624274Y527062D01*
X2624429Y525187D01*
X2624894Y523520D01*
X2625514Y522270D01*
X2626444Y521229D01*
X2627684Y520812D01*
X2628924Y521229D01*
X2629854Y522270D01*
X2630474Y523520D01*
X2630939Y525187D01*
X2631094Y527062D01*
X2630939Y528937D01*
X2630474Y530604D01*
X2629854Y531854D01*
X2628924Y532895D01*
X2627684Y533312D01*
G01X2587539Y644629D02*
X2588469Y645878D01*
X2589554Y646504D01*
X2590794Y646712D01*
X2592344Y646295D01*
X2593429Y645254D01*
X2593739Y644004D01*
X2593584Y642753D01*
X2592964Y641712D01*
X2589864Y639629D01*
X2588469Y638170D01*
X2587539Y636087D01*
X2587229Y634212D01*
X2593739D01*
G01X2599939Y644629D02*
X2600869Y645878D01*
X2601954Y646504D01*
X2603194Y646712D01*
X2604744Y646295D01*
X2605829Y645254D01*
X2606139Y644004D01*
X2605984Y642753D01*
X2605364Y641712D01*
X2602264Y639629D01*
X2600869Y638170D01*
X2599939Y636087D01*
X2599629Y634212D01*
X2606139D01*
G01X2615284Y633795D02*
X2614974Y634004D01*
Y634420D01*
X2615284Y634629D01*
X2615594Y634420D01*
Y634004D01*
X2615284Y633795D01*
G01X2627684Y646712D02*
X2626444Y646295D01*
X2625514Y645254D01*
X2624894Y644004D01*
X2624429Y642337D01*
X2624274Y640462D01*
X2624429Y638587D01*
X2624894Y636920D01*
X2625514Y635670D01*
X2626444Y634629D01*
X2627684Y634212D01*
X2628924Y634629D01*
X2629854Y635670D01*
X2630474Y636920D01*
X2630939Y638587D01*
X2631094Y640462D01*
X2630939Y642337D01*
X2630474Y644004D01*
X2629854Y645254D01*
X2628924Y646295D01*
X2627684Y646712D01*
G01X2590484Y672012D02*
Y684512D01*
X2588624Y682012D01*
G01Y672012D02*
X2592344D01*
G01X2602884Y684512D02*
X2601644Y684095D01*
X2600714Y683054D01*
X2600094Y681804D01*
X2599629Y680137D01*
X2599474Y678262D01*
X2599629Y676387D01*
X2600094Y674720D01*
X2600714Y673470D01*
X2601644Y672429D01*
X2602884Y672012D01*
X2604124Y672429D01*
X2605054Y673470D01*
X2605674Y674720D01*
X2606139Y676387D01*
X2606294Y678262D01*
X2606139Y680137D01*
X2605674Y681804D01*
X2605054Y683054D01*
X2604124Y684095D01*
X2602884Y684512D01*
G01X2615284Y671595D02*
X2614974Y671804D01*
Y672220D01*
X2615284Y672429D01*
X2615594Y672220D01*
Y671804D01*
X2615284Y671595D01*
G01X2627684Y684512D02*
X2626444Y684095D01*
X2625514Y683054D01*
X2624894Y681804D01*
X2624429Y680137D01*
X2624274Y678262D01*
X2624429Y676387D01*
X2624894Y674720D01*
X2625514Y673470D01*
X2626444Y672429D01*
X2627684Y672012D01*
X2628924Y672429D01*
X2629854Y673470D01*
X2630474Y674720D01*
X2630939Y676387D01*
X2631094Y678262D01*
X2630939Y680137D01*
X2630474Y681804D01*
X2629854Y683054D01*
X2628924Y684095D01*
X2627684Y684512D01*
G01X2590484Y709812D02*
Y722312D01*
X2588624Y719812D01*
G01Y709812D02*
X2592344D01*
G01X2602884Y722312D02*
X2601644Y721895D01*
X2600714Y720854D01*
X2600094Y719604D01*
X2599629Y717937D01*
X2599474Y716062D01*
X2599629Y714187D01*
X2600094Y712520D01*
X2600714Y711270D01*
X2601644Y710229D01*
X2602884Y709812D01*
X2604124Y710229D01*
X2605054Y711270D01*
X2605674Y712520D01*
X2606139Y714187D01*
X2606294Y716062D01*
X2606139Y717937D01*
X2605674Y719604D01*
X2605054Y720854D01*
X2604124Y721895D01*
X2602884Y722312D01*
G01X2615284Y709395D02*
X2614974Y709604D01*
Y710020D01*
X2615284Y710229D01*
X2615594Y710020D01*
Y709604D01*
X2615284Y709395D01*
G01X2627684Y722312D02*
X2626444Y721895D01*
X2625514Y720854D01*
X2624894Y719604D01*
X2624429Y717937D01*
X2624274Y716062D01*
X2624429Y714187D01*
X2624894Y712520D01*
X2625514Y711270D01*
X2626444Y710229D01*
X2627684Y709812D01*
X2628924Y710229D01*
X2629854Y711270D01*
X2630474Y712520D01*
X2630939Y714187D01*
X2631094Y716062D01*
X2630939Y717937D01*
X2630474Y719604D01*
X2629854Y720854D01*
X2628924Y721895D01*
X2627684Y722312D01*
G01X2723784Y753712D02*
Y741212D01*
G01X2720219Y753712D02*
X2727349D01*
G01X2736184Y741212D02*
X2734944Y741420D01*
X2733859Y742253D01*
X2732929Y743504D01*
X2732309Y744962D01*
X2731999Y746629D01*
Y748295D01*
X2732309Y749962D01*
X2732929Y751420D01*
X2733859Y752670D01*
X2734944Y753504D01*
X2736184Y753712D01*
X2737424Y753504D01*
X2738509Y752670D01*
X2739439Y751420D01*
X2740059Y749962D01*
X2740369Y748295D01*
Y746629D01*
X2740059Y744962D01*
X2739439Y743504D01*
X2738509Y742253D01*
X2737424Y741420D01*
X2736184Y741212D01*
G01X2745484Y753712D02*
Y741212D01*
X2751684D01*
G01X2764084D02*
X2757884D01*
Y753712D01*
X2764084D01*
G01X2761604Y747670D02*
X2757884D01*
G01X2770284Y741212D02*
Y753712D01*
X2774159D01*
X2775399Y753087D01*
X2776174Y752254D01*
X2776484Y750587D01*
X2776174Y748920D01*
X2775244Y747879D01*
X2774159Y747254D01*
X2770284D01*
G01X2774159D02*
X2776484Y741212D01*
G01X2781909D02*
X2785784Y753712D01*
X2789659Y741212D01*
G01X2788264Y745587D02*
X2783304D01*
G01X2794619Y741212D02*
Y753712D01*
X2801749Y741212D01*
Y753712D01*
G01X2813994Y752670D02*
X2813064Y753295D01*
X2811979Y753712D01*
X2810739D01*
X2809344Y753087D01*
X2808259Y752045D01*
X2807484Y750795D01*
X2806864Y748712D01*
X2806709Y746837D01*
X2807019Y744962D01*
X2807484Y743712D01*
X2808414Y742462D01*
X2809499Y741629D01*
X2810584Y741212D01*
X2811669D01*
X2812754Y741629D01*
X2813684Y742253D01*
X2814459Y743087D01*
G01X2826084Y741212D02*
X2819884D01*
Y753712D01*
X2826084D01*
G01X2823604Y747670D02*
X2819884D01*
G01X2830734Y737045D02*
X2840034D01*
G01X2844374Y741212D02*
Y753712D01*
X2847474D01*
X2848714Y753087D01*
X2849644Y752254D01*
X2850419Y751004D01*
X2851039Y749545D01*
X2851194Y747462D01*
X2851039Y745379D01*
X2850419Y743920D01*
X2849644Y742670D01*
X2848714Y741837D01*
X2847474Y741212D01*
X2844374D01*
G01X2857084D02*
Y753712D01*
X2860959D01*
X2862199Y753087D01*
X2862974Y752254D01*
X2863284Y750587D01*
X2862974Y748920D01*
X2862044Y747879D01*
X2860959Y747254D01*
X2857084D01*
G01X2860959D02*
X2863284Y741212D01*
G01X2870724Y753712D02*
X2874444D01*
G01X2872584D02*
Y741212D01*
G01X2870724D02*
X2874444D01*
G01X2881884Y753712D02*
Y741212D01*
X2888084D01*
G01X2894284Y753712D02*
Y741212D01*
X2900484D01*
G01X2709524Y791212D02*
Y803712D01*
X2712624D01*
X2713864Y803087D01*
X2714794Y802254D01*
X2715569Y801004D01*
X2716189Y799545D01*
X2716344Y797462D01*
X2716189Y795379D01*
X2715569Y793920D01*
X2714794Y792670D01*
X2713864Y791837D01*
X2712624Y791212D01*
X2709524D01*
G01X2722234D02*
Y803712D01*
X2726109D01*
X2727349Y803087D01*
X2728124Y802254D01*
X2728434Y800587D01*
X2728124Y798920D01*
X2727194Y797879D01*
X2726109Y797254D01*
X2722234D01*
G01X2726109D02*
X2728434Y791212D01*
G01X2735874Y803712D02*
X2739594D01*
G01X2737734D02*
Y791212D01*
G01X2735874D02*
X2739594D01*
G01X2747034Y803712D02*
Y791212D01*
X2753234D01*
G01X2759434Y803712D02*
Y791212D01*
X2765634D01*
G01X2790744Y802670D02*
X2789814Y803295D01*
X2788729Y803712D01*
X2787489D01*
X2786094Y803087D01*
X2785009Y802045D01*
X2784234Y800795D01*
X2783614Y798712D01*
X2783459Y796837D01*
X2783769Y794962D01*
X2784234Y793712D01*
X2785164Y792462D01*
X2786249Y791629D01*
X2787334Y791212D01*
X2788419D01*
X2789504Y791629D01*
X2790434Y792253D01*
X2791209Y793087D01*
G01X2796479Y791212D02*
Y803712D01*
G01X2802989D02*
Y791212D01*
G01Y797462D02*
X2796479D01*
G01X2808259Y791212D02*
X2812134Y803712D01*
X2816009Y791212D01*
G01X2814614Y795587D02*
X2809654D01*
G01X2821434Y791212D02*
Y803712D01*
X2825309D01*
X2826549Y803087D01*
X2827324Y802254D01*
X2827634Y800587D01*
X2827324Y798920D01*
X2826394Y797879D01*
X2825309Y797254D01*
X2821434D01*
G01X2825309D02*
X2827634Y791212D01*
G01X2836934Y803712D02*
Y791212D01*
G01X2833369Y803712D02*
X2840499D01*
G01X2849334Y790795D02*
X2849024Y791004D01*
Y791420D01*
X2849334Y791629D01*
X2849644Y791420D01*
Y791004D01*
X2849334Y790795D01*
G01Y796420D02*
X2849024Y796629D01*
Y797045D01*
X2849334Y797254D01*
X2849644Y797045D01*
Y796629D01*
X2849334Y796420D01*
G01X2874134Y803712D02*
Y791212D01*
G01X2870569Y803712D02*
X2877699D01*
G01X2886534Y791212D02*
X2885294Y791420D01*
X2884209Y792253D01*
X2883279Y793504D01*
X2882659Y794962D01*
X2882349Y796629D01*
Y798295D01*
X2882659Y799962D01*
X2883279Y801420D01*
X2884209Y802670D01*
X2885294Y803504D01*
X2886534Y803712D01*
X2887774Y803504D01*
X2888859Y802670D01*
X2889789Y801420D01*
X2890409Y799962D01*
X2890719Y798295D01*
Y796629D01*
X2890409Y794962D01*
X2889789Y793504D01*
X2888859Y792253D01*
X2887774Y791420D01*
X2886534Y791212D01*
G01X2895834D02*
Y803712D01*
X2899554D01*
X2900794Y803087D01*
X2901724Y801629D01*
X2902034Y799962D01*
X2901724Y798295D01*
X2900949Y797045D01*
X2899554Y796420D01*
X2895834D01*
G01X2923734Y803712D02*
Y791212D01*
G01X2921564Y799545D02*
X2925904D01*
G01X2936134Y791212D02*
X2935204Y791420D01*
X2934274Y792253D01*
X2933654Y793712D01*
X2933344Y795379D01*
X2933654Y797045D01*
X2934274Y798504D01*
X2935204Y799337D01*
X2936134Y799545D01*
X2937064Y799337D01*
X2937994Y798504D01*
X2938614Y797045D01*
X2938769Y795379D01*
X2938614Y793712D01*
X2937994Y792253D01*
X2937064Y791420D01*
X2936134Y791212D01*
G01X2962174Y797879D02*
X2962794Y798504D01*
X2963259Y799545D01*
X2963569Y801004D01*
X2963259Y802254D01*
X2962639Y803087D01*
X2961554Y803712D01*
X2957369D01*
Y791212D01*
X2962484D01*
X2963569Y792045D01*
X2964189Y793295D01*
X2964499Y794754D01*
X2964189Y796212D01*
X2963259Y797462D01*
X2962174Y797879D01*
X2957369D01*
G01X2973334Y791212D02*
X2972094Y791420D01*
X2971009Y792253D01*
X2970079Y793504D01*
X2969459Y794962D01*
X2969149Y796629D01*
Y798295D01*
X2969459Y799962D01*
X2970079Y801420D01*
X2971009Y802670D01*
X2972094Y803504D01*
X2973334Y803712D01*
X2974574Y803504D01*
X2975659Y802670D01*
X2976589Y801420D01*
X2977209Y799962D01*
X2977519Y798295D01*
Y796629D01*
X2977209Y794962D01*
X2976589Y793504D01*
X2975659Y792253D01*
X2974574Y791420D01*
X2973334Y791212D01*
G01X2985734Y803712D02*
Y791212D01*
G01X2982169Y803712D02*
X2989299D01*
G01X2998134D02*
Y791212D01*
G01X2994569Y803712D02*
X3001699D01*
G01X3010534Y791212D02*
X3009294Y791420D01*
X3008209Y792253D01*
X3007279Y793504D01*
X3006659Y794962D01*
X3006349Y796629D01*
Y798295D01*
X3006659Y799962D01*
X3007279Y801420D01*
X3008209Y802670D01*
X3009294Y803504D01*
X3010534Y803712D01*
X3011774Y803504D01*
X3012859Y802670D01*
X3013789Y801420D01*
X3014409Y799962D01*
X3014719Y798295D01*
Y796629D01*
X3014409Y794962D01*
X3013789Y793504D01*
X3012859Y792253D01*
X3011774Y791420D01*
X3010534Y791212D01*
G01X3018904D02*
Y803712D01*
X3022934Y793295D01*
X3026964Y803712D01*
Y791212D01*
G01X2759279Y-42021D02*
X2762999D01*
G01X2760984Y-39313D02*
Y-44730D01*
G01X2770439Y-35771D02*
X2771369Y-34522D01*
X2772454Y-33896D01*
X2773694Y-33688D01*
X2775244Y-34105D01*
X2776329Y-35146D01*
X2776639Y-36396D01*
X2776484Y-37647D01*
X2775864Y-38688D01*
X2772764Y-40771D01*
X2771369Y-42230D01*
X2770439Y-44313D01*
X2770129Y-46188D01*
X2776639D01*
G01X2785784Y-46605D02*
X2785474Y-46396D01*
Y-45980D01*
X2785784Y-45771D01*
X2786094Y-45980D01*
Y-46396D01*
X2785784Y-46605D01*
G01X2798184Y-33688D02*
X2796944Y-34105D01*
X2796014Y-35146D01*
X2795394Y-36396D01*
X2794929Y-38063D01*
X2794774Y-39938D01*
X2794929Y-41813D01*
X2795394Y-43480D01*
X2796014Y-44730D01*
X2796944Y-45771D01*
X2798184Y-46188D01*
X2799424Y-45771D01*
X2800354Y-44730D01*
X2800974Y-43480D01*
X2801439Y-41813D01*
X2801594Y-39938D01*
X2801439Y-38063D01*
X2800974Y-36396D01*
X2800354Y-35146D01*
X2799424Y-34105D01*
X2798184Y-33688D01*
G01X2807794Y-46605D02*
X2813374Y-33688D01*
G01X2820969Y-42021D02*
X2824999D01*
G01X2832439Y-35771D02*
X2833369Y-34522D01*
X2834454Y-33896D01*
X2835694Y-33688D01*
X2837244Y-34105D01*
X2838329Y-35146D01*
X2838639Y-36396D01*
X2838484Y-37647D01*
X2837864Y-38688D01*
X2834764Y-40771D01*
X2833369Y-42230D01*
X2832439Y-44313D01*
X2832129Y-46188D01*
X2838639D01*
G01X2847784Y-46605D02*
X2847474Y-46396D01*
Y-45980D01*
X2847784Y-45771D01*
X2848094Y-45980D01*
Y-46396D01*
X2847784Y-46605D01*
G01X2860184Y-33688D02*
X2858944Y-34105D01*
X2858014Y-35146D01*
X2857394Y-36396D01*
X2856929Y-38063D01*
X2856774Y-39938D01*
X2856929Y-41813D01*
X2857394Y-43480D01*
X2858014Y-44730D01*
X2858944Y-45771D01*
X2860184Y-46188D01*
X2861424Y-45771D01*
X2862354Y-44730D01*
X2862974Y-43480D01*
X2863439Y-41813D01*
X2863594Y-39938D01*
X2863439Y-38063D01*
X2862974Y-36396D01*
X2862354Y-35146D01*
X2861424Y-34105D01*
X2860184Y-33688D01*
G01X2759279Y-4221D02*
X2762999D01*
G01X2760984Y-1513D02*
Y-6930D01*
G01X2770439Y2029D02*
X2771369Y3278D01*
X2772454Y3904D01*
X2773694Y4112D01*
X2775244Y3695D01*
X2776329Y2654D01*
X2776639Y1404D01*
X2776484Y153D01*
X2775864Y-888D01*
X2772764Y-2971D01*
X2771369Y-4430D01*
X2770439Y-6513D01*
X2770129Y-8388D01*
X2776639D01*
G01X2785784Y-8805D02*
X2785474Y-8596D01*
Y-8180D01*
X2785784Y-7971D01*
X2786094Y-8180D01*
Y-8596D01*
X2785784Y-8805D01*
G01X2798184Y4112D02*
X2796944Y3695D01*
X2796014Y2654D01*
X2795394Y1404D01*
X2794929Y-263D01*
X2794774Y-2138D01*
X2794929Y-4013D01*
X2795394Y-5680D01*
X2796014Y-6930D01*
X2796944Y-7971D01*
X2798184Y-8388D01*
X2799424Y-7971D01*
X2800354Y-6930D01*
X2800974Y-5680D01*
X2801439Y-4013D01*
X2801594Y-2138D01*
X2801439Y-263D01*
X2800974Y1404D01*
X2800354Y2654D01*
X2799424Y3695D01*
X2798184Y4112D01*
G01X2807794Y-8805D02*
X2813374Y4112D01*
G01X2820969Y-4221D02*
X2824999D01*
G01X2832439Y2029D02*
X2833369Y3278D01*
X2834454Y3904D01*
X2835694Y4112D01*
X2837244Y3695D01*
X2838329Y2654D01*
X2838639Y1404D01*
X2838484Y153D01*
X2837864Y-888D01*
X2834764Y-2971D01*
X2833369Y-4430D01*
X2832439Y-6513D01*
X2832129Y-8388D01*
X2838639D01*
G01X2847784Y-8805D02*
X2847474Y-8596D01*
Y-8180D01*
X2847784Y-7971D01*
X2848094Y-8180D01*
Y-8596D01*
X2847784Y-8805D01*
G01X2860184Y4112D02*
X2858944Y3695D01*
X2858014Y2654D01*
X2857394Y1404D01*
X2856929Y-263D01*
X2856774Y-2138D01*
X2856929Y-4013D01*
X2857394Y-5680D01*
X2858014Y-6930D01*
X2858944Y-7971D01*
X2860184Y-8388D01*
X2861424Y-7971D01*
X2862354Y-6930D01*
X2862974Y-5680D01*
X2863439Y-4013D01*
X2863594Y-2138D01*
X2863439Y-263D01*
X2862974Y1404D01*
X2862354Y2654D01*
X2861424Y3695D01*
X2860184Y4112D01*
G01X2759279Y33579D02*
X2762999D01*
G01X2760984Y36287D02*
Y30870D01*
G01X2770439Y39829D02*
X2771369Y41078D01*
X2772454Y41704D01*
X2773694Y41912D01*
X2775244Y41495D01*
X2776329Y40454D01*
X2776639Y39204D01*
X2776484Y37953D01*
X2775864Y36912D01*
X2772764Y34829D01*
X2771369Y33370D01*
X2770439Y31287D01*
X2770129Y29412D01*
X2776639D01*
G01X2785784Y28995D02*
X2785474Y29204D01*
Y29620D01*
X2785784Y29829D01*
X2786094Y29620D01*
Y29204D01*
X2785784Y28995D01*
G01X2798184Y41912D02*
X2796944Y41495D01*
X2796014Y40454D01*
X2795394Y39204D01*
X2794929Y37537D01*
X2794774Y35662D01*
X2794929Y33787D01*
X2795394Y32120D01*
X2796014Y30870D01*
X2796944Y29829D01*
X2798184Y29412D01*
X2799424Y29829D01*
X2800354Y30870D01*
X2800974Y32120D01*
X2801439Y33787D01*
X2801594Y35662D01*
X2801439Y37537D01*
X2800974Y39204D01*
X2800354Y40454D01*
X2799424Y41495D01*
X2798184Y41912D01*
G01X2807794Y28995D02*
X2813374Y41912D01*
G01X2820969Y33579D02*
X2824999D01*
G01X2832439Y39829D02*
X2833369Y41078D01*
X2834454Y41704D01*
X2835694Y41912D01*
X2837244Y41495D01*
X2838329Y40454D01*
X2838639Y39204D01*
X2838484Y37953D01*
X2837864Y36912D01*
X2834764Y34829D01*
X2833369Y33370D01*
X2832439Y31287D01*
X2832129Y29412D01*
X2838639D01*
G01X2847784Y28995D02*
X2847474Y29204D01*
Y29620D01*
X2847784Y29829D01*
X2848094Y29620D01*
Y29204D01*
X2847784Y28995D01*
G01X2860184Y41912D02*
X2858944Y41495D01*
X2858014Y40454D01*
X2857394Y39204D01*
X2856929Y37537D01*
X2856774Y35662D01*
X2856929Y33787D01*
X2857394Y32120D01*
X2858014Y30870D01*
X2858944Y29829D01*
X2860184Y29412D01*
X2861424Y29829D01*
X2862354Y30870D01*
X2862974Y32120D01*
X2863439Y33787D01*
X2863594Y35662D01*
X2863439Y37537D01*
X2862974Y39204D01*
X2862354Y40454D01*
X2861424Y41495D01*
X2860184Y41912D01*
G01X2759279Y71379D02*
X2762999D01*
G01X2760984Y74087D02*
Y68670D01*
G01X2770439Y77629D02*
X2771369Y78878D01*
X2772454Y79504D01*
X2773694Y79712D01*
X2775244Y79295D01*
X2776329Y78254D01*
X2776639Y77004D01*
X2776484Y75753D01*
X2775864Y74712D01*
X2772764Y72629D01*
X2771369Y71170D01*
X2770439Y69087D01*
X2770129Y67212D01*
X2776639D01*
G01X2785784Y66795D02*
X2785474Y67004D01*
Y67420D01*
X2785784Y67629D01*
X2786094Y67420D01*
Y67004D01*
X2785784Y66795D01*
G01X2798184Y79712D02*
X2796944Y79295D01*
X2796014Y78254D01*
X2795394Y77004D01*
X2794929Y75337D01*
X2794774Y73462D01*
X2794929Y71587D01*
X2795394Y69920D01*
X2796014Y68670D01*
X2796944Y67629D01*
X2798184Y67212D01*
X2799424Y67629D01*
X2800354Y68670D01*
X2800974Y69920D01*
X2801439Y71587D01*
X2801594Y73462D01*
X2801439Y75337D01*
X2800974Y77004D01*
X2800354Y78254D01*
X2799424Y79295D01*
X2798184Y79712D01*
G01X2807794Y66795D02*
X2813374Y79712D01*
G01X2820969Y71379D02*
X2824999D01*
G01X2835384Y79712D02*
X2834144Y79295D01*
X2833214Y78254D01*
X2832594Y77004D01*
X2832129Y75337D01*
X2831974Y73462D01*
X2832129Y71587D01*
X2832594Y69920D01*
X2833214Y68670D01*
X2834144Y67629D01*
X2835384Y67212D01*
X2836624Y67629D01*
X2837554Y68670D01*
X2838174Y69920D01*
X2838639Y71587D01*
X2838794Y73462D01*
X2838639Y75337D01*
X2838174Y77004D01*
X2837554Y78254D01*
X2836624Y79295D01*
X2835384Y79712D01*
G01X2847784Y66795D02*
X2847474Y67004D01*
Y67420D01*
X2847784Y67629D01*
X2848094Y67420D01*
Y67004D01*
X2847784Y66795D01*
G01X2860184Y79712D02*
X2858944Y79295D01*
X2858014Y78254D01*
X2857394Y77004D01*
X2856929Y75337D01*
X2856774Y73462D01*
X2856929Y71587D01*
X2857394Y69920D01*
X2858014Y68670D01*
X2858944Y67629D01*
X2860184Y67212D01*
X2861424Y67629D01*
X2862354Y68670D01*
X2862974Y69920D01*
X2863439Y71587D01*
X2863594Y73462D01*
X2863439Y75337D01*
X2862974Y77004D01*
X2862354Y78254D01*
X2861424Y79295D01*
X2860184Y79712D01*
G01X2759279Y109179D02*
X2762999D01*
G01X2760984Y111887D02*
Y106470D01*
G01X2770439Y115429D02*
X2771369Y116678D01*
X2772454Y117304D01*
X2773694Y117512D01*
X2775244Y117095D01*
X2776329Y116054D01*
X2776639Y114804D01*
X2776484Y113553D01*
X2775864Y112512D01*
X2772764Y110429D01*
X2771369Y108970D01*
X2770439Y106887D01*
X2770129Y105012D01*
X2776639D01*
G01X2785784Y104595D02*
X2785474Y104804D01*
Y105220D01*
X2785784Y105429D01*
X2786094Y105220D01*
Y104804D01*
X2785784Y104595D01*
G01X2798184Y117512D02*
X2796944Y117095D01*
X2796014Y116054D01*
X2795394Y114804D01*
X2794929Y113137D01*
X2794774Y111262D01*
X2794929Y109387D01*
X2795394Y107720D01*
X2796014Y106470D01*
X2796944Y105429D01*
X2798184Y105012D01*
X2799424Y105429D01*
X2800354Y106470D01*
X2800974Y107720D01*
X2801439Y109387D01*
X2801594Y111262D01*
X2801439Y113137D01*
X2800974Y114804D01*
X2800354Y116054D01*
X2799424Y117095D01*
X2798184Y117512D01*
G01X2807794Y104595D02*
X2813374Y117512D01*
G01X2820969Y109179D02*
X2824999D01*
G01X2832439Y115429D02*
X2833369Y116678D01*
X2834454Y117304D01*
X2835694Y117512D01*
X2837244Y117095D01*
X2838329Y116054D01*
X2838639Y114804D01*
X2838484Y113553D01*
X2837864Y112512D01*
X2834764Y110429D01*
X2833369Y108970D01*
X2832439Y106887D01*
X2832129Y105012D01*
X2838639D01*
G01X2847784Y104595D02*
X2847474Y104804D01*
Y105220D01*
X2847784Y105429D01*
X2848094Y105220D01*
Y104804D01*
X2847784Y104595D01*
G01X2860184Y117512D02*
X2858944Y117095D01*
X2858014Y116054D01*
X2857394Y114804D01*
X2856929Y113137D01*
X2856774Y111262D01*
X2856929Y109387D01*
X2857394Y107720D01*
X2858014Y106470D01*
X2858944Y105429D01*
X2860184Y105012D01*
X2861424Y105429D01*
X2862354Y106470D01*
X2862974Y107720D01*
X2863439Y109387D01*
X2863594Y111262D01*
X2863439Y113137D01*
X2862974Y114804D01*
X2862354Y116054D01*
X2861424Y117095D01*
X2860184Y117512D01*
G01X2746879Y146979D02*
X2750599D01*
G01X2748584Y149687D02*
Y144270D01*
G01X2760984Y142812D02*
Y155312D01*
X2759124Y152812D01*
G01Y142812D02*
X2762844D01*
G01X2773384Y142395D02*
X2773074Y142604D01*
Y143020D01*
X2773384Y143229D01*
X2773694Y143020D01*
Y142604D01*
X2773384Y142395D01*
G01X2785784Y142812D02*
Y155312D01*
X2783924Y152812D01*
G01Y142812D02*
X2787644D01*
G01X2798184D02*
X2799269Y143020D01*
X2800509Y143645D01*
X2801284Y144687D01*
X2801594Y146145D01*
X2801284Y147603D01*
X2800354Y148854D01*
X2798959Y149479D01*
X2797409D01*
X2796479Y149895D01*
X2795704Y150937D01*
X2795394Y152395D01*
X2795859Y153854D01*
X2796944Y154895D01*
X2798184Y155312D01*
X2799424Y154895D01*
X2800509Y153854D01*
X2800974Y152395D01*
X2800664Y150937D01*
X2799889Y149895D01*
X2798959Y149479D01*
X2797409D01*
X2796014Y148854D01*
X2795084Y147603D01*
X2794774Y146145D01*
X2795084Y144687D01*
X2795859Y143645D01*
X2797099Y143020D01*
X2798184Y142812D01*
G01X2807794Y142395D02*
X2813374Y155312D01*
G01X2820969Y146979D02*
X2824999D01*
G01X2835384Y142812D02*
Y155312D01*
X2833524Y152812D01*
G01Y142812D02*
X2837244D01*
G01X2847784Y142395D02*
X2847474Y142604D01*
Y143020D01*
X2847784Y143229D01*
X2848094Y143020D01*
Y142604D01*
X2847784Y142395D01*
G01X2860184Y142812D02*
Y155312D01*
X2858324Y152812D01*
G01Y142812D02*
X2862044D01*
G01X2872584D02*
X2873669Y143020D01*
X2874909Y143645D01*
X2875684Y144687D01*
X2875994Y146145D01*
X2875684Y147603D01*
X2874754Y148854D01*
X2873359Y149479D01*
X2871809D01*
X2870879Y149895D01*
X2870104Y150937D01*
X2869794Y152395D01*
X2870259Y153854D01*
X2871344Y154895D01*
X2872584Y155312D01*
X2873824Y154895D01*
X2874909Y153854D01*
X2875374Y152395D01*
X2875064Y150937D01*
X2874289Y149895D01*
X2873359Y149479D01*
X2871809D01*
X2870414Y148854D01*
X2869484Y147603D01*
X2869174Y146145D01*
X2869484Y144687D01*
X2870259Y143645D01*
X2871499Y143020D01*
X2872584Y142812D01*
G01X2759279Y184779D02*
X2762999D01*
G01X2760984Y187487D02*
Y182070D01*
G01X2770439Y191029D02*
X2771369Y192278D01*
X2772454Y192904D01*
X2773694Y193112D01*
X2775244Y192695D01*
X2776329Y191654D01*
X2776639Y190404D01*
X2776484Y189153D01*
X2775864Y188112D01*
X2772764Y186029D01*
X2771369Y184570D01*
X2770439Y182487D01*
X2770129Y180612D01*
X2776639D01*
G01X2785784Y180195D02*
X2785474Y180404D01*
Y180820D01*
X2785784Y181029D01*
X2786094Y180820D01*
Y180404D01*
X2785784Y180195D01*
G01X2798184Y193112D02*
X2796944Y192695D01*
X2796014Y191654D01*
X2795394Y190404D01*
X2794929Y188737D01*
X2794774Y186862D01*
X2794929Y184987D01*
X2795394Y183320D01*
X2796014Y182070D01*
X2796944Y181029D01*
X2798184Y180612D01*
X2799424Y181029D01*
X2800354Y182070D01*
X2800974Y183320D01*
X2801439Y184987D01*
X2801594Y186862D01*
X2801439Y188737D01*
X2800974Y190404D01*
X2800354Y191654D01*
X2799424Y192695D01*
X2798184Y193112D01*
G01X2807794Y180195D02*
X2813374Y193112D01*
G01X2820969Y184779D02*
X2824999D01*
G01X2832439Y191029D02*
X2833369Y192278D01*
X2834454Y192904D01*
X2835694Y193112D01*
X2837244Y192695D01*
X2838329Y191654D01*
X2838639Y190404D01*
X2838484Y189153D01*
X2837864Y188112D01*
X2834764Y186029D01*
X2833369Y184570D01*
X2832439Y182487D01*
X2832129Y180612D01*
X2838639D01*
G01X2847784Y180195D02*
X2847474Y180404D01*
Y180820D01*
X2847784Y181029D01*
X2848094Y180820D01*
Y180404D01*
X2847784Y180195D01*
G01X2860184Y193112D02*
X2858944Y192695D01*
X2858014Y191654D01*
X2857394Y190404D01*
X2856929Y188737D01*
X2856774Y186862D01*
X2856929Y184987D01*
X2857394Y183320D01*
X2858014Y182070D01*
X2858944Y181029D01*
X2860184Y180612D01*
X2861424Y181029D01*
X2862354Y182070D01*
X2862974Y183320D01*
X2863439Y184987D01*
X2863594Y186862D01*
X2863439Y188737D01*
X2862974Y190404D01*
X2862354Y191654D01*
X2861424Y192695D01*
X2860184Y193112D01*
G01X2753079Y222579D02*
X2756799D01*
G01X2754784Y225287D02*
Y219870D01*
G01X2767184Y218412D02*
Y230912D01*
X2765324Y228412D01*
G01Y218412D02*
X2769044D01*
G01X2779584Y217995D02*
X2779274Y218204D01*
Y218620D01*
X2779584Y218829D01*
X2779894Y218620D01*
Y218204D01*
X2779584Y217995D01*
G01X2789349Y219870D02*
X2790434Y218829D01*
X2791674Y218412D01*
X2792914Y218829D01*
X2793999Y220078D01*
X2794774Y221954D01*
X2795084Y223829D01*
Y226120D01*
X2794774Y227995D01*
X2793999Y229662D01*
X2793069Y230495D01*
X2791984Y230912D01*
X2790744Y230495D01*
X2789814Y229662D01*
X2789194Y228412D01*
X2788884Y226745D01*
X2789194Y225287D01*
X2789969Y223829D01*
X2790899Y222995D01*
X2791984Y222787D01*
X2793224Y223203D01*
X2794154Y224245D01*
X2795084Y226120D01*
G01X2801439Y223620D02*
X2802524Y225079D01*
X2803454Y225912D01*
X2804694Y226329D01*
X2805779Y225912D01*
X2806554Y225079D01*
X2807174Y223829D01*
X2807329Y222370D01*
X2807174Y221120D01*
X2806554Y219870D01*
X2805624Y218829D01*
X2804539Y218412D01*
X2803299Y218829D01*
X2802214Y220078D01*
X2801594Y221954D01*
X2801439Y224037D01*
X2801749Y226745D01*
X2802214Y228204D01*
X2802989Y229662D01*
X2804074Y230704D01*
X2805159Y230912D01*
X2806244Y230495D01*
X2807019Y229454D01*
G01X2813994Y217995D02*
X2819574Y230912D01*
G01X2827169Y222579D02*
X2831199D01*
G01X2841584Y230912D02*
X2840344Y230495D01*
X2839414Y229454D01*
X2838794Y228204D01*
X2838329Y226537D01*
X2838174Y224662D01*
X2838329Y222787D01*
X2838794Y221120D01*
X2839414Y219870D01*
X2840344Y218829D01*
X2841584Y218412D01*
X2842824Y218829D01*
X2843754Y219870D01*
X2844374Y221120D01*
X2844839Y222787D01*
X2844994Y224662D01*
X2844839Y226537D01*
X2844374Y228204D01*
X2843754Y229454D01*
X2842824Y230495D01*
X2841584Y230912D01*
G01X2853984Y217995D02*
X2853674Y218204D01*
Y218620D01*
X2853984Y218829D01*
X2854294Y218620D01*
Y218204D01*
X2853984Y217995D01*
G01X2866384Y230912D02*
X2865144Y230495D01*
X2864214Y229454D01*
X2863594Y228204D01*
X2863129Y226537D01*
X2862974Y224662D01*
X2863129Y222787D01*
X2863594Y221120D01*
X2864214Y219870D01*
X2865144Y218829D01*
X2866384Y218412D01*
X2867624Y218829D01*
X2868554Y219870D01*
X2869174Y221120D01*
X2869639Y222787D01*
X2869794Y224662D01*
X2869639Y226537D01*
X2869174Y228204D01*
X2868554Y229454D01*
X2867624Y230495D01*
X2866384Y230912D01*
G01X2759279Y260379D02*
X2762999D01*
G01X2760984Y263087D02*
Y257670D01*
G01X2775244Y256212D02*
Y268712D01*
X2769509Y259754D01*
X2777259D01*
G01X2785784Y255795D02*
X2785474Y256004D01*
Y256420D01*
X2785784Y256629D01*
X2786094Y256420D01*
Y256004D01*
X2785784Y255795D01*
G01X2798184Y268712D02*
X2796944Y268295D01*
X2796014Y267254D01*
X2795394Y266004D01*
X2794929Y264337D01*
X2794774Y262462D01*
X2794929Y260587D01*
X2795394Y258920D01*
X2796014Y257670D01*
X2796944Y256629D01*
X2798184Y256212D01*
X2799424Y256629D01*
X2800354Y257670D01*
X2800974Y258920D01*
X2801439Y260587D01*
X2801594Y262462D01*
X2801439Y264337D01*
X2800974Y266004D01*
X2800354Y267254D01*
X2799424Y268295D01*
X2798184Y268712D01*
G01X2807794Y255795D02*
X2813374Y268712D01*
G01X2820969Y260379D02*
X2824999D01*
G01X2837244Y256212D02*
Y268712D01*
X2831509Y259754D01*
X2839259D01*
G01X2847784Y255795D02*
X2847474Y256004D01*
Y256420D01*
X2847784Y256629D01*
X2848094Y256420D01*
Y256004D01*
X2847784Y255795D01*
G01X2860184Y268712D02*
X2858944Y268295D01*
X2858014Y267254D01*
X2857394Y266004D01*
X2856929Y264337D01*
X2856774Y262462D01*
X2856929Y260587D01*
X2857394Y258920D01*
X2858014Y257670D01*
X2858944Y256629D01*
X2860184Y256212D01*
X2861424Y256629D01*
X2862354Y257670D01*
X2862974Y258920D01*
X2863439Y260587D01*
X2863594Y262462D01*
X2863439Y264337D01*
X2862974Y266004D01*
X2862354Y267254D01*
X2861424Y268295D01*
X2860184Y268712D01*
G01X2759279Y298179D02*
X2762999D01*
G01X2760984Y300887D02*
Y295470D01*
G01X2770439Y304429D02*
X2771369Y305678D01*
X2772454Y306304D01*
X2773694Y306512D01*
X2775244Y306095D01*
X2776329Y305054D01*
X2776639Y303804D01*
X2776484Y302553D01*
X2775864Y301512D01*
X2772764Y299429D01*
X2771369Y297970D01*
X2770439Y295887D01*
X2770129Y294012D01*
X2776639D01*
G01X2785784Y293595D02*
X2785474Y293804D01*
Y294220D01*
X2785784Y294429D01*
X2786094Y294220D01*
Y293804D01*
X2785784Y293595D01*
G01X2798184Y306512D02*
X2796944Y306095D01*
X2796014Y305054D01*
X2795394Y303804D01*
X2794929Y302137D01*
X2794774Y300262D01*
X2794929Y298387D01*
X2795394Y296720D01*
X2796014Y295470D01*
X2796944Y294429D01*
X2798184Y294012D01*
X2799424Y294429D01*
X2800354Y295470D01*
X2800974Y296720D01*
X2801439Y298387D01*
X2801594Y300262D01*
X2801439Y302137D01*
X2800974Y303804D01*
X2800354Y305054D01*
X2799424Y306095D01*
X2798184Y306512D01*
G01X2807794Y293595D02*
X2813374Y306512D01*
G01X2820969Y298179D02*
X2824999D01*
G01X2832439Y304429D02*
X2833369Y305678D01*
X2834454Y306304D01*
X2835694Y306512D01*
X2837244Y306095D01*
X2838329Y305054D01*
X2838639Y303804D01*
X2838484Y302553D01*
X2837864Y301512D01*
X2834764Y299429D01*
X2833369Y297970D01*
X2832439Y295887D01*
X2832129Y294012D01*
X2838639D01*
G01X2847784Y293595D02*
X2847474Y293804D01*
Y294220D01*
X2847784Y294429D01*
X2848094Y294220D01*
Y293804D01*
X2847784Y293595D01*
G01X2860184Y306512D02*
X2858944Y306095D01*
X2858014Y305054D01*
X2857394Y303804D01*
X2856929Y302137D01*
X2856774Y300262D01*
X2856929Y298387D01*
X2857394Y296720D01*
X2858014Y295470D01*
X2858944Y294429D01*
X2860184Y294012D01*
X2861424Y294429D01*
X2862354Y295470D01*
X2862974Y296720D01*
X2863439Y298387D01*
X2863594Y300262D01*
X2863439Y302137D01*
X2862974Y303804D01*
X2862354Y305054D01*
X2861424Y306095D01*
X2860184Y306512D01*
G01X2759279Y335979D02*
X2762999D01*
G01X2760984Y338687D02*
Y333270D01*
G01X2769974Y334312D02*
X2770904Y332853D01*
X2772144Y332020D01*
X2773539Y331812D01*
X2774779Y332020D01*
X2776019Y333062D01*
X2776794Y334312D01*
X2776949Y335562D01*
X2776639Y337020D01*
X2775554Y338062D01*
X2774469Y338479D01*
X2773074D01*
G01X2774469D02*
X2775399Y339104D01*
X2776174Y340145D01*
X2776484Y341395D01*
X2776174Y342645D01*
X2775399Y343687D01*
X2774004Y344312D01*
X2772609Y344104D01*
X2771214Y343270D01*
G01X2785784Y331395D02*
X2785474Y331604D01*
Y332020D01*
X2785784Y332229D01*
X2786094Y332020D01*
Y331604D01*
X2785784Y331395D01*
G01X2798184Y344312D02*
X2796944Y343895D01*
X2796014Y342854D01*
X2795394Y341604D01*
X2794929Y339937D01*
X2794774Y338062D01*
X2794929Y336187D01*
X2795394Y334520D01*
X2796014Y333270D01*
X2796944Y332229D01*
X2798184Y331812D01*
X2799424Y332229D01*
X2800354Y333270D01*
X2800974Y334520D01*
X2801439Y336187D01*
X2801594Y338062D01*
X2801439Y339937D01*
X2800974Y341604D01*
X2800354Y342854D01*
X2799424Y343895D01*
X2798184Y344312D01*
G01X2807794Y331395D02*
X2813374Y344312D01*
G01X2820969Y335979D02*
X2824999D01*
G01X2831974Y334312D02*
X2832904Y332853D01*
X2834144Y332020D01*
X2835539Y331812D01*
X2836779Y332020D01*
X2838019Y333062D01*
X2838794Y334312D01*
X2838949Y335562D01*
X2838639Y337020D01*
X2837554Y338062D01*
X2836469Y338479D01*
X2835074D01*
G01X2836469D02*
X2837399Y339104D01*
X2838174Y340145D01*
X2838484Y341395D01*
X2838174Y342645D01*
X2837399Y343687D01*
X2836004Y344312D01*
X2834609Y344104D01*
X2833214Y343270D01*
G01X2847784Y331395D02*
X2847474Y331604D01*
Y332020D01*
X2847784Y332229D01*
X2848094Y332020D01*
Y331604D01*
X2847784Y331395D01*
G01X2860184Y344312D02*
X2858944Y343895D01*
X2858014Y342854D01*
X2857394Y341604D01*
X2856929Y339937D01*
X2856774Y338062D01*
X2856929Y336187D01*
X2857394Y334520D01*
X2858014Y333270D01*
X2858944Y332229D01*
X2860184Y331812D01*
X2861424Y332229D01*
X2862354Y333270D01*
X2862974Y334520D01*
X2863439Y336187D01*
X2863594Y338062D01*
X2863439Y339937D01*
X2862974Y341604D01*
X2862354Y342854D01*
X2861424Y343895D01*
X2860184Y344312D01*
G01X2759279Y373779D02*
X2762999D01*
G01X2760984Y376487D02*
Y371070D01*
G01X2769974Y372112D02*
X2770904Y370653D01*
X2772144Y369820D01*
X2773539Y369612D01*
X2774779Y369820D01*
X2776019Y370862D01*
X2776794Y372112D01*
X2776949Y373362D01*
X2776639Y374820D01*
X2775554Y375862D01*
X2774469Y376279D01*
X2773074D01*
G01X2774469D02*
X2775399Y376904D01*
X2776174Y377945D01*
X2776484Y379195D01*
X2776174Y380445D01*
X2775399Y381487D01*
X2774004Y382112D01*
X2772609Y381904D01*
X2771214Y381070D01*
G01X2785784Y369195D02*
X2785474Y369404D01*
Y369820D01*
X2785784Y370029D01*
X2786094Y369820D01*
Y369404D01*
X2785784Y369195D01*
G01X2798184Y382112D02*
X2796944Y381695D01*
X2796014Y380654D01*
X2795394Y379404D01*
X2794929Y377737D01*
X2794774Y375862D01*
X2794929Y373987D01*
X2795394Y372320D01*
X2796014Y371070D01*
X2796944Y370029D01*
X2798184Y369612D01*
X2799424Y370029D01*
X2800354Y371070D01*
X2800974Y372320D01*
X2801439Y373987D01*
X2801594Y375862D01*
X2801439Y377737D01*
X2800974Y379404D01*
X2800354Y380654D01*
X2799424Y381695D01*
X2798184Y382112D01*
G01X2807794Y369195D02*
X2813374Y382112D01*
G01X2820969Y373779D02*
X2824999D01*
G01X2831974Y372112D02*
X2832904Y370653D01*
X2834144Y369820D01*
X2835539Y369612D01*
X2836779Y369820D01*
X2838019Y370862D01*
X2838794Y372112D01*
X2838949Y373362D01*
X2838639Y374820D01*
X2837554Y375862D01*
X2836469Y376279D01*
X2835074D01*
G01X2836469D02*
X2837399Y376904D01*
X2838174Y377945D01*
X2838484Y379195D01*
X2838174Y380445D01*
X2837399Y381487D01*
X2836004Y382112D01*
X2834609Y381904D01*
X2833214Y381070D01*
G01X2847784Y369195D02*
X2847474Y369404D01*
Y369820D01*
X2847784Y370029D01*
X2848094Y369820D01*
Y369404D01*
X2847784Y369195D01*
G01X2860184Y382112D02*
X2858944Y381695D01*
X2858014Y380654D01*
X2857394Y379404D01*
X2856929Y377737D01*
X2856774Y375862D01*
X2856929Y373987D01*
X2857394Y372320D01*
X2858014Y371070D01*
X2858944Y370029D01*
X2860184Y369612D01*
X2861424Y370029D01*
X2862354Y371070D01*
X2862974Y372320D01*
X2863439Y373987D01*
X2863594Y375862D01*
X2863439Y377737D01*
X2862974Y379404D01*
X2862354Y380654D01*
X2861424Y381695D01*
X2860184Y382112D01*
G01X2759279Y411579D02*
X2762999D01*
G01X2760984Y414287D02*
Y408870D01*
G01X2769974Y409912D02*
X2770904Y408453D01*
X2772144Y407620D01*
X2773539Y407412D01*
X2774779Y407620D01*
X2776019Y408662D01*
X2776794Y409912D01*
X2776949Y411162D01*
X2776639Y412620D01*
X2775554Y413662D01*
X2774469Y414079D01*
X2773074D01*
G01X2774469D02*
X2775399Y414704D01*
X2776174Y415745D01*
X2776484Y416995D01*
X2776174Y418245D01*
X2775399Y419287D01*
X2774004Y419912D01*
X2772609Y419704D01*
X2771214Y418870D01*
G01X2785784Y406995D02*
X2785474Y407204D01*
Y407620D01*
X2785784Y407829D01*
X2786094Y407620D01*
Y407204D01*
X2785784Y406995D01*
G01X2798184Y419912D02*
X2796944Y419495D01*
X2796014Y418454D01*
X2795394Y417204D01*
X2794929Y415537D01*
X2794774Y413662D01*
X2794929Y411787D01*
X2795394Y410120D01*
X2796014Y408870D01*
X2796944Y407829D01*
X2798184Y407412D01*
X2799424Y407829D01*
X2800354Y408870D01*
X2800974Y410120D01*
X2801439Y411787D01*
X2801594Y413662D01*
X2801439Y415537D01*
X2800974Y417204D01*
X2800354Y418454D01*
X2799424Y419495D01*
X2798184Y419912D01*
G01X2807794Y406995D02*
X2813374Y419912D01*
G01X2820969Y411579D02*
X2824999D01*
G01X2831974Y409912D02*
X2832904Y408453D01*
X2834144Y407620D01*
X2835539Y407412D01*
X2836779Y407620D01*
X2838019Y408662D01*
X2838794Y409912D01*
X2838949Y411162D01*
X2838639Y412620D01*
X2837554Y413662D01*
X2836469Y414079D01*
X2835074D01*
G01X2836469D02*
X2837399Y414704D01*
X2838174Y415745D01*
X2838484Y416995D01*
X2838174Y418245D01*
X2837399Y419287D01*
X2836004Y419912D01*
X2834609Y419704D01*
X2833214Y418870D01*
G01X2847784Y406995D02*
X2847474Y407204D01*
Y407620D01*
X2847784Y407829D01*
X2848094Y407620D01*
Y407204D01*
X2847784Y406995D01*
G01X2860184Y419912D02*
X2858944Y419495D01*
X2858014Y418454D01*
X2857394Y417204D01*
X2856929Y415537D01*
X2856774Y413662D01*
X2856929Y411787D01*
X2857394Y410120D01*
X2858014Y408870D01*
X2858944Y407829D01*
X2860184Y407412D01*
X2861424Y407829D01*
X2862354Y408870D01*
X2862974Y410120D01*
X2863439Y411787D01*
X2863594Y413662D01*
X2863439Y415537D01*
X2862974Y417204D01*
X2862354Y418454D01*
X2861424Y419495D01*
X2860184Y419912D01*
G01X2759279Y449379D02*
X2762999D01*
G01X2760984Y452087D02*
Y446670D01*
G01X2769974Y447712D02*
X2770904Y446253D01*
X2772144Y445420D01*
X2773539Y445212D01*
X2774779Y445420D01*
X2776019Y446462D01*
X2776794Y447712D01*
X2776949Y448962D01*
X2776639Y450420D01*
X2775554Y451462D01*
X2774469Y451879D01*
X2773074D01*
G01X2774469D02*
X2775399Y452504D01*
X2776174Y453545D01*
X2776484Y454795D01*
X2776174Y456045D01*
X2775399Y457087D01*
X2774004Y457712D01*
X2772609Y457504D01*
X2771214Y456670D01*
G01X2785784Y444795D02*
X2785474Y445004D01*
Y445420D01*
X2785784Y445629D01*
X2786094Y445420D01*
Y445004D01*
X2785784Y444795D01*
G01X2798184Y457712D02*
X2796944Y457295D01*
X2796014Y456254D01*
X2795394Y455004D01*
X2794929Y453337D01*
X2794774Y451462D01*
X2794929Y449587D01*
X2795394Y447920D01*
X2796014Y446670D01*
X2796944Y445629D01*
X2798184Y445212D01*
X2799424Y445629D01*
X2800354Y446670D01*
X2800974Y447920D01*
X2801439Y449587D01*
X2801594Y451462D01*
X2801439Y453337D01*
X2800974Y455004D01*
X2800354Y456254D01*
X2799424Y457295D01*
X2798184Y457712D01*
G01X2807794Y444795D02*
X2813374Y457712D01*
G01X2820969Y449379D02*
X2824999D01*
G01X2831974Y447712D02*
X2832904Y446253D01*
X2834144Y445420D01*
X2835539Y445212D01*
X2836779Y445420D01*
X2838019Y446462D01*
X2838794Y447712D01*
X2838949Y448962D01*
X2838639Y450420D01*
X2837554Y451462D01*
X2836469Y451879D01*
X2835074D01*
G01X2836469D02*
X2837399Y452504D01*
X2838174Y453545D01*
X2838484Y454795D01*
X2838174Y456045D01*
X2837399Y457087D01*
X2836004Y457712D01*
X2834609Y457504D01*
X2833214Y456670D01*
G01X2847784Y444795D02*
X2847474Y445004D01*
Y445420D01*
X2847784Y445629D01*
X2848094Y445420D01*
Y445004D01*
X2847784Y444795D01*
G01X2860184Y457712D02*
X2858944Y457295D01*
X2858014Y456254D01*
X2857394Y455004D01*
X2856929Y453337D01*
X2856774Y451462D01*
X2856929Y449587D01*
X2857394Y447920D01*
X2858014Y446670D01*
X2858944Y445629D01*
X2860184Y445212D01*
X2861424Y445629D01*
X2862354Y446670D01*
X2862974Y447920D01*
X2863439Y449587D01*
X2863594Y451462D01*
X2863439Y453337D01*
X2862974Y455004D01*
X2862354Y456254D01*
X2861424Y457295D01*
X2860184Y457712D01*
G01X2759279Y487179D02*
X2762999D01*
G01X2760984Y489887D02*
Y484470D01*
G01X2769974Y485512D02*
X2770904Y484053D01*
X2772144Y483220D01*
X2773539Y483012D01*
X2774779Y483220D01*
X2776019Y484262D01*
X2776794Y485512D01*
X2776949Y486762D01*
X2776639Y488220D01*
X2775554Y489262D01*
X2774469Y489679D01*
X2773074D01*
G01X2774469D02*
X2775399Y490304D01*
X2776174Y491345D01*
X2776484Y492595D01*
X2776174Y493845D01*
X2775399Y494887D01*
X2774004Y495512D01*
X2772609Y495304D01*
X2771214Y494470D01*
G01X2785784Y482595D02*
X2785474Y482804D01*
Y483220D01*
X2785784Y483429D01*
X2786094Y483220D01*
Y482804D01*
X2785784Y482595D01*
G01X2798184Y495512D02*
X2796944Y495095D01*
X2796014Y494054D01*
X2795394Y492804D01*
X2794929Y491137D01*
X2794774Y489262D01*
X2794929Y487387D01*
X2795394Y485720D01*
X2796014Y484470D01*
X2796944Y483429D01*
X2798184Y483012D01*
X2799424Y483429D01*
X2800354Y484470D01*
X2800974Y485720D01*
X2801439Y487387D01*
X2801594Y489262D01*
X2801439Y491137D01*
X2800974Y492804D01*
X2800354Y494054D01*
X2799424Y495095D01*
X2798184Y495512D01*
G01X2807794Y482595D02*
X2813374Y495512D01*
G01X2820969Y487179D02*
X2824999D01*
G01X2831974Y485512D02*
X2832904Y484053D01*
X2834144Y483220D01*
X2835539Y483012D01*
X2836779Y483220D01*
X2838019Y484262D01*
X2838794Y485512D01*
X2838949Y486762D01*
X2838639Y488220D01*
X2837554Y489262D01*
X2836469Y489679D01*
X2835074D01*
G01X2836469D02*
X2837399Y490304D01*
X2838174Y491345D01*
X2838484Y492595D01*
X2838174Y493845D01*
X2837399Y494887D01*
X2836004Y495512D01*
X2834609Y495304D01*
X2833214Y494470D01*
G01X2847784Y482595D02*
X2847474Y482804D01*
Y483220D01*
X2847784Y483429D01*
X2848094Y483220D01*
Y482804D01*
X2847784Y482595D01*
G01X2860184Y495512D02*
X2858944Y495095D01*
X2858014Y494054D01*
X2857394Y492804D01*
X2856929Y491137D01*
X2856774Y489262D01*
X2856929Y487387D01*
X2857394Y485720D01*
X2858014Y484470D01*
X2858944Y483429D01*
X2860184Y483012D01*
X2861424Y483429D01*
X2862354Y484470D01*
X2862974Y485720D01*
X2863439Y487387D01*
X2863594Y489262D01*
X2863439Y491137D01*
X2862974Y492804D01*
X2862354Y494054D01*
X2861424Y495095D01*
X2860184Y495512D01*
G01X2759279Y524979D02*
X2762999D01*
G01X2760984Y527687D02*
Y522270D01*
G01X2769974Y523312D02*
X2770904Y521853D01*
X2772144Y521020D01*
X2773539Y520812D01*
X2774779Y521020D01*
X2776019Y522062D01*
X2776794Y523312D01*
X2776949Y524562D01*
X2776639Y526020D01*
X2775554Y527062D01*
X2774469Y527479D01*
X2773074D01*
G01X2774469D02*
X2775399Y528104D01*
X2776174Y529145D01*
X2776484Y530395D01*
X2776174Y531645D01*
X2775399Y532687D01*
X2774004Y533312D01*
X2772609Y533104D01*
X2771214Y532270D01*
G01X2785784Y520395D02*
X2785474Y520604D01*
Y521020D01*
X2785784Y521229D01*
X2786094Y521020D01*
Y520604D01*
X2785784Y520395D01*
G01X2798184Y533312D02*
X2796944Y532895D01*
X2796014Y531854D01*
X2795394Y530604D01*
X2794929Y528937D01*
X2794774Y527062D01*
X2794929Y525187D01*
X2795394Y523520D01*
X2796014Y522270D01*
X2796944Y521229D01*
X2798184Y520812D01*
X2799424Y521229D01*
X2800354Y522270D01*
X2800974Y523520D01*
X2801439Y525187D01*
X2801594Y527062D01*
X2801439Y528937D01*
X2800974Y530604D01*
X2800354Y531854D01*
X2799424Y532895D01*
X2798184Y533312D01*
G01X2807794Y520395D02*
X2813374Y533312D01*
G01X2820969Y524979D02*
X2824999D01*
G01X2831974Y523312D02*
X2832904Y521853D01*
X2834144Y521020D01*
X2835539Y520812D01*
X2836779Y521020D01*
X2838019Y522062D01*
X2838794Y523312D01*
X2838949Y524562D01*
X2838639Y526020D01*
X2837554Y527062D01*
X2836469Y527479D01*
X2835074D01*
G01X2836469D02*
X2837399Y528104D01*
X2838174Y529145D01*
X2838484Y530395D01*
X2838174Y531645D01*
X2837399Y532687D01*
X2836004Y533312D01*
X2834609Y533104D01*
X2833214Y532270D01*
G01X2847784Y520395D02*
X2847474Y520604D01*
Y521020D01*
X2847784Y521229D01*
X2848094Y521020D01*
Y520604D01*
X2847784Y520395D01*
G01X2860184Y533312D02*
X2858944Y532895D01*
X2858014Y531854D01*
X2857394Y530604D01*
X2856929Y528937D01*
X2856774Y527062D01*
X2856929Y525187D01*
X2857394Y523520D01*
X2858014Y522270D01*
X2858944Y521229D01*
X2860184Y520812D01*
X2861424Y521229D01*
X2862354Y522270D01*
X2862974Y523520D01*
X2863439Y525187D01*
X2863594Y527062D01*
X2863439Y528937D01*
X2862974Y530604D01*
X2862354Y531854D01*
X2861424Y532895D01*
X2860184Y533312D01*
G01X2759279Y562779D02*
X2762999D01*
G01X2760984Y565487D02*
Y560070D01*
G01X2770439Y569029D02*
X2771369Y570278D01*
X2772454Y570904D01*
X2773694Y571112D01*
X2775244Y570695D01*
X2776329Y569654D01*
X2776639Y568404D01*
X2776484Y567153D01*
X2775864Y566112D01*
X2772764Y564029D01*
X2771369Y562570D01*
X2770439Y560487D01*
X2770129Y558612D01*
X2776639D01*
G01X2785784Y558195D02*
X2785474Y558404D01*
Y558820D01*
X2785784Y559029D01*
X2786094Y558820D01*
Y558404D01*
X2785784Y558195D01*
G01X2798184Y571112D02*
X2796944Y570695D01*
X2796014Y569654D01*
X2795394Y568404D01*
X2794929Y566737D01*
X2794774Y564862D01*
X2794929Y562987D01*
X2795394Y561320D01*
X2796014Y560070D01*
X2796944Y559029D01*
X2798184Y558612D01*
X2799424Y559029D01*
X2800354Y560070D01*
X2800974Y561320D01*
X2801439Y562987D01*
X2801594Y564862D01*
X2801439Y566737D01*
X2800974Y568404D01*
X2800354Y569654D01*
X2799424Y570695D01*
X2798184Y571112D01*
G01X2807794Y558195D02*
X2813374Y571112D01*
G01X2820969Y562779D02*
X2824999D01*
G01X2832439Y569029D02*
X2833369Y570278D01*
X2834454Y570904D01*
X2835694Y571112D01*
X2837244Y570695D01*
X2838329Y569654D01*
X2838639Y568404D01*
X2838484Y567153D01*
X2837864Y566112D01*
X2834764Y564029D01*
X2833369Y562570D01*
X2832439Y560487D01*
X2832129Y558612D01*
X2838639D01*
G01X2847784Y558195D02*
X2847474Y558404D01*
Y558820D01*
X2847784Y559029D01*
X2848094Y558820D01*
Y558404D01*
X2847784Y558195D01*
G01X2860184Y571112D02*
X2858944Y570695D01*
X2858014Y569654D01*
X2857394Y568404D01*
X2856929Y566737D01*
X2856774Y564862D01*
X2856929Y562987D01*
X2857394Y561320D01*
X2858014Y560070D01*
X2858944Y559029D01*
X2860184Y558612D01*
X2861424Y559029D01*
X2862354Y560070D01*
X2862974Y561320D01*
X2863439Y562987D01*
X2863594Y564862D01*
X2863439Y566737D01*
X2862974Y568404D01*
X2862354Y569654D01*
X2861424Y570695D01*
X2860184Y571112D01*
G01X2746879Y600579D02*
X2750599D01*
G01X2748584Y603287D02*
Y597870D01*
G01X2760984Y596412D02*
Y608912D01*
X2759124Y606412D01*
G01Y596412D02*
X2762844D01*
G01X2773384Y595995D02*
X2773074Y596204D01*
Y596620D01*
X2773384Y596829D01*
X2773694Y596620D01*
Y596204D01*
X2773384Y595995D01*
G01X2783149Y597870D02*
X2784234Y596829D01*
X2785474Y596412D01*
X2786714Y596829D01*
X2787799Y598078D01*
X2788574Y599954D01*
X2788884Y601829D01*
Y604120D01*
X2788574Y605995D01*
X2787799Y607662D01*
X2786869Y608495D01*
X2785784Y608912D01*
X2784544Y608495D01*
X2783614Y607662D01*
X2782994Y606412D01*
X2782684Y604745D01*
X2782994Y603287D01*
X2783769Y601829D01*
X2784699Y600995D01*
X2785784Y600787D01*
X2787024Y601203D01*
X2787954Y602245D01*
X2788884Y604120D01*
G01X2795239Y601620D02*
X2796324Y603079D01*
X2797254Y603912D01*
X2798494Y604329D01*
X2799579Y603912D01*
X2800354Y603079D01*
X2800974Y601829D01*
X2801129Y600370D01*
X2800974Y599120D01*
X2800354Y597870D01*
X2799424Y596829D01*
X2798339Y596412D01*
X2797099Y596829D01*
X2796014Y598078D01*
X2795394Y599954D01*
X2795239Y602037D01*
X2795549Y604745D01*
X2796014Y606204D01*
X2796789Y607662D01*
X2797874Y608704D01*
X2798959Y608912D01*
X2800044Y608495D01*
X2800819Y607454D01*
G01X2807794Y595995D02*
X2813374Y608912D01*
G01X2820969Y600579D02*
X2824999D01*
G01X2835384Y596412D02*
Y608912D01*
X2833524Y606412D01*
G01Y596412D02*
X2837244D01*
G01X2847784Y595995D02*
X2847474Y596204D01*
Y596620D01*
X2847784Y596829D01*
X2848094Y596620D01*
Y596204D01*
X2847784Y595995D01*
G01X2857549Y597870D02*
X2858634Y596829D01*
X2859874Y596412D01*
X2861114Y596829D01*
X2862199Y598078D01*
X2862974Y599954D01*
X2863284Y601829D01*
Y604120D01*
X2862974Y605995D01*
X2862199Y607662D01*
X2861269Y608495D01*
X2860184Y608912D01*
X2858944Y608495D01*
X2858014Y607662D01*
X2857394Y606412D01*
X2857084Y604745D01*
X2857394Y603287D01*
X2858169Y601829D01*
X2859099Y600995D01*
X2860184Y600787D01*
X2861424Y601203D01*
X2862354Y602245D01*
X2863284Y604120D01*
G01X2869639Y601620D02*
X2870724Y603079D01*
X2871654Y603912D01*
X2872894Y604329D01*
X2873979Y603912D01*
X2874754Y603079D01*
X2875374Y601829D01*
X2875529Y600370D01*
X2875374Y599120D01*
X2874754Y597870D01*
X2873824Y596829D01*
X2872739Y596412D01*
X2871499Y596829D01*
X2870414Y598078D01*
X2869794Y599954D01*
X2869639Y602037D01*
X2869949Y604745D01*
X2870414Y606204D01*
X2871189Y607662D01*
X2872274Y608704D01*
X2873359Y608912D01*
X2874444Y608495D01*
X2875219Y607454D01*
G01X2759279Y638379D02*
X2762999D01*
G01X2760984Y641087D02*
Y635670D01*
G01X2769974Y636712D02*
X2770904Y635253D01*
X2772144Y634420D01*
X2773539Y634212D01*
X2774779Y634420D01*
X2776019Y635462D01*
X2776794Y636712D01*
X2776949Y637962D01*
X2776639Y639420D01*
X2775554Y640462D01*
X2774469Y640879D01*
X2773074D01*
G01X2774469D02*
X2775399Y641504D01*
X2776174Y642545D01*
X2776484Y643795D01*
X2776174Y645045D01*
X2775399Y646087D01*
X2774004Y646712D01*
X2772609Y646504D01*
X2771214Y645670D01*
G01X2785784Y633795D02*
X2785474Y634004D01*
Y634420D01*
X2785784Y634629D01*
X2786094Y634420D01*
Y634004D01*
X2785784Y633795D01*
G01X2798184Y646712D02*
X2796944Y646295D01*
X2796014Y645254D01*
X2795394Y644004D01*
X2794929Y642337D01*
X2794774Y640462D01*
X2794929Y638587D01*
X2795394Y636920D01*
X2796014Y635670D01*
X2796944Y634629D01*
X2798184Y634212D01*
X2799424Y634629D01*
X2800354Y635670D01*
X2800974Y636920D01*
X2801439Y638587D01*
X2801594Y640462D01*
X2801439Y642337D01*
X2800974Y644004D01*
X2800354Y645254D01*
X2799424Y646295D01*
X2798184Y646712D01*
G01X2807794Y633795D02*
X2813374Y646712D01*
G01X2820969Y638379D02*
X2824999D01*
G01X2831974Y636712D02*
X2832904Y635253D01*
X2834144Y634420D01*
X2835539Y634212D01*
X2836779Y634420D01*
X2838019Y635462D01*
X2838794Y636712D01*
X2838949Y637962D01*
X2838639Y639420D01*
X2837554Y640462D01*
X2836469Y640879D01*
X2835074D01*
G01X2836469D02*
X2837399Y641504D01*
X2838174Y642545D01*
X2838484Y643795D01*
X2838174Y645045D01*
X2837399Y646087D01*
X2836004Y646712D01*
X2834609Y646504D01*
X2833214Y645670D01*
G01X2847784Y633795D02*
X2847474Y634004D01*
Y634420D01*
X2847784Y634629D01*
X2848094Y634420D01*
Y634004D01*
X2847784Y633795D01*
G01X2860184Y646712D02*
X2858944Y646295D01*
X2858014Y645254D01*
X2857394Y644004D01*
X2856929Y642337D01*
X2856774Y640462D01*
X2856929Y638587D01*
X2857394Y636920D01*
X2858014Y635670D01*
X2858944Y634629D01*
X2860184Y634212D01*
X2861424Y634629D01*
X2862354Y635670D01*
X2862974Y636920D01*
X2863439Y638587D01*
X2863594Y640462D01*
X2863439Y642337D01*
X2862974Y644004D01*
X2862354Y645254D01*
X2861424Y646295D01*
X2860184Y646712D01*
G01X2753079Y676179D02*
X2756799D01*
G01X2754784Y678887D02*
Y673470D01*
G01X2767184Y684512D02*
X2765944Y684095D01*
X2765014Y683054D01*
X2764394Y681804D01*
X2763929Y680137D01*
X2763774Y678262D01*
X2763929Y676387D01*
X2764394Y674720D01*
X2765014Y673470D01*
X2765944Y672429D01*
X2767184Y672012D01*
X2768424Y672429D01*
X2769354Y673470D01*
X2769974Y674720D01*
X2770439Y676387D01*
X2770594Y678262D01*
X2770439Y680137D01*
X2769974Y681804D01*
X2769354Y683054D01*
X2768424Y684095D01*
X2767184Y684512D01*
G01X2779584Y671595D02*
X2779274Y671804D01*
Y672220D01*
X2779584Y672429D01*
X2779894Y672220D01*
Y671804D01*
X2779584Y671595D01*
G01X2791984Y684512D02*
X2790744Y684095D01*
X2789814Y683054D01*
X2789194Y681804D01*
X2788729Y680137D01*
X2788574Y678262D01*
X2788729Y676387D01*
X2789194Y674720D01*
X2789814Y673470D01*
X2790744Y672429D01*
X2791984Y672012D01*
X2793224Y672429D01*
X2794154Y673470D01*
X2794774Y674720D01*
X2795239Y676387D01*
X2795394Y678262D01*
X2795239Y680137D01*
X2794774Y681804D01*
X2794154Y683054D01*
X2793224Y684095D01*
X2791984Y684512D01*
G01X2801594Y671595D02*
X2807174Y684512D01*
G01X2814769Y676179D02*
X2818799D01*
G01X2829184Y672012D02*
Y684512D01*
X2827324Y682012D01*
G01Y672012D02*
X2831044D01*
G01X2841584Y684512D02*
X2840344Y684095D01*
X2839414Y683054D01*
X2838794Y681804D01*
X2838329Y680137D01*
X2838174Y678262D01*
X2838329Y676387D01*
X2838794Y674720D01*
X2839414Y673470D01*
X2840344Y672429D01*
X2841584Y672012D01*
X2842824Y672429D01*
X2843754Y673470D01*
X2844374Y674720D01*
X2844839Y676387D01*
X2844994Y678262D01*
X2844839Y680137D01*
X2844374Y681804D01*
X2843754Y683054D01*
X2842824Y684095D01*
X2841584Y684512D01*
G01X2853984Y671595D02*
X2853674Y671804D01*
Y672220D01*
X2853984Y672429D01*
X2854294Y672220D01*
Y671804D01*
X2853984Y671595D01*
G01X2866384Y684512D02*
X2865144Y684095D01*
X2864214Y683054D01*
X2863594Y681804D01*
X2863129Y680137D01*
X2862974Y678262D01*
X2863129Y676387D01*
X2863594Y674720D01*
X2864214Y673470D01*
X2865144Y672429D01*
X2866384Y672012D01*
X2867624Y672429D01*
X2868554Y673470D01*
X2869174Y674720D01*
X2869639Y676387D01*
X2869794Y678262D01*
X2869639Y680137D01*
X2869174Y681804D01*
X2868554Y683054D01*
X2867624Y684095D01*
X2866384Y684512D01*
G01X2753079Y713979D02*
X2756799D01*
G01X2754784Y716687D02*
Y711270D01*
G01X2767184Y722312D02*
X2765944Y721895D01*
X2765014Y720854D01*
X2764394Y719604D01*
X2763929Y717937D01*
X2763774Y716062D01*
X2763929Y714187D01*
X2764394Y712520D01*
X2765014Y711270D01*
X2765944Y710229D01*
X2767184Y709812D01*
X2768424Y710229D01*
X2769354Y711270D01*
X2769974Y712520D01*
X2770439Y714187D01*
X2770594Y716062D01*
X2770439Y717937D01*
X2769974Y719604D01*
X2769354Y720854D01*
X2768424Y721895D01*
X2767184Y722312D01*
G01X2779584Y709395D02*
X2779274Y709604D01*
Y710020D01*
X2779584Y710229D01*
X2779894Y710020D01*
Y709604D01*
X2779584Y709395D01*
G01X2791984Y722312D02*
X2790744Y721895D01*
X2789814Y720854D01*
X2789194Y719604D01*
X2788729Y717937D01*
X2788574Y716062D01*
X2788729Y714187D01*
X2789194Y712520D01*
X2789814Y711270D01*
X2790744Y710229D01*
X2791984Y709812D01*
X2793224Y710229D01*
X2794154Y711270D01*
X2794774Y712520D01*
X2795239Y714187D01*
X2795394Y716062D01*
X2795239Y717937D01*
X2794774Y719604D01*
X2794154Y720854D01*
X2793224Y721895D01*
X2791984Y722312D01*
G01X2801594Y709395D02*
X2807174Y722312D01*
G01X2814769Y713979D02*
X2818799D01*
G01X2829184Y709812D02*
Y722312D01*
X2827324Y719812D01*
G01Y709812D02*
X2831044D01*
G01X2841584Y722312D02*
X2840344Y721895D01*
X2839414Y720854D01*
X2838794Y719604D01*
X2838329Y717937D01*
X2838174Y716062D01*
X2838329Y714187D01*
X2838794Y712520D01*
X2839414Y711270D01*
X2840344Y710229D01*
X2841584Y709812D01*
X2842824Y710229D01*
X2843754Y711270D01*
X2844374Y712520D01*
X2844839Y714187D01*
X2844994Y716062D01*
X2844839Y717937D01*
X2844374Y719604D01*
X2843754Y720854D01*
X2842824Y721895D01*
X2841584Y722312D01*
G01X2853984Y709395D02*
X2853674Y709604D01*
Y710020D01*
X2853984Y710229D01*
X2854294Y710020D01*
Y709604D01*
X2853984Y709395D01*
G01X2866384Y722312D02*
X2865144Y721895D01*
X2864214Y720854D01*
X2863594Y719604D01*
X2863129Y717937D01*
X2862974Y716062D01*
X2863129Y714187D01*
X2863594Y712520D01*
X2864214Y711270D01*
X2865144Y710229D01*
X2866384Y709812D01*
X2867624Y710229D01*
X2868554Y711270D01*
X2869174Y712520D01*
X2869639Y714187D01*
X2869794Y716062D01*
X2869639Y717937D01*
X2869174Y719604D01*
X2868554Y720854D01*
X2867624Y721895D01*
X2866384Y722312D01*
G01X2740059Y766212D02*
X2743934Y778712D01*
X2747809Y766212D01*
G01X2746414Y770587D02*
X2741454D01*
G01X2753234Y778712D02*
Y766212D01*
X2759434D01*
G01X2765634Y778712D02*
Y766212D01*
X2771834D01*
G01X2790124Y778712D02*
Y769754D01*
X2790744Y767878D01*
X2791984Y766629D01*
X2793534Y766212D01*
X2795084Y766629D01*
X2796324Y767878D01*
X2796944Y769754D01*
Y778712D01*
G01X2802369Y766212D02*
Y778712D01*
X2809499Y766212D01*
Y778712D01*
G01X2816474D02*
X2820194D01*
G01X2818334D02*
Y766212D01*
G01X2816474D02*
X2820194D01*
G01X2830734Y778712D02*
Y766212D01*
G01X2827169Y778712D02*
X2834299D01*
G01X2839879Y767878D02*
X2841119Y766837D01*
X2842514Y766212D01*
X2843754D01*
X2844994Y766837D01*
X2845924Y767878D01*
X2846389Y769337D01*
X2846079Y770795D01*
X2845304Y772045D01*
X2843909Y772879D01*
X2842049Y773295D01*
X2840964Y774129D01*
X2840499Y775587D01*
X2840809Y777045D01*
X2841584Y778087D01*
X2842669Y778712D01*
X2843754D01*
X2844839Y778295D01*
X2845769Y777254D01*
G01X2864059Y766212D02*
X2867934Y778712D01*
X2871809Y766212D01*
G01X2870414Y770587D02*
X2865454D01*
G01X2877234Y766212D02*
Y778712D01*
X2881109D01*
X2882349Y778087D01*
X2883124Y777254D01*
X2883434Y775587D01*
X2883124Y773920D01*
X2882194Y772879D01*
X2881109Y772254D01*
X2877234D01*
G01X2881109D02*
X2883434Y766212D01*
G01X2895834D02*
X2889634D01*
Y778712D01*
X2895834D01*
G01X2893354Y772670D02*
X2889634D01*
G01X2915674Y778712D02*
X2919394D01*
G01X2917534D02*
Y766212D01*
G01X2915674D02*
X2919394D01*
G01X2926369D02*
Y778712D01*
X2933499Y766212D01*
Y778712D01*
G01X2950704Y766212D02*
Y778712D01*
X2954734Y768295D01*
X2958764Y778712D01*
Y766212D01*
G01X2965274Y778712D02*
X2968994D01*
G01X2967134D02*
Y766212D01*
G01X2965274D02*
X2968994D01*
G01X2976434Y778712D02*
Y766212D01*
X2982634D01*
G01X2988679Y767878D02*
X2989919Y766837D01*
X2991314Y766212D01*
X2992554D01*
X2993794Y766837D01*
X2994724Y767878D01*
X2995189Y769337D01*
X2994879Y770795D01*
X2994104Y772045D01*
X2992709Y772879D01*
X2990849Y773295D01*
X2989764Y774129D01*
X2989299Y775587D01*
X2989609Y777045D01*
X2990384Y778087D01*
X2991469Y778712D01*
X2992554D01*
X2993639Y778295D01*
X2994569Y777254D01*
G01X2919084Y753712D02*
Y741212D01*
G01X2915519Y753712D02*
X2922649D01*
G01X2931484Y741212D02*
X2930244Y741420D01*
X2929159Y742253D01*
X2928229Y743504D01*
X2927609Y744962D01*
X2927299Y746629D01*
Y748295D01*
X2927609Y749962D01*
X2928229Y751420D01*
X2929159Y752670D01*
X2930244Y753504D01*
X2931484Y753712D01*
X2932724Y753504D01*
X2933809Y752670D01*
X2934739Y751420D01*
X2935359Y749962D01*
X2935669Y748295D01*
Y746629D01*
X2935359Y744962D01*
X2934739Y743504D01*
X2933809Y742253D01*
X2932724Y741420D01*
X2931484Y741212D01*
G01X2940784Y753712D02*
Y741212D01*
X2946984D01*
G01X2959384D02*
X2953184D01*
Y753712D01*
X2959384D01*
G01X2956904Y747670D02*
X2953184D01*
G01X2965584Y741212D02*
Y753712D01*
X2969459D01*
X2970699Y753087D01*
X2971474Y752254D01*
X2971784Y750587D01*
X2971474Y748920D01*
X2970544Y747879D01*
X2969459Y747254D01*
X2965584D01*
G01X2969459D02*
X2971784Y741212D01*
G01X2977209D02*
X2981084Y753712D01*
X2984959Y741212D01*
G01X2983564Y745587D02*
X2978604D01*
G01X2989919Y741212D02*
Y753712D01*
X2997049Y741212D01*
Y753712D01*
G01X3009294Y752670D02*
X3008364Y753295D01*
X3007279Y753712D01*
X3006039D01*
X3004644Y753087D01*
X3003559Y752045D01*
X3002784Y750795D01*
X3002164Y748712D01*
X3002009Y746837D01*
X3002319Y744962D01*
X3002784Y743712D01*
X3003714Y742462D01*
X3004799Y741629D01*
X3005884Y741212D01*
X3006969D01*
X3008054Y741629D01*
X3008984Y742253D01*
X3009759Y743087D01*
G01X3021384Y741212D02*
X3015184D01*
Y753712D01*
X3021384D01*
G01X3018904Y747670D02*
X3015184D01*
G01X3026034Y737045D02*
X3035334D01*
G01X3043084Y753712D02*
Y741212D01*
G01X3039519Y753712D02*
X3046649D01*
G01X3052384Y741212D02*
Y753712D01*
X3056259D01*
X3057499Y753087D01*
X3058274Y752254D01*
X3058584Y750587D01*
X3058274Y748920D01*
X3057344Y747879D01*
X3056259Y747254D01*
X3052384D01*
G01X3056259D02*
X3058584Y741212D01*
G01X3064009D02*
X3067884Y753712D01*
X3071759Y741212D01*
G01X3070364Y745587D02*
X3065404D01*
G01X3076409Y753712D02*
X3080284Y741212D01*
X3084159Y753712D01*
G01X3095784Y741212D02*
X3089584D01*
Y753712D01*
X3095784D01*
G01X3093304Y747670D02*
X3089584D01*
G01X3101984Y753712D02*
Y741212D01*
X3108184D01*
G01X2960779Y-42021D02*
X2964499D01*
G01X2962484Y-39313D02*
Y-44730D01*
G01X2971939Y-35771D02*
X2972869Y-34522D01*
X2973954Y-33896D01*
X2975194Y-33688D01*
X2976744Y-34105D01*
X2977829Y-35146D01*
X2978139Y-36396D01*
X2977984Y-37647D01*
X2977364Y-38688D01*
X2974264Y-40771D01*
X2972869Y-42230D01*
X2971939Y-44313D01*
X2971629Y-46188D01*
X2978139D01*
G01X2987284Y-46605D02*
X2986974Y-46396D01*
Y-45980D01*
X2987284Y-45771D01*
X2987594Y-45980D01*
Y-46396D01*
X2987284Y-46605D01*
G01X2999684Y-33688D02*
X2998444Y-34105D01*
X2997514Y-35146D01*
X2996894Y-36396D01*
X2996429Y-38063D01*
X2996274Y-39938D01*
X2996429Y-41813D01*
X2996894Y-43480D01*
X2997514Y-44730D01*
X2998444Y-45771D01*
X2999684Y-46188D01*
X3000924Y-45771D01*
X3001854Y-44730D01*
X3002474Y-43480D01*
X3002939Y-41813D01*
X3003094Y-39938D01*
X3002939Y-38063D01*
X3002474Y-36396D01*
X3001854Y-35146D01*
X3000924Y-34105D01*
X2999684Y-33688D01*
G01X3009294Y-46605D02*
X3014874Y-33688D01*
G01X3022469Y-42021D02*
X3026499D01*
G01X3033939Y-35771D02*
X3034869Y-34522D01*
X3035954Y-33896D01*
X3037194Y-33688D01*
X3038744Y-34105D01*
X3039829Y-35146D01*
X3040139Y-36396D01*
X3039984Y-37647D01*
X3039364Y-38688D01*
X3036264Y-40771D01*
X3034869Y-42230D01*
X3033939Y-44313D01*
X3033629Y-46188D01*
X3040139D01*
G01X3049284Y-46605D02*
X3048974Y-46396D01*
Y-45980D01*
X3049284Y-45771D01*
X3049594Y-45980D01*
Y-46396D01*
X3049284Y-46605D01*
G01X3061684Y-33688D02*
X3060444Y-34105D01*
X3059514Y-35146D01*
X3058894Y-36396D01*
X3058429Y-38063D01*
X3058274Y-39938D01*
X3058429Y-41813D01*
X3058894Y-43480D01*
X3059514Y-44730D01*
X3060444Y-45771D01*
X3061684Y-46188D01*
X3062924Y-45771D01*
X3063854Y-44730D01*
X3064474Y-43480D01*
X3064939Y-41813D01*
X3065094Y-39938D01*
X3064939Y-38063D01*
X3064474Y-36396D01*
X3063854Y-35146D01*
X3062924Y-34105D01*
X3061684Y-33688D01*
G01X3010069Y-4221D02*
X3014099D01*
G01X3010069Y33579D02*
X3014099D01*
G01X3010069Y71379D02*
X3014099D01*
G01X3010069Y109179D02*
X3014099D01*
G01X3010069Y146979D02*
X3014099D01*
G01X3010069Y184779D02*
X3014099D01*
G01X3010069Y222579D02*
X3014099D01*
G01X3010069Y260379D02*
X3014099D01*
G01X3010069Y298179D02*
X3014099D01*
G01X3010069Y335979D02*
X3014099D01*
G01X3010069Y373779D02*
X3014099D01*
G01X3010069Y411579D02*
X3014099D01*
G01X3010069Y449379D02*
X3014099D01*
G01X3010069Y487179D02*
X3014099D01*
G01X3010069Y524979D02*
X3014099D01*
G01X3010069Y562779D02*
X3014099D01*
G01X3010069Y600579D02*
X3014099D01*
G01X3010069Y638379D02*
X3014099D01*
G01X3010069Y676179D02*
X3014099D01*
G01X3010069Y713979D02*
X3014099D01*
G01X3117019Y-8388D02*
Y4112D01*
X3124149Y-8388D01*
Y4112D01*
G01X3132984Y-8388D02*
X3131744Y-8180D01*
X3130659Y-7347D01*
X3129729Y-6096D01*
X3129109Y-4638D01*
X3128799Y-2971D01*
Y-1305D01*
X3129109Y362D01*
X3129729Y1820D01*
X3130659Y3070D01*
X3131744Y3904D01*
X3132984Y4112D01*
X3134224Y3904D01*
X3135309Y3070D01*
X3136239Y1820D01*
X3136859Y362D01*
X3137169Y-1305D01*
Y-2971D01*
X3136859Y-4638D01*
X3136239Y-6096D01*
X3135309Y-7347D01*
X3134224Y-8180D01*
X3132984Y-8388D01*
G01X3141819D02*
Y4112D01*
X3148949Y-8388D01*
Y4112D01*
G01X3155769Y-4221D02*
X3159799D01*
G01X3167084Y-8388D02*
Y4112D01*
X3170804D01*
X3172044Y3487D01*
X3172974Y2029D01*
X3173284Y362D01*
X3172974Y-1305D01*
X3172199Y-2555D01*
X3170804Y-3180D01*
X3167084D01*
G01X3179484Y4112D02*
Y-8388D01*
X3185684D01*
G01X3191109D02*
X3194984Y4112D01*
X3198859Y-8388D01*
G01X3197464Y-4013D02*
X3192504D01*
G01X3207384Y4112D02*
Y-8388D01*
G01X3203819Y4112D02*
X3210949D01*
G01X3222884Y-8388D02*
X3216684D01*
Y4112D01*
X3222884D01*
G01X3220404Y-1930D02*
X3216684D01*
G01X3228774Y-8388D02*
Y4112D01*
X3231874D01*
X3233114Y3487D01*
X3234044Y2654D01*
X3234819Y1404D01*
X3235439Y-55D01*
X3235594Y-2138D01*
X3235439Y-4221D01*
X3234819Y-5680D01*
X3234044Y-6930D01*
X3233114Y-7763D01*
X3231874Y-8388D01*
X3228774D01*
G01X3117019Y29412D02*
Y41912D01*
X3124149Y29412D01*
Y41912D01*
G01X3132984Y29412D02*
X3131744Y29620D01*
X3130659Y30453D01*
X3129729Y31704D01*
X3129109Y33162D01*
X3128799Y34829D01*
Y36495D01*
X3129109Y38162D01*
X3129729Y39620D01*
X3130659Y40870D01*
X3131744Y41704D01*
X3132984Y41912D01*
X3134224Y41704D01*
X3135309Y40870D01*
X3136239Y39620D01*
X3136859Y38162D01*
X3137169Y36495D01*
Y34829D01*
X3136859Y33162D01*
X3136239Y31704D01*
X3135309Y30453D01*
X3134224Y29620D01*
X3132984Y29412D01*
G01X3141819D02*
Y41912D01*
X3148949Y29412D01*
Y41912D01*
G01X3155769Y33579D02*
X3159799D01*
G01X3167084Y29412D02*
Y41912D01*
X3170804D01*
X3172044Y41287D01*
X3172974Y39829D01*
X3173284Y38162D01*
X3172974Y36495D01*
X3172199Y35245D01*
X3170804Y34620D01*
X3167084D01*
G01X3179484Y41912D02*
Y29412D01*
X3185684D01*
G01X3191109D02*
X3194984Y41912D01*
X3198859Y29412D01*
G01X3197464Y33787D02*
X3192504D01*
G01X3207384Y41912D02*
Y29412D01*
G01X3203819Y41912D02*
X3210949D01*
G01X3222884Y29412D02*
X3216684D01*
Y41912D01*
X3222884D01*
G01X3220404Y35870D02*
X3216684D01*
G01X3228774Y29412D02*
Y41912D01*
X3231874D01*
X3233114Y41287D01*
X3234044Y40454D01*
X3234819Y39204D01*
X3235439Y37745D01*
X3235594Y35662D01*
X3235439Y33579D01*
X3234819Y32120D01*
X3234044Y30870D01*
X3233114Y30037D01*
X3231874Y29412D01*
X3228774D01*
G01X3117019Y67212D02*
Y79712D01*
X3124149Y67212D01*
Y79712D01*
G01X3132984Y67212D02*
X3131744Y67420D01*
X3130659Y68253D01*
X3129729Y69504D01*
X3129109Y70962D01*
X3128799Y72629D01*
Y74295D01*
X3129109Y75962D01*
X3129729Y77420D01*
X3130659Y78670D01*
X3131744Y79504D01*
X3132984Y79712D01*
X3134224Y79504D01*
X3135309Y78670D01*
X3136239Y77420D01*
X3136859Y75962D01*
X3137169Y74295D01*
Y72629D01*
X3136859Y70962D01*
X3136239Y69504D01*
X3135309Y68253D01*
X3134224Y67420D01*
X3132984Y67212D01*
G01X3141819D02*
Y79712D01*
X3148949Y67212D01*
Y79712D01*
G01X3155769Y71379D02*
X3159799D01*
G01X3167084Y67212D02*
Y79712D01*
X3170804D01*
X3172044Y79087D01*
X3172974Y77629D01*
X3173284Y75962D01*
X3172974Y74295D01*
X3172199Y73045D01*
X3170804Y72420D01*
X3167084D01*
G01X3179484Y79712D02*
Y67212D01*
X3185684D01*
G01X3191109D02*
X3194984Y79712D01*
X3198859Y67212D01*
G01X3197464Y71587D02*
X3192504D01*
G01X3207384Y79712D02*
Y67212D01*
G01X3203819Y79712D02*
X3210949D01*
G01X3222884Y67212D02*
X3216684D01*
Y79712D01*
X3222884D01*
G01X3220404Y73670D02*
X3216684D01*
G01X3228774Y67212D02*
Y79712D01*
X3231874D01*
X3233114Y79087D01*
X3234044Y78254D01*
X3234819Y77004D01*
X3235439Y75545D01*
X3235594Y73462D01*
X3235439Y71379D01*
X3234819Y69920D01*
X3234044Y68670D01*
X3233114Y67837D01*
X3231874Y67212D01*
X3228774D01*
G01X3117019Y105012D02*
Y117512D01*
X3124149Y105012D01*
Y117512D01*
G01X3132984Y105012D02*
X3131744Y105220D01*
X3130659Y106053D01*
X3129729Y107304D01*
X3129109Y108762D01*
X3128799Y110429D01*
Y112095D01*
X3129109Y113762D01*
X3129729Y115220D01*
X3130659Y116470D01*
X3131744Y117304D01*
X3132984Y117512D01*
X3134224Y117304D01*
X3135309Y116470D01*
X3136239Y115220D01*
X3136859Y113762D01*
X3137169Y112095D01*
Y110429D01*
X3136859Y108762D01*
X3136239Y107304D01*
X3135309Y106053D01*
X3134224Y105220D01*
X3132984Y105012D01*
G01X3141819D02*
Y117512D01*
X3148949Y105012D01*
Y117512D01*
G01X3155769Y109179D02*
X3159799D01*
G01X3167084Y105012D02*
Y117512D01*
X3170804D01*
X3172044Y116887D01*
X3172974Y115429D01*
X3173284Y113762D01*
X3172974Y112095D01*
X3172199Y110845D01*
X3170804Y110220D01*
X3167084D01*
G01X3179484Y117512D02*
Y105012D01*
X3185684D01*
G01X3191109D02*
X3194984Y117512D01*
X3198859Y105012D01*
G01X3197464Y109387D02*
X3192504D01*
G01X3207384Y117512D02*
Y105012D01*
G01X3203819Y117512D02*
X3210949D01*
G01X3222884Y105012D02*
X3216684D01*
Y117512D01*
X3222884D01*
G01X3220404Y111470D02*
X3216684D01*
G01X3228774Y105012D02*
Y117512D01*
X3231874D01*
X3233114Y116887D01*
X3234044Y116054D01*
X3234819Y114804D01*
X3235439Y113345D01*
X3235594Y111262D01*
X3235439Y109179D01*
X3234819Y107720D01*
X3234044Y106470D01*
X3233114Y105637D01*
X3231874Y105012D01*
X3228774D01*
G01X3117019Y142812D02*
Y155312D01*
X3124149Y142812D01*
Y155312D01*
G01X3132984Y142812D02*
X3131744Y143020D01*
X3130659Y143853D01*
X3129729Y145104D01*
X3129109Y146562D01*
X3128799Y148229D01*
Y149895D01*
X3129109Y151562D01*
X3129729Y153020D01*
X3130659Y154270D01*
X3131744Y155104D01*
X3132984Y155312D01*
X3134224Y155104D01*
X3135309Y154270D01*
X3136239Y153020D01*
X3136859Y151562D01*
X3137169Y149895D01*
Y148229D01*
X3136859Y146562D01*
X3136239Y145104D01*
X3135309Y143853D01*
X3134224Y143020D01*
X3132984Y142812D01*
G01X3141819D02*
Y155312D01*
X3148949Y142812D01*
Y155312D01*
G01X3155769Y146979D02*
X3159799D01*
G01X3167084Y142812D02*
Y155312D01*
X3170804D01*
X3172044Y154687D01*
X3172974Y153229D01*
X3173284Y151562D01*
X3172974Y149895D01*
X3172199Y148645D01*
X3170804Y148020D01*
X3167084D01*
G01X3179484Y155312D02*
Y142812D01*
X3185684D01*
G01X3191109D02*
X3194984Y155312D01*
X3198859Y142812D01*
G01X3197464Y147187D02*
X3192504D01*
G01X3207384Y155312D02*
Y142812D01*
G01X3203819Y155312D02*
X3210949D01*
G01X3222884Y142812D02*
X3216684D01*
Y155312D01*
X3222884D01*
G01X3220404Y149270D02*
X3216684D01*
G01X3228774Y142812D02*
Y155312D01*
X3231874D01*
X3233114Y154687D01*
X3234044Y153854D01*
X3234819Y152604D01*
X3235439Y151145D01*
X3235594Y149062D01*
X3235439Y146979D01*
X3234819Y145520D01*
X3234044Y144270D01*
X3233114Y143437D01*
X3231874Y142812D01*
X3228774D01*
G01X3117019Y180612D02*
Y193112D01*
X3124149Y180612D01*
Y193112D01*
G01X3132984Y180612D02*
X3131744Y180820D01*
X3130659Y181653D01*
X3129729Y182904D01*
X3129109Y184362D01*
X3128799Y186029D01*
Y187695D01*
X3129109Y189362D01*
X3129729Y190820D01*
X3130659Y192070D01*
X3131744Y192904D01*
X3132984Y193112D01*
X3134224Y192904D01*
X3135309Y192070D01*
X3136239Y190820D01*
X3136859Y189362D01*
X3137169Y187695D01*
Y186029D01*
X3136859Y184362D01*
X3136239Y182904D01*
X3135309Y181653D01*
X3134224Y180820D01*
X3132984Y180612D01*
G01X3141819D02*
Y193112D01*
X3148949Y180612D01*
Y193112D01*
G01X3155769Y184779D02*
X3159799D01*
G01X3167084Y180612D02*
Y193112D01*
X3170804D01*
X3172044Y192487D01*
X3172974Y191029D01*
X3173284Y189362D01*
X3172974Y187695D01*
X3172199Y186445D01*
X3170804Y185820D01*
X3167084D01*
G01X3179484Y193112D02*
Y180612D01*
X3185684D01*
G01X3191109D02*
X3194984Y193112D01*
X3198859Y180612D01*
G01X3197464Y184987D02*
X3192504D01*
G01X3207384Y193112D02*
Y180612D01*
G01X3203819Y193112D02*
X3210949D01*
G01X3222884Y180612D02*
X3216684D01*
Y193112D01*
X3222884D01*
G01X3220404Y187070D02*
X3216684D01*
G01X3228774Y180612D02*
Y193112D01*
X3231874D01*
X3233114Y192487D01*
X3234044Y191654D01*
X3234819Y190404D01*
X3235439Y188945D01*
X3235594Y186862D01*
X3235439Y184779D01*
X3234819Y183320D01*
X3234044Y182070D01*
X3233114Y181237D01*
X3231874Y180612D01*
X3228774D01*
G01X3117019Y218412D02*
Y230912D01*
X3124149Y218412D01*
Y230912D01*
G01X3132984Y218412D02*
X3131744Y218620D01*
X3130659Y219453D01*
X3129729Y220704D01*
X3129109Y222162D01*
X3128799Y223829D01*
Y225495D01*
X3129109Y227162D01*
X3129729Y228620D01*
X3130659Y229870D01*
X3131744Y230704D01*
X3132984Y230912D01*
X3134224Y230704D01*
X3135309Y229870D01*
X3136239Y228620D01*
X3136859Y227162D01*
X3137169Y225495D01*
Y223829D01*
X3136859Y222162D01*
X3136239Y220704D01*
X3135309Y219453D01*
X3134224Y218620D01*
X3132984Y218412D01*
G01X3141819D02*
Y230912D01*
X3148949Y218412D01*
Y230912D01*
G01X3155769Y222579D02*
X3159799D01*
G01X3167084Y218412D02*
Y230912D01*
X3170804D01*
X3172044Y230287D01*
X3172974Y228829D01*
X3173284Y227162D01*
X3172974Y225495D01*
X3172199Y224245D01*
X3170804Y223620D01*
X3167084D01*
G01X3179484Y230912D02*
Y218412D01*
X3185684D01*
G01X3191109D02*
X3194984Y230912D01*
X3198859Y218412D01*
G01X3197464Y222787D02*
X3192504D01*
G01X3207384Y230912D02*
Y218412D01*
G01X3203819Y230912D02*
X3210949D01*
G01X3222884Y218412D02*
X3216684D01*
Y230912D01*
X3222884D01*
G01X3220404Y224870D02*
X3216684D01*
G01X3228774Y218412D02*
Y230912D01*
X3231874D01*
X3233114Y230287D01*
X3234044Y229454D01*
X3234819Y228204D01*
X3235439Y226745D01*
X3235594Y224662D01*
X3235439Y222579D01*
X3234819Y221120D01*
X3234044Y219870D01*
X3233114Y219037D01*
X3231874Y218412D01*
X3228774D01*
G01X3142284Y-46188D02*
Y-33688D01*
X3146004D01*
X3147244Y-34313D01*
X3148174Y-35771D01*
X3148484Y-37438D01*
X3148174Y-39105D01*
X3147399Y-40355D01*
X3146004Y-40980D01*
X3142284D01*
G01X3154684Y-33688D02*
Y-46188D01*
X3160884D01*
G01X3166309D02*
X3170184Y-33688D01*
X3174059Y-46188D01*
G01X3172664Y-41813D02*
X3167704D01*
G01X3182584Y-33688D02*
Y-46188D01*
G01X3179019Y-33688D02*
X3186149D01*
G01X3198084Y-46188D02*
X3191884D01*
Y-33688D01*
X3198084D01*
G01X3195604Y-39730D02*
X3191884D01*
G01X3203974Y-46188D02*
Y-33688D01*
X3207074D01*
X3208314Y-34313D01*
X3209244Y-35146D01*
X3210019Y-36396D01*
X3210639Y-37855D01*
X3210794Y-39938D01*
X3210639Y-42021D01*
X3210019Y-43480D01*
X3209244Y-44730D01*
X3208314Y-45563D01*
X3207074Y-46188D01*
X3203974D01*
G01X3142284Y256212D02*
Y268712D01*
X3146004D01*
X3147244Y268087D01*
X3148174Y266629D01*
X3148484Y264962D01*
X3148174Y263295D01*
X3147399Y262045D01*
X3146004Y261420D01*
X3142284D01*
G01X3154684Y268712D02*
Y256212D01*
X3160884D01*
G01X3166309D02*
X3170184Y268712D01*
X3174059Y256212D01*
G01X3172664Y260587D02*
X3167704D01*
G01X3182584Y268712D02*
Y256212D01*
G01X3179019Y268712D02*
X3186149D01*
G01X3198084Y256212D02*
X3191884D01*
Y268712D01*
X3198084D01*
G01X3195604Y262670D02*
X3191884D01*
G01X3203974Y256212D02*
Y268712D01*
X3207074D01*
X3208314Y268087D01*
X3209244Y267254D01*
X3210019Y266004D01*
X3210639Y264545D01*
X3210794Y262462D01*
X3210639Y260379D01*
X3210019Y258920D01*
X3209244Y257670D01*
X3208314Y256837D01*
X3207074Y256212D01*
X3203974D01*
G01X3142284Y294012D02*
Y306512D01*
X3146004D01*
X3147244Y305887D01*
X3148174Y304429D01*
X3148484Y302762D01*
X3148174Y301095D01*
X3147399Y299845D01*
X3146004Y299220D01*
X3142284D01*
G01X3154684Y306512D02*
Y294012D01*
X3160884D01*
G01X3166309D02*
X3170184Y306512D01*
X3174059Y294012D01*
G01X3172664Y298387D02*
X3167704D01*
G01X3182584Y306512D02*
Y294012D01*
G01X3179019Y306512D02*
X3186149D01*
G01X3198084Y294012D02*
X3191884D01*
Y306512D01*
X3198084D01*
G01X3195604Y300470D02*
X3191884D01*
G01X3203974Y294012D02*
Y306512D01*
X3207074D01*
X3208314Y305887D01*
X3209244Y305054D01*
X3210019Y303804D01*
X3210639Y302345D01*
X3210794Y300262D01*
X3210639Y298179D01*
X3210019Y296720D01*
X3209244Y295470D01*
X3208314Y294637D01*
X3207074Y294012D01*
X3203974D01*
G01X3142284Y331812D02*
Y344312D01*
X3146004D01*
X3147244Y343687D01*
X3148174Y342229D01*
X3148484Y340562D01*
X3148174Y338895D01*
X3147399Y337645D01*
X3146004Y337020D01*
X3142284D01*
G01X3154684Y344312D02*
Y331812D01*
X3160884D01*
G01X3166309D02*
X3170184Y344312D01*
X3174059Y331812D01*
G01X3172664Y336187D02*
X3167704D01*
G01X3182584Y344312D02*
Y331812D01*
G01X3179019Y344312D02*
X3186149D01*
G01X3198084Y331812D02*
X3191884D01*
Y344312D01*
X3198084D01*
G01X3195604Y338270D02*
X3191884D01*
G01X3203974Y331812D02*
Y344312D01*
X3207074D01*
X3208314Y343687D01*
X3209244Y342854D01*
X3210019Y341604D01*
X3210639Y340145D01*
X3210794Y338062D01*
X3210639Y335979D01*
X3210019Y334520D01*
X3209244Y333270D01*
X3208314Y332437D01*
X3207074Y331812D01*
X3203974D01*
G01X3142284Y369612D02*
Y382112D01*
X3146004D01*
X3147244Y381487D01*
X3148174Y380029D01*
X3148484Y378362D01*
X3148174Y376695D01*
X3147399Y375445D01*
X3146004Y374820D01*
X3142284D01*
G01X3154684Y382112D02*
Y369612D01*
X3160884D01*
G01X3166309D02*
X3170184Y382112D01*
X3174059Y369612D01*
G01X3172664Y373987D02*
X3167704D01*
G01X3182584Y382112D02*
Y369612D01*
G01X3179019Y382112D02*
X3186149D01*
G01X3198084Y369612D02*
X3191884D01*
Y382112D01*
X3198084D01*
G01X3195604Y376070D02*
X3191884D01*
G01X3203974Y369612D02*
Y382112D01*
X3207074D01*
X3208314Y381487D01*
X3209244Y380654D01*
X3210019Y379404D01*
X3210639Y377945D01*
X3210794Y375862D01*
X3210639Y373779D01*
X3210019Y372320D01*
X3209244Y371070D01*
X3208314Y370237D01*
X3207074Y369612D01*
X3203974D01*
G01X3142284Y407412D02*
Y419912D01*
X3146004D01*
X3147244Y419287D01*
X3148174Y417829D01*
X3148484Y416162D01*
X3148174Y414495D01*
X3147399Y413245D01*
X3146004Y412620D01*
X3142284D01*
G01X3154684Y419912D02*
Y407412D01*
X3160884D01*
G01X3166309D02*
X3170184Y419912D01*
X3174059Y407412D01*
G01X3172664Y411787D02*
X3167704D01*
G01X3182584Y419912D02*
Y407412D01*
G01X3179019Y419912D02*
X3186149D01*
G01X3198084Y407412D02*
X3191884D01*
Y419912D01*
X3198084D01*
G01X3195604Y413870D02*
X3191884D01*
G01X3203974Y407412D02*
Y419912D01*
X3207074D01*
X3208314Y419287D01*
X3209244Y418454D01*
X3210019Y417204D01*
X3210639Y415745D01*
X3210794Y413662D01*
X3210639Y411579D01*
X3210019Y410120D01*
X3209244Y408870D01*
X3208314Y408037D01*
X3207074Y407412D01*
X3203974D01*
G01X3142284Y445212D02*
Y457712D01*
X3146004D01*
X3147244Y457087D01*
X3148174Y455629D01*
X3148484Y453962D01*
X3148174Y452295D01*
X3147399Y451045D01*
X3146004Y450420D01*
X3142284D01*
G01X3154684Y457712D02*
Y445212D01*
X3160884D01*
G01X3166309D02*
X3170184Y457712D01*
X3174059Y445212D01*
G01X3172664Y449587D02*
X3167704D01*
G01X3182584Y457712D02*
Y445212D01*
G01X3179019Y457712D02*
X3186149D01*
G01X3198084Y445212D02*
X3191884D01*
Y457712D01*
X3198084D01*
G01X3195604Y451670D02*
X3191884D01*
G01X3203974Y445212D02*
Y457712D01*
X3207074D01*
X3208314Y457087D01*
X3209244Y456254D01*
X3210019Y455004D01*
X3210639Y453545D01*
X3210794Y451462D01*
X3210639Y449379D01*
X3210019Y447920D01*
X3209244Y446670D01*
X3208314Y445837D01*
X3207074Y445212D01*
X3203974D01*
G01X3142284Y483012D02*
Y495512D01*
X3146004D01*
X3147244Y494887D01*
X3148174Y493429D01*
X3148484Y491762D01*
X3148174Y490095D01*
X3147399Y488845D01*
X3146004Y488220D01*
X3142284D01*
G01X3154684Y495512D02*
Y483012D01*
X3160884D01*
G01X3166309D02*
X3170184Y495512D01*
X3174059Y483012D01*
G01X3172664Y487387D02*
X3167704D01*
G01X3182584Y495512D02*
Y483012D01*
G01X3179019Y495512D02*
X3186149D01*
G01X3198084Y483012D02*
X3191884D01*
Y495512D01*
X3198084D01*
G01X3195604Y489470D02*
X3191884D01*
G01X3203974Y483012D02*
Y495512D01*
X3207074D01*
X3208314Y494887D01*
X3209244Y494054D01*
X3210019Y492804D01*
X3210639Y491345D01*
X3210794Y489262D01*
X3210639Y487179D01*
X3210019Y485720D01*
X3209244Y484470D01*
X3208314Y483637D01*
X3207074Y483012D01*
X3203974D01*
G01X3142284Y520812D02*
Y533312D01*
X3146004D01*
X3147244Y532687D01*
X3148174Y531229D01*
X3148484Y529562D01*
X3148174Y527895D01*
X3147399Y526645D01*
X3146004Y526020D01*
X3142284D01*
G01X3154684Y533312D02*
Y520812D01*
X3160884D01*
G01X3166309D02*
X3170184Y533312D01*
X3174059Y520812D01*
G01X3172664Y525187D02*
X3167704D01*
G01X3182584Y533312D02*
Y520812D01*
G01X3179019Y533312D02*
X3186149D01*
G01X3198084Y520812D02*
X3191884D01*
Y533312D01*
X3198084D01*
G01X3195604Y527270D02*
X3191884D01*
G01X3203974Y520812D02*
Y533312D01*
X3207074D01*
X3208314Y532687D01*
X3209244Y531854D01*
X3210019Y530604D01*
X3210639Y529145D01*
X3210794Y527062D01*
X3210639Y524979D01*
X3210019Y523520D01*
X3209244Y522270D01*
X3208314Y521437D01*
X3207074Y520812D01*
X3203974D01*
G01X3142284Y558612D02*
Y571112D01*
X3146004D01*
X3147244Y570487D01*
X3148174Y569029D01*
X3148484Y567362D01*
X3148174Y565695D01*
X3147399Y564445D01*
X3146004Y563820D01*
X3142284D01*
G01X3154684Y571112D02*
Y558612D01*
X3160884D01*
G01X3166309D02*
X3170184Y571112D01*
X3174059Y558612D01*
G01X3172664Y562987D02*
X3167704D01*
G01X3182584Y571112D02*
Y558612D01*
G01X3179019Y571112D02*
X3186149D01*
G01X3198084Y558612D02*
X3191884D01*
Y571112D01*
X3198084D01*
G01X3195604Y565070D02*
X3191884D01*
G01X3203974Y558612D02*
Y571112D01*
X3207074D01*
X3208314Y570487D01*
X3209244Y569654D01*
X3210019Y568404D01*
X3210639Y566945D01*
X3210794Y564862D01*
X3210639Y562779D01*
X3210019Y561320D01*
X3209244Y560070D01*
X3208314Y559237D01*
X3207074Y558612D01*
X3203974D01*
G01X3142284Y596412D02*
Y608912D01*
X3146004D01*
X3147244Y608287D01*
X3148174Y606829D01*
X3148484Y605162D01*
X3148174Y603495D01*
X3147399Y602245D01*
X3146004Y601620D01*
X3142284D01*
G01X3154684Y608912D02*
Y596412D01*
X3160884D01*
G01X3166309D02*
X3170184Y608912D01*
X3174059Y596412D01*
G01X3172664Y600787D02*
X3167704D01*
G01X3182584Y608912D02*
Y596412D01*
G01X3179019Y608912D02*
X3186149D01*
G01X3198084Y596412D02*
X3191884D01*
Y608912D01*
X3198084D01*
G01X3195604Y602870D02*
X3191884D01*
G01X3203974Y596412D02*
Y608912D01*
X3207074D01*
X3208314Y608287D01*
X3209244Y607454D01*
X3210019Y606204D01*
X3210639Y604745D01*
X3210794Y602662D01*
X3210639Y600579D01*
X3210019Y599120D01*
X3209244Y597870D01*
X3208314Y597037D01*
X3207074Y596412D01*
X3203974D01*
G01X3142284Y634212D02*
Y646712D01*
X3146004D01*
X3147244Y646087D01*
X3148174Y644629D01*
X3148484Y642962D01*
X3148174Y641295D01*
X3147399Y640045D01*
X3146004Y639420D01*
X3142284D01*
G01X3154684Y646712D02*
Y634212D01*
X3160884D01*
G01X3166309D02*
X3170184Y646712D01*
X3174059Y634212D01*
G01X3172664Y638587D02*
X3167704D01*
G01X3182584Y646712D02*
Y634212D01*
G01X3179019Y646712D02*
X3186149D01*
G01X3198084Y634212D02*
X3191884D01*
Y646712D01*
X3198084D01*
G01X3195604Y640670D02*
X3191884D01*
G01X3203974Y634212D02*
Y646712D01*
X3207074D01*
X3208314Y646087D01*
X3209244Y645254D01*
X3210019Y644004D01*
X3210639Y642545D01*
X3210794Y640462D01*
X3210639Y638379D01*
X3210019Y636920D01*
X3209244Y635670D01*
X3208314Y634837D01*
X3207074Y634212D01*
X3203974D01*
G01X3142284Y672012D02*
Y684512D01*
X3146004D01*
X3147244Y683887D01*
X3148174Y682429D01*
X3148484Y680762D01*
X3148174Y679095D01*
X3147399Y677845D01*
X3146004Y677220D01*
X3142284D01*
G01X3154684Y684512D02*
Y672012D01*
X3160884D01*
G01X3166309D02*
X3170184Y684512D01*
X3174059Y672012D01*
G01X3172664Y676387D02*
X3167704D01*
G01X3182584Y684512D02*
Y672012D01*
G01X3179019Y684512D02*
X3186149D01*
G01X3198084Y672012D02*
X3191884D01*
Y684512D01*
X3198084D01*
G01X3195604Y678470D02*
X3191884D01*
G01X3203974Y672012D02*
Y684512D01*
X3207074D01*
X3208314Y683887D01*
X3209244Y683054D01*
X3210019Y681804D01*
X3210639Y680345D01*
X3210794Y678262D01*
X3210639Y676179D01*
X3210019Y674720D01*
X3209244Y673470D01*
X3208314Y672637D01*
X3207074Y672012D01*
X3203974D01*
G01X3142284Y709812D02*
Y722312D01*
X3146004D01*
X3147244Y721687D01*
X3148174Y720229D01*
X3148484Y718562D01*
X3148174Y716895D01*
X3147399Y715645D01*
X3146004Y715020D01*
X3142284D01*
G01X3154684Y722312D02*
Y709812D01*
X3160884D01*
G01X3166309D02*
X3170184Y722312D01*
X3174059Y709812D01*
G01X3172664Y714187D02*
X3167704D01*
G01X3182584Y722312D02*
Y709812D01*
G01X3179019Y722312D02*
X3186149D01*
G01X3198084Y709812D02*
X3191884D01*
Y722312D01*
X3198084D01*
G01X3195604Y716270D02*
X3191884D01*
G01X3203974Y709812D02*
Y722312D01*
X3207074D01*
X3208314Y721687D01*
X3209244Y720854D01*
X3210019Y719604D01*
X3210639Y718145D01*
X3210794Y716062D01*
X3210639Y713979D01*
X3210019Y712520D01*
X3209244Y711270D01*
X3208314Y710437D01*
X3207074Y709812D01*
X3203974D01*
G01X3142284Y741212D02*
Y753712D01*
X3146004D01*
X3147244Y753087D01*
X3148174Y751629D01*
X3148484Y749962D01*
X3148174Y748295D01*
X3147399Y747045D01*
X3146004Y746420D01*
X3142284D01*
G01X3154684Y753712D02*
Y741212D01*
X3160884D01*
G01X3166309D02*
X3170184Y753712D01*
X3174059Y741212D01*
G01X3172664Y745587D02*
X3167704D01*
G01X3182584Y753712D02*
Y741212D01*
G01X3179019Y753712D02*
X3186149D01*
G01X3198084Y741212D02*
X3191884D01*
Y753712D01*
X3198084D01*
G01X3195604Y747670D02*
X3191884D01*
G01X3203974Y741212D02*
Y753712D01*
X3207074D01*
X3208314Y753087D01*
X3209244Y752254D01*
X3210019Y751004D01*
X3210639Y749545D01*
X3210794Y747462D01*
X3210639Y745379D01*
X3210019Y743920D01*
X3209244Y742670D01*
X3208314Y741837D01*
X3207074Y741212D01*
X3203974D01*
G01X3275739Y-35771D02*
X3276669Y-34522D01*
X3277754Y-33896D01*
X3278994Y-33688D01*
X3280544Y-34105D01*
X3281629Y-35146D01*
X3281939Y-36396D01*
X3281784Y-37647D01*
X3281164Y-38688D01*
X3278064Y-40771D01*
X3276669Y-42230D01*
X3275739Y-44313D01*
X3275429Y-46188D01*
X3281939D01*
G01X3280544Y-8388D02*
Y4112D01*
X3274809Y-4846D01*
X3282559D01*
G01X3280544Y29412D02*
Y41912D01*
X3274809Y32954D01*
X3282559D01*
G01X3275274Y69712D02*
X3276204Y68253D01*
X3277444Y67420D01*
X3278839Y67212D01*
X3280079Y67420D01*
X3281319Y68462D01*
X3282094Y69712D01*
X3282249Y70962D01*
X3281939Y72420D01*
X3280854Y73462D01*
X3279769Y73879D01*
X3278374D01*
G01X3279769D02*
X3280699Y74504D01*
X3281474Y75545D01*
X3281784Y76795D01*
X3281474Y78045D01*
X3280699Y79087D01*
X3279304Y79712D01*
X3277909Y79504D01*
X3276514Y78670D01*
G01X3280544Y105012D02*
Y117512D01*
X3274809Y108554D01*
X3282559D01*
G01X3275739Y153229D02*
X3276669Y154478D01*
X3277754Y155104D01*
X3278994Y155312D01*
X3280544Y154895D01*
X3281629Y153854D01*
X3281939Y152604D01*
X3281784Y151353D01*
X3281164Y150312D01*
X3278064Y148229D01*
X3276669Y146770D01*
X3275739Y144687D01*
X3275429Y142812D01*
X3281939D01*
G01X3280544Y180612D02*
Y193112D01*
X3274809Y184154D01*
X3282559D01*
G01X3275739Y228829D02*
X3276669Y230078D01*
X3277754Y230704D01*
X3278994Y230912D01*
X3280544Y230495D01*
X3281629Y229454D01*
X3281939Y228204D01*
X3281784Y226953D01*
X3281164Y225912D01*
X3278064Y223829D01*
X3276669Y222370D01*
X3275739Y220287D01*
X3275429Y218412D01*
X3281939D01*
G01X3280544Y256212D02*
Y268712D01*
X3274809Y259754D01*
X3282559D01*
G01X3275739Y304429D02*
X3276669Y305678D01*
X3277754Y306304D01*
X3278994Y306512D01*
X3280544Y306095D01*
X3281629Y305054D01*
X3281939Y303804D01*
X3281784Y302553D01*
X3281164Y301512D01*
X3278064Y299429D01*
X3276669Y297970D01*
X3275739Y295887D01*
X3275429Y294012D01*
X3281939D01*
G01X3280544Y331812D02*
Y344312D01*
X3274809Y335354D01*
X3282559D01*
G01X3272484Y369612D02*
Y382112D01*
X3270624Y379612D01*
G01Y369612D02*
X3274344D01*
G01X3281939Y374820D02*
X3283024Y376279D01*
X3283954Y377112D01*
X3285194Y377529D01*
X3286279Y377112D01*
X3287054Y376279D01*
X3287674Y375029D01*
X3287829Y373570D01*
X3287674Y372320D01*
X3287054Y371070D01*
X3286124Y370029D01*
X3285039Y369612D01*
X3283799Y370029D01*
X3282714Y371278D01*
X3282094Y373154D01*
X3281939Y375237D01*
X3282249Y377945D01*
X3282714Y379404D01*
X3283489Y380862D01*
X3284574Y381904D01*
X3285659Y382112D01*
X3286744Y381695D01*
X3287519Y380654D01*
G01X3272484Y407412D02*
Y419912D01*
X3270624Y417412D01*
G01Y407412D02*
X3274344D01*
G01X3281939Y417829D02*
X3282869Y419078D01*
X3283954Y419704D01*
X3285194Y419912D01*
X3286744Y419495D01*
X3287829Y418454D01*
X3288139Y417204D01*
X3287984Y415953D01*
X3287364Y414912D01*
X3284264Y412829D01*
X3282869Y411370D01*
X3281939Y409287D01*
X3281629Y407412D01*
X3288139D01*
G01X3274344Y445212D02*
Y457712D01*
X3268609Y448754D01*
X3276359D01*
G01X3284884Y457712D02*
X3283644Y457295D01*
X3282714Y456254D01*
X3282094Y455004D01*
X3281629Y453337D01*
X3281474Y451462D01*
X3281629Y449587D01*
X3282094Y447920D01*
X3282714Y446670D01*
X3283644Y445629D01*
X3284884Y445212D01*
X3286124Y445629D01*
X3287054Y446670D01*
X3287674Y447920D01*
X3288139Y449587D01*
X3288294Y451462D01*
X3288139Y453337D01*
X3287674Y455004D01*
X3287054Y456254D01*
X3286124Y457295D01*
X3284884Y457712D01*
G01X3276049Y484470D02*
X3277134Y483429D01*
X3278374Y483012D01*
X3279614Y483429D01*
X3280699Y484678D01*
X3281474Y486554D01*
X3281784Y488429D01*
Y490720D01*
X3281474Y492595D01*
X3280699Y494262D01*
X3279769Y495095D01*
X3278684Y495512D01*
X3277444Y495095D01*
X3276514Y494262D01*
X3275894Y493012D01*
X3275584Y491345D01*
X3275894Y489887D01*
X3276669Y488429D01*
X3277599Y487595D01*
X3278684Y487387D01*
X3279924Y487803D01*
X3280854Y488845D01*
X3281784Y490720D01*
G01X3269074Y523312D02*
X3270004Y521853D01*
X3271244Y521020D01*
X3272639Y520812D01*
X3273879Y521020D01*
X3275119Y522062D01*
X3275894Y523312D01*
X3276049Y524562D01*
X3275739Y526020D01*
X3274654Y527062D01*
X3273569Y527479D01*
X3272174D01*
G01X3273569D02*
X3274499Y528104D01*
X3275274Y529145D01*
X3275584Y530395D01*
X3275274Y531645D01*
X3274499Y532687D01*
X3273104Y533312D01*
X3271709Y533104D01*
X3270314Y532270D01*
G01X3281939Y531229D02*
X3282869Y532478D01*
X3283954Y533104D01*
X3285194Y533312D01*
X3286744Y532895D01*
X3287829Y531854D01*
X3288139Y530604D01*
X3287984Y529353D01*
X3287364Y528312D01*
X3284264Y526229D01*
X3282869Y524770D01*
X3281939Y522687D01*
X3281629Y520812D01*
X3288139D01*
G01X3272174Y558612D02*
X3272484Y561320D01*
X3272949Y563612D01*
X3273569Y565695D01*
X3274344Y567987D01*
X3275584Y571112D01*
X3269384D01*
G01X3281939Y569029D02*
X3282869Y570278D01*
X3283954Y570904D01*
X3285194Y571112D01*
X3286744Y570695D01*
X3287829Y569654D01*
X3288139Y568404D01*
X3287984Y567153D01*
X3287364Y566112D01*
X3284264Y564029D01*
X3282869Y562570D01*
X3281939Y560487D01*
X3281629Y558612D01*
X3288139D01*
G01X3263339Y606829D02*
X3264269Y608078D01*
X3265354Y608704D01*
X3266594Y608912D01*
X3268144Y608495D01*
X3269229Y607454D01*
X3269539Y606204D01*
X3269384Y604953D01*
X3268764Y603912D01*
X3265664Y601829D01*
X3264269Y600370D01*
X3263339Y598287D01*
X3263029Y596412D01*
X3269539D01*
G01X3278684D02*
Y608912D01*
X3276824Y606412D01*
G01Y596412D02*
X3280544D01*
G01X3288139Y601620D02*
X3289224Y603079D01*
X3290154Y603912D01*
X3291394Y604329D01*
X3292479Y603912D01*
X3293254Y603079D01*
X3293874Y601829D01*
X3294029Y600370D01*
X3293874Y599120D01*
X3293254Y597870D01*
X3292324Y596829D01*
X3291239Y596412D01*
X3289999Y596829D01*
X3288914Y598078D01*
X3288294Y599954D01*
X3288139Y602037D01*
X3288449Y604745D01*
X3288914Y606204D01*
X3289689Y607662D01*
X3290774Y608704D01*
X3291859Y608912D01*
X3292944Y608495D01*
X3293719Y607454D01*
G01X3269074Y636712D02*
X3270004Y635253D01*
X3271244Y634420D01*
X3272639Y634212D01*
X3273879Y634420D01*
X3275119Y635462D01*
X3275894Y636712D01*
X3276049Y637962D01*
X3275739Y639420D01*
X3274654Y640462D01*
X3273569Y640879D01*
X3272174D01*
G01X3273569D02*
X3274499Y641504D01*
X3275274Y642545D01*
X3275584Y643795D01*
X3275274Y645045D01*
X3274499Y646087D01*
X3273104Y646712D01*
X3271709Y646504D01*
X3270314Y645670D01*
G01X3281939Y644629D02*
X3282869Y645878D01*
X3283954Y646504D01*
X3285194Y646712D01*
X3286744Y646295D01*
X3287829Y645254D01*
X3288139Y644004D01*
X3287984Y642753D01*
X3287364Y641712D01*
X3284264Y639629D01*
X3282869Y638170D01*
X3281939Y636087D01*
X3281629Y634212D01*
X3288139D01*
G01X3260084Y672012D02*
Y684512D01*
X3258224Y682012D01*
G01Y672012D02*
X3261944D01*
G01X3269074Y673887D02*
X3270004Y672845D01*
X3271089Y672220D01*
X3272484Y672012D01*
X3273879Y672429D01*
X3274964Y673262D01*
X3275739Y674720D01*
X3275894Y676387D01*
X3275584Y678054D01*
X3274809Y679095D01*
X3273724Y679929D01*
X3272639Y680137D01*
X3271554Y679929D01*
X3270159Y679095D01*
X3270624Y684512D01*
X3274809D01*
G01X3281939Y677220D02*
X3283024Y678679D01*
X3283954Y679512D01*
X3285194Y679929D01*
X3286279Y679512D01*
X3287054Y678679D01*
X3287674Y677429D01*
X3287829Y675970D01*
X3287674Y674720D01*
X3287054Y673470D01*
X3286124Y672429D01*
X3285039Y672012D01*
X3283799Y672429D01*
X3282714Y673678D01*
X3282094Y675554D01*
X3281939Y677637D01*
X3282249Y680345D01*
X3282714Y681804D01*
X3283489Y683262D01*
X3284574Y684304D01*
X3285659Y684512D01*
X3286744Y684095D01*
X3287519Y683054D01*
G01X3293874Y674512D02*
X3294804Y673053D01*
X3296044Y672220D01*
X3297439Y672012D01*
X3298679Y672220D01*
X3299919Y673262D01*
X3300694Y674512D01*
X3300849Y675762D01*
X3300539Y677220D01*
X3299454Y678262D01*
X3298369Y678679D01*
X3296974D01*
G01X3298369D02*
X3299299Y679304D01*
X3300074Y680345D01*
X3300384Y681595D01*
X3300074Y682845D01*
X3299299Y683887D01*
X3297904Y684512D01*
X3296509Y684304D01*
X3295114Y683470D01*
G01X3263339Y720229D02*
X3264269Y721478D01*
X3265354Y722104D01*
X3266594Y722312D01*
X3268144Y721895D01*
X3269229Y720854D01*
X3269539Y719604D01*
X3269384Y718353D01*
X3268764Y717312D01*
X3265664Y715229D01*
X3264269Y713770D01*
X3263339Y711687D01*
X3263029Y709812D01*
X3269539D01*
G01X3278684D02*
Y722312D01*
X3276824Y719812D01*
G01Y709812D02*
X3280544D01*
G01X3288139Y715020D02*
X3289224Y716479D01*
X3290154Y717312D01*
X3291394Y717729D01*
X3292479Y717312D01*
X3293254Y716479D01*
X3293874Y715229D01*
X3294029Y713770D01*
X3293874Y712520D01*
X3293254Y711270D01*
X3292324Y710229D01*
X3291239Y709812D01*
X3289999Y710229D01*
X3288914Y711478D01*
X3288294Y713354D01*
X3288139Y715437D01*
X3288449Y718145D01*
X3288914Y719604D01*
X3289689Y721062D01*
X3290774Y722104D01*
X3291859Y722312D01*
X3292944Y721895D01*
X3293719Y720854D01*
G01X3266284Y741212D02*
X3265044Y741420D01*
X3263959Y742253D01*
X3263029Y743504D01*
X3262409Y744962D01*
X3262099Y746629D01*
Y748295D01*
X3262409Y749962D01*
X3263029Y751420D01*
X3263959Y752670D01*
X3265044Y753504D01*
X3266284Y753712D01*
X3267524Y753504D01*
X3268609Y752670D01*
X3269539Y751420D01*
X3270159Y749962D01*
X3270469Y748295D01*
Y746629D01*
X3270159Y744962D01*
X3269539Y743504D01*
X3268609Y742253D01*
X3267524Y741420D01*
X3266284Y741212D01*
G01X3267524Y744545D02*
X3269384Y741212D01*
G01X3278684Y753712D02*
Y741212D01*
G01X3275119Y753712D02*
X3282249D01*
G01X3291084Y741212D02*
Y746837D01*
X3287984Y753712D01*
G01X3294184D02*
X3291084Y746837D01*
G01X3354383Y561424D02*
Y568924D01*
X3356717D01*
X3357463Y568549D01*
X3357930Y568049D01*
X3358117Y567049D01*
X3357930Y566049D01*
X3357370Y565424D01*
X3356717Y565049D01*
X3354383D01*
G01X3356717D02*
X3358117Y561424D01*
G01X3365617D02*
X3361883D01*
Y568924D01*
X3365617D01*
G01X3364123Y565299D02*
X3361883D01*
G01X3373303Y568299D02*
X3372743Y568674D01*
X3372090Y568924D01*
X3371343D01*
X3370503Y568549D01*
X3369850Y567924D01*
X3369383Y567174D01*
X3369010Y565924D01*
X3368917Y564799D01*
X3369103Y563674D01*
X3369383Y562924D01*
X3369943Y562174D01*
X3370597Y561674D01*
X3371250Y561424D01*
X3371903D01*
X3372557Y561674D01*
X3373117Y562049D01*
X3373583Y562549D01*
G01X3378750Y561424D02*
X3378003Y561549D01*
X3377350Y562049D01*
X3376790Y562799D01*
X3376417Y563674D01*
X3376230Y564674D01*
Y565674D01*
X3376417Y566674D01*
X3376790Y567549D01*
X3377350Y568299D01*
X3378003Y568799D01*
X3378750Y568924D01*
X3379497Y568799D01*
X3380150Y568299D01*
X3380710Y567549D01*
X3381083Y566674D01*
X3381270Y565674D01*
Y564674D01*
X3381083Y563674D01*
X3380710Y562799D01*
X3380150Y562049D01*
X3379497Y561549D01*
X3378750Y561424D01*
G01X3383823D02*
Y568924D01*
X3386250Y562674D01*
X3388677Y568924D01*
Y561424D01*
G01X3391323D02*
Y568924D01*
X3393750Y562674D01*
X3396177Y568924D01*
Y561424D01*
G01X3403117D02*
X3399383D01*
Y568924D01*
X3403117D01*
G01X3401623Y565299D02*
X3399383D01*
G01X3406603Y561424D02*
Y568924D01*
X3410897Y561424D01*
Y568924D01*
G01X3414197Y561424D02*
Y568924D01*
X3416063D01*
X3416810Y568549D01*
X3417370Y568049D01*
X3417837Y567299D01*
X3418210Y566424D01*
X3418303Y565174D01*
X3418210Y563924D01*
X3417837Y563049D01*
X3417370Y562299D01*
X3416810Y561799D01*
X3416063Y561424D01*
X3414197D01*
G01X3425617D02*
X3421883D01*
Y568924D01*
X3425617D01*
G01X3424123Y565299D02*
X3421883D01*
G01X3429197Y561424D02*
Y568924D01*
X3431063D01*
X3431810Y568549D01*
X3432370Y568049D01*
X3432837Y567299D01*
X3433210Y566424D01*
X3433303Y565174D01*
X3433210Y563924D01*
X3432837Y563049D01*
X3432370Y562299D01*
X3431810Y561799D01*
X3431063Y561424D01*
X3429197D01*
G01X3444197D02*
Y568924D01*
X3446063D01*
X3446810Y568549D01*
X3447370Y568049D01*
X3447837Y567299D01*
X3448210Y566424D01*
X3448303Y565174D01*
X3448210Y563924D01*
X3447837Y563049D01*
X3447370Y562299D01*
X3446810Y561799D01*
X3446063Y561424D01*
X3444197D01*
G01X3451883D02*
Y568924D01*
X3454217D01*
X3454963Y568549D01*
X3455430Y568049D01*
X3455617Y567049D01*
X3455430Y566049D01*
X3454870Y565424D01*
X3454217Y565049D01*
X3451883D01*
G01X3454217D02*
X3455617Y561424D01*
G01X3460130Y568924D02*
X3462370D01*
G01X3461250D02*
Y561424D01*
G01X3460130D02*
X3462370D01*
G01X3466883Y568924D02*
Y561424D01*
X3470617D01*
G01X3474383Y568924D02*
Y561424D01*
X3478117D01*
G01X3489290Y562424D02*
X3490037Y561799D01*
X3490877Y561424D01*
X3491623D01*
X3492370Y561799D01*
X3492930Y562424D01*
X3493210Y563299D01*
X3493023Y564174D01*
X3492557Y564924D01*
X3491717Y565424D01*
X3490597Y565674D01*
X3489943Y566174D01*
X3489663Y567049D01*
X3489850Y567924D01*
X3490317Y568549D01*
X3490970Y568924D01*
X3491623D01*
X3492277Y568674D01*
X3492837Y568049D01*
G01X3497630Y568924D02*
X3499870D01*
G01X3498750D02*
Y561424D01*
G01X3497630D02*
X3499870D01*
G01X3504477Y568924D02*
X3508023D01*
X3504477Y561424D01*
X3508023D01*
G01X3515617D02*
X3511883D01*
Y568924D01*
X3515617D01*
G01X3514123Y565299D02*
X3511883D01*
G01X3526977Y561424D02*
Y568924D01*
X3530523D01*
G01X3529217Y565299D02*
X3526977D01*
G01X3536250Y561424D02*
X3535503Y561549D01*
X3534850Y562049D01*
X3534290Y562799D01*
X3533917Y563674D01*
X3533730Y564674D01*
Y565674D01*
X3533917Y566674D01*
X3534290Y567549D01*
X3534850Y568299D01*
X3535503Y568799D01*
X3536250Y568924D01*
X3536997Y568799D01*
X3537650Y568299D01*
X3538210Y567549D01*
X3538583Y566674D01*
X3538770Y565674D01*
Y564674D01*
X3538583Y563674D01*
X3538210Y562799D01*
X3537650Y562049D01*
X3536997Y561549D01*
X3536250Y561424D01*
G01X3541883D02*
Y568924D01*
X3544217D01*
X3544963Y568549D01*
X3545430Y568049D01*
X3545617Y567049D01*
X3545430Y566049D01*
X3544870Y565424D01*
X3544217Y565049D01*
X3541883D01*
G01X3544217D02*
X3545617Y561424D01*
G01X3558750D02*
Y568924D01*
X3557630Y567424D01*
G01Y561424D02*
X3559870D01*
G01X3566250Y561174D02*
X3566063Y561299D01*
Y561549D01*
X3566250Y561674D01*
X3566437Y561549D01*
Y561299D01*
X3566250Y561174D01*
G01X3573750Y568924D02*
X3573003Y568674D01*
X3572443Y568049D01*
X3572070Y567299D01*
X3571790Y566299D01*
X3571697Y565174D01*
X3571790Y564049D01*
X3572070Y563049D01*
X3572443Y562299D01*
X3573003Y561674D01*
X3573750Y561424D01*
X3574497Y561674D01*
X3575057Y562299D01*
X3575430Y563049D01*
X3575710Y564049D01*
X3575803Y565174D01*
X3575710Y566299D01*
X3575430Y567299D01*
X3575057Y568049D01*
X3574497Y568674D01*
X3573750Y568924D01*
G01X3579477Y567674D02*
X3580037Y568424D01*
X3580690Y568799D01*
X3581437Y568924D01*
X3582370Y568674D01*
X3583023Y568049D01*
X3583210Y567299D01*
X3583117Y566549D01*
X3582743Y565924D01*
X3580877Y564674D01*
X3580037Y563799D01*
X3579477Y562549D01*
X3579290Y561424D01*
X3583210D01*
G01X3586323D02*
Y568924D01*
X3588750Y562674D01*
X3591177Y568924D01*
Y561424D01*
G01X3593823D02*
Y568924D01*
X3596250Y562674D01*
X3598677Y568924D01*
Y561424D01*
G01X3609477D02*
Y568924D01*
X3613023D01*
G01X3611717Y565299D02*
X3609477D01*
G01X3617630Y568924D02*
X3619870D01*
G01X3618750D02*
Y561424D01*
G01X3617630D02*
X3619870D01*
G01X3624103D02*
Y568924D01*
X3628397Y561424D01*
Y568924D01*
G01X3632630D02*
X3634870D01*
G01X3633750D02*
Y561424D01*
G01X3632630D02*
X3634870D01*
G01X3639290Y562424D02*
X3640037Y561799D01*
X3640877Y561424D01*
X3641623D01*
X3642370Y561799D01*
X3642930Y562424D01*
X3643210Y563299D01*
X3643023Y564174D01*
X3642557Y564924D01*
X3641717Y565424D01*
X3640597Y565674D01*
X3639943Y566174D01*
X3639663Y567049D01*
X3639850Y567924D01*
X3640317Y568549D01*
X3640970Y568924D01*
X3641623D01*
X3642277Y568674D01*
X3642837Y568049D01*
G01X3646790Y561424D02*
Y568924D01*
G01X3650710D02*
Y561424D01*
G01Y565174D02*
X3646790D01*
G01X3658117Y561424D02*
X3654383D01*
Y568924D01*
X3658117D01*
G01X3656623Y565299D02*
X3654383D01*
G01X3661697Y561424D02*
Y568924D01*
X3663563D01*
X3664310Y568549D01*
X3664870Y568049D01*
X3665337Y567299D01*
X3665710Y566424D01*
X3665803Y565174D01*
X3665710Y563924D01*
X3665337Y563049D01*
X3664870Y562299D01*
X3664310Y561799D01*
X3663563Y561424D01*
X3661697D01*
G01X3676883D02*
Y568924D01*
X3679123D01*
X3679870Y568549D01*
X3680430Y567674D01*
X3680617Y566674D01*
X3680430Y565674D01*
X3679963Y564924D01*
X3679123Y564549D01*
X3676883D01*
G01X3686250Y568924D02*
Y561424D01*
G01X3684103Y568924D02*
X3688397D01*
G01X3691790Y561424D02*
Y568924D01*
G01X3695710D02*
Y561424D01*
G01Y565174D02*
X3691790D01*
G01X3707630Y568924D02*
X3709870D01*
G01X3708750D02*
Y561424D01*
G01X3707630D02*
X3709870D01*
G01X3714290Y562424D02*
X3715037Y561799D01*
X3715877Y561424D01*
X3716623D01*
X3717370Y561799D01*
X3717930Y562424D01*
X3718210Y563299D01*
X3718023Y564174D01*
X3717557Y564924D01*
X3716717Y565424D01*
X3715597Y565674D01*
X3714943Y566174D01*
X3714663Y567049D01*
X3714850Y567924D01*
X3715317Y568549D01*
X3715970Y568924D01*
X3716623D01*
X3717277Y568674D01*
X3717837Y568049D01*
G01X3731250Y561424D02*
Y568924D01*
X3730130Y567424D01*
G01Y561424D02*
X3732370D01*
G01X3738750Y561174D02*
X3738563Y561299D01*
Y561549D01*
X3738750Y561674D01*
X3738937Y561549D01*
Y561299D01*
X3738750Y561174D01*
G01X3746250Y561424D02*
Y568924D01*
X3745130Y567424D01*
G01Y561424D02*
X3747370D01*
G01X3751697Y562549D02*
X3752257Y561924D01*
X3752910Y561549D01*
X3753750Y561424D01*
X3754590Y561674D01*
X3755243Y562174D01*
X3755710Y563049D01*
X3755803Y564049D01*
X3755617Y565049D01*
X3755150Y565674D01*
X3754497Y566174D01*
X3753843Y566299D01*
X3753190Y566174D01*
X3752350Y565674D01*
X3752630Y568924D01*
X3755150D01*
G01X3760223Y563924D02*
X3762463D01*
G01X3761250Y565549D02*
Y562299D01*
G01X3767070Y561174D02*
X3770430Y568924D01*
G01X3775037Y563924D02*
X3777463D01*
G01X3783750Y568924D02*
X3783003Y568674D01*
X3782443Y568049D01*
X3782070Y567299D01*
X3781790Y566299D01*
X3781697Y565174D01*
X3781790Y564049D01*
X3782070Y563049D01*
X3782443Y562299D01*
X3783003Y561674D01*
X3783750Y561424D01*
X3784497Y561674D01*
X3785057Y562299D01*
X3785430Y563049D01*
X3785710Y564049D01*
X3785803Y565174D01*
X3785710Y566299D01*
X3785430Y567299D01*
X3785057Y568049D01*
X3784497Y568674D01*
X3783750Y568924D01*
G01X3791250Y561174D02*
X3791063Y561299D01*
Y561549D01*
X3791250Y561674D01*
X3791437Y561549D01*
Y561299D01*
X3791250Y561174D01*
G01X3798750Y568924D02*
X3798003Y568674D01*
X3797443Y568049D01*
X3797070Y567299D01*
X3796790Y566299D01*
X3796697Y565174D01*
X3796790Y564049D01*
X3797070Y563049D01*
X3797443Y562299D01*
X3798003Y561674D01*
X3798750Y561424D01*
X3799497Y561674D01*
X3800057Y562299D01*
X3800430Y563049D01*
X3800710Y564049D01*
X3800803Y565174D01*
X3800710Y566299D01*
X3800430Y567299D01*
X3800057Y568049D01*
X3799497Y568674D01*
X3798750Y568924D01*
G01X3804477Y567674D02*
X3805037Y568424D01*
X3805690Y568799D01*
X3806437Y568924D01*
X3807370Y568674D01*
X3808023Y568049D01*
X3808210Y567299D01*
X3808117Y566549D01*
X3807743Y565924D01*
X3805877Y564674D01*
X3805037Y563799D01*
X3804477Y562549D01*
X3804290Y561424D01*
X3808210D01*
G01X3811697Y562549D02*
X3812257Y561924D01*
X3812910Y561549D01*
X3813750Y561424D01*
X3814590Y561674D01*
X3815243Y562174D01*
X3815710Y563049D01*
X3815803Y564049D01*
X3815617Y565049D01*
X3815150Y565674D01*
X3814497Y566174D01*
X3813843Y566299D01*
X3813190Y566174D01*
X3812350Y565674D01*
X3812630Y568924D01*
X3815150D01*
G01X3818823Y561424D02*
Y568924D01*
X3821250Y562674D01*
X3823677Y568924D01*
Y561424D01*
G01X3826323D02*
Y568924D01*
X3828750Y562674D01*
X3831177Y568924D01*
Y561424D01*
G01X3836250Y561174D02*
X3836063Y561299D01*
Y561549D01*
X3836250Y561674D01*
X3836437Y561549D01*
Y561299D01*
X3836250Y561174D01*
G01X3350688Y601812D02*
X3352928D01*
G01X3351808D02*
Y594312D01*
G01X3350688D02*
X3352928D01*
G01X3356881D02*
Y601812D01*
X3359308Y595562D01*
X3361735Y601812D01*
Y594312D01*
G01X3364381D02*
Y601812D01*
X3366808Y595562D01*
X3369235Y601812D01*
Y594312D01*
G01X3376175D02*
X3372441D01*
Y601812D01*
X3376175D01*
G01X3374681Y598187D02*
X3372441D01*
G01X3379941Y594312D02*
Y601812D01*
X3382275D01*
X3383021Y601437D01*
X3383488Y600937D01*
X3383675Y599937D01*
X3383488Y598937D01*
X3382928Y598312D01*
X3382275Y597937D01*
X3379941D01*
G01X3382275D02*
X3383675Y594312D01*
G01X3387348Y595312D02*
X3388095Y594687D01*
X3388935Y594312D01*
X3389681D01*
X3390428Y594687D01*
X3390988Y595312D01*
X3391268Y596187D01*
X3391081Y597062D01*
X3390615Y597812D01*
X3389775Y598312D01*
X3388655Y598562D01*
X3388001Y599062D01*
X3387721Y599937D01*
X3387908Y600812D01*
X3388375Y601437D01*
X3389028Y601812D01*
X3389681D01*
X3390335Y601562D01*
X3390895Y600937D01*
G01X3395688Y601812D02*
X3397928D01*
G01X3396808D02*
Y594312D01*
G01X3395688D02*
X3397928D01*
G01X3404308D02*
X3403561Y594437D01*
X3402908Y594937D01*
X3402348Y595687D01*
X3401975Y596562D01*
X3401788Y597562D01*
Y598562D01*
X3401975Y599562D01*
X3402348Y600437D01*
X3402908Y601187D01*
X3403561Y601687D01*
X3404308Y601812D01*
X3405055Y601687D01*
X3405708Y601187D01*
X3406268Y600437D01*
X3406641Y599562D01*
X3406828Y598562D01*
Y597562D01*
X3406641Y596562D01*
X3406268Y595687D01*
X3405708Y594937D01*
X3405055Y594437D01*
X3404308Y594312D01*
G01X3409661D02*
Y601812D01*
X3413955Y594312D01*
Y601812D01*
G01X3426808D02*
Y594312D01*
G01X3424661Y601812D02*
X3428955D01*
G01X3433188D02*
X3435428D01*
G01X3434308D02*
Y594312D01*
G01X3433188D02*
X3435428D01*
G01X3439661D02*
Y601812D01*
X3443955Y594312D01*
Y601812D01*
G01X3447628Y594062D02*
X3450988Y601812D01*
G01X3458861Y601187D02*
X3458301Y601562D01*
X3457648Y601812D01*
X3456901D01*
X3456061Y601437D01*
X3455408Y600812D01*
X3454941Y600062D01*
X3454568Y598812D01*
X3454475Y597687D01*
X3454661Y596562D01*
X3454941Y595812D01*
X3455501Y595062D01*
X3456155Y594562D01*
X3456808Y594312D01*
X3457461D01*
X3458115Y594562D01*
X3458675Y594937D01*
X3459141Y595437D01*
G01X3464308Y594312D02*
X3463561Y594437D01*
X3462908Y594937D01*
X3462348Y595687D01*
X3461975Y596562D01*
X3461788Y597562D01*
Y598562D01*
X3461975Y599562D01*
X3462348Y600437D01*
X3462908Y601187D01*
X3463561Y601687D01*
X3464308Y601812D01*
X3465055Y601687D01*
X3465708Y601187D01*
X3466268Y600437D01*
X3466641Y599562D01*
X3466828Y598562D01*
Y597562D01*
X3466641Y596562D01*
X3466268Y595687D01*
X3465708Y594937D01*
X3465055Y594437D01*
X3464308Y594312D01*
G01X3469941D02*
Y601812D01*
X3472181D01*
X3472928Y601437D01*
X3473488Y600562D01*
X3473675Y599562D01*
X3473488Y598562D01*
X3473021Y597812D01*
X3472181Y597437D01*
X3469941D01*
G01X3477441Y594312D02*
Y601812D01*
X3479681D01*
X3480428Y601437D01*
X3480988Y600562D01*
X3481175Y599562D01*
X3480988Y598562D01*
X3480521Y597812D01*
X3479681Y597437D01*
X3477441D01*
G01X3488675Y594312D02*
X3484941D01*
Y601812D01*
X3488675D01*
G01X3487181Y598187D02*
X3484941D01*
G01X3492441Y594312D02*
Y601812D01*
X3494775D01*
X3495521Y601437D01*
X3495988Y600937D01*
X3496175Y599937D01*
X3495988Y598937D01*
X3495428Y598312D01*
X3494775Y597937D01*
X3492441D01*
G01X3494775D02*
X3496175Y594312D01*
G01X3501808Y594062D02*
X3501621Y594187D01*
Y594437D01*
X3501808Y594562D01*
X3501995Y594437D01*
Y594187D01*
X3501808Y594062D01*
G01Y597437D02*
X3501621Y597562D01*
Y597812D01*
X3501808Y597937D01*
X3501995Y597812D01*
Y597562D01*
X3501808Y597437D01*
G01X3507441Y594312D02*
Y601812D01*
X3509775D01*
X3510521Y601437D01*
X3510988Y600937D01*
X3511175Y599937D01*
X3510988Y598937D01*
X3510428Y598312D01*
X3509775Y597937D01*
X3507441D01*
G01X3509775D02*
X3511175Y594312D01*
G01X3518675D02*
X3514941D01*
Y601812D01*
X3518675D01*
G01X3517181Y598187D02*
X3514941D01*
G01X3526361Y601187D02*
X3525801Y601562D01*
X3525148Y601812D01*
X3524401D01*
X3523561Y601437D01*
X3522908Y600812D01*
X3522441Y600062D01*
X3522068Y598812D01*
X3521975Y597687D01*
X3522161Y596562D01*
X3522441Y595812D01*
X3523001Y595062D01*
X3523655Y594562D01*
X3524308Y594312D01*
X3524961D01*
X3525615Y594562D01*
X3526175Y594937D01*
X3526641Y595437D01*
G01X3531808Y594312D02*
X3531061Y594437D01*
X3530408Y594937D01*
X3529848Y595687D01*
X3529475Y596562D01*
X3529288Y597562D01*
Y598562D01*
X3529475Y599562D01*
X3529848Y600437D01*
X3530408Y601187D01*
X3531061Y601687D01*
X3531808Y601812D01*
X3532555Y601687D01*
X3533208Y601187D01*
X3533768Y600437D01*
X3534141Y599562D01*
X3534328Y598562D01*
Y597562D01*
X3534141Y596562D01*
X3533768Y595687D01*
X3533208Y594937D01*
X3532555Y594437D01*
X3531808Y594312D01*
G01X3536881D02*
Y601812D01*
X3539308Y595562D01*
X3541735Y601812D01*
Y594312D01*
G01X3544381D02*
Y601812D01*
X3546808Y595562D01*
X3549235Y601812D01*
Y594312D01*
G01X3556175D02*
X3552441D01*
Y601812D01*
X3556175D01*
G01X3554681Y598187D02*
X3552441D01*
G01X3559661Y594312D02*
Y601812D01*
X3563955Y594312D01*
Y601812D01*
G01X3567255Y594312D02*
Y601812D01*
X3569121D01*
X3569868Y601437D01*
X3570428Y600937D01*
X3570895Y600187D01*
X3571268Y599312D01*
X3571361Y598062D01*
X3571268Y596812D01*
X3570895Y595937D01*
X3570428Y595187D01*
X3569868Y594687D01*
X3569121Y594312D01*
X3567255D01*
G01X3578675D02*
X3574941D01*
Y601812D01*
X3578675D01*
G01X3577181Y598187D02*
X3574941D01*
G01X3582255Y594312D02*
Y601812D01*
X3584121D01*
X3584868Y601437D01*
X3585428Y600937D01*
X3585895Y600187D01*
X3586268Y599312D01*
X3586361Y598062D01*
X3586268Y596812D01*
X3585895Y595937D01*
X3585428Y595187D01*
X3584868Y594687D01*
X3584121Y594312D01*
X3582255D01*
G01X3597255D02*
Y601812D01*
X3599121D01*
X3599868Y601437D01*
X3600428Y600937D01*
X3600895Y600187D01*
X3601268Y599312D01*
X3601361Y598062D01*
X3601268Y596812D01*
X3600895Y595937D01*
X3600428Y595187D01*
X3599868Y594687D01*
X3599121Y594312D01*
X3597255D01*
G01X3604941D02*
Y601812D01*
X3607275D01*
X3608021Y601437D01*
X3608488Y600937D01*
X3608675Y599937D01*
X3608488Y598937D01*
X3607928Y598312D01*
X3607275Y597937D01*
X3604941D01*
G01X3607275D02*
X3608675Y594312D01*
G01X3613188Y601812D02*
X3615428D01*
G01X3614308D02*
Y594312D01*
G01X3613188D02*
X3615428D01*
G01X3619941Y601812D02*
Y594312D01*
X3623675D01*
G01X3627441Y601812D02*
Y594312D01*
X3631175D01*
G01X3642348Y595312D02*
X3643095Y594687D01*
X3643935Y594312D01*
X3644681D01*
X3645428Y594687D01*
X3645988Y595312D01*
X3646268Y596187D01*
X3646081Y597062D01*
X3645615Y597812D01*
X3644775Y598312D01*
X3643655Y598562D01*
X3643001Y599062D01*
X3642721Y599937D01*
X3642908Y600812D01*
X3643375Y601437D01*
X3644028Y601812D01*
X3644681D01*
X3645335Y601562D01*
X3645895Y600937D01*
G01X3650688Y601812D02*
X3652928D01*
G01X3651808D02*
Y594312D01*
G01X3650688D02*
X3652928D01*
G01X3657535Y601812D02*
X3661081D01*
X3657535Y594312D01*
X3661081D01*
G01X3668675D02*
X3664941D01*
Y601812D01*
X3668675D01*
G01X3667181Y598187D02*
X3664941D01*
G01X3680035Y594312D02*
Y601812D01*
X3683581D01*
G01X3682275Y598187D02*
X3680035D01*
G01X3689308Y594312D02*
X3688561Y594437D01*
X3687908Y594937D01*
X3687348Y595687D01*
X3686975Y596562D01*
X3686788Y597562D01*
Y598562D01*
X3686975Y599562D01*
X3687348Y600437D01*
X3687908Y601187D01*
X3688561Y601687D01*
X3689308Y601812D01*
X3690055Y601687D01*
X3690708Y601187D01*
X3691268Y600437D01*
X3691641Y599562D01*
X3691828Y598562D01*
Y597562D01*
X3691641Y596562D01*
X3691268Y595687D01*
X3690708Y594937D01*
X3690055Y594437D01*
X3689308Y594312D01*
G01X3694941D02*
Y601812D01*
X3697275D01*
X3698021Y601437D01*
X3698488Y600937D01*
X3698675Y599937D01*
X3698488Y598937D01*
X3697928Y598312D01*
X3697275Y597937D01*
X3694941D01*
G01X3697275D02*
X3698675Y594312D01*
G01X3711808Y601812D02*
X3711061Y601562D01*
X3710501Y600937D01*
X3710128Y600187D01*
X3709848Y599187D01*
X3709755Y598062D01*
X3709848Y596937D01*
X3710128Y595937D01*
X3710501Y595187D01*
X3711061Y594562D01*
X3711808Y594312D01*
X3712555Y594562D01*
X3713115Y595187D01*
X3713488Y595937D01*
X3713768Y596937D01*
X3713861Y598062D01*
X3713768Y599187D01*
X3713488Y600187D01*
X3713115Y600937D01*
X3712555Y601562D01*
X3711808Y601812D01*
G01X3719308Y594062D02*
X3719121Y594187D01*
Y594437D01*
X3719308Y594562D01*
X3719495Y594437D01*
Y594187D01*
X3719308Y594062D01*
G01X3726621Y594312D02*
X3726808Y595937D01*
X3727088Y597312D01*
X3727461Y598562D01*
X3727928Y599937D01*
X3728675Y601812D01*
X3724941D01*
G01X3732255Y595437D02*
X3732815Y594812D01*
X3733468Y594437D01*
X3734308Y594312D01*
X3735148Y594562D01*
X3735801Y595062D01*
X3736268Y595937D01*
X3736361Y596937D01*
X3736175Y597937D01*
X3735708Y598562D01*
X3735055Y599062D01*
X3734401Y599187D01*
X3733748Y599062D01*
X3732908Y598562D01*
X3733188Y601812D01*
X3735708D01*
G01X3739381Y594312D02*
Y601812D01*
X3741808Y595562D01*
X3744235Y601812D01*
Y594312D01*
G01X3746881D02*
Y601812D01*
X3749308Y595562D01*
X3751735Y601812D01*
Y594312D01*
G01X3762535D02*
Y601812D01*
X3766081D01*
G01X3764775Y598187D02*
X3762535D01*
G01X3770688Y601812D02*
X3772928D01*
G01X3771808D02*
Y594312D01*
G01X3770688D02*
X3772928D01*
G01X3777161D02*
Y601812D01*
X3781455Y594312D01*
Y601812D01*
G01X3785688D02*
X3787928D01*
G01X3786808D02*
Y594312D01*
G01X3785688D02*
X3787928D01*
G01X3792348Y595312D02*
X3793095Y594687D01*
X3793935Y594312D01*
X3794681D01*
X3795428Y594687D01*
X3795988Y595312D01*
X3796268Y596187D01*
X3796081Y597062D01*
X3795615Y597812D01*
X3794775Y598312D01*
X3793655Y598562D01*
X3793001Y599062D01*
X3792721Y599937D01*
X3792908Y600812D01*
X3793375Y601437D01*
X3794028Y601812D01*
X3794681D01*
X3795335Y601562D01*
X3795895Y600937D01*
G01X3799848Y594312D02*
Y601812D01*
G01X3803768D02*
Y594312D01*
G01Y598062D02*
X3799848D01*
G01X3811175Y594312D02*
X3807441D01*
Y601812D01*
X3811175D01*
G01X3809681Y598187D02*
X3807441D01*
G01X3814755Y594312D02*
Y601812D01*
X3816621D01*
X3817368Y601437D01*
X3817928Y600937D01*
X3818395Y600187D01*
X3818768Y599312D01*
X3818861Y598062D01*
X3818768Y596812D01*
X3818395Y595937D01*
X3817928Y595187D01*
X3817368Y594687D01*
X3816621Y594312D01*
X3814755D01*
G01X3829941D02*
Y601812D01*
X3832181D01*
X3832928Y601437D01*
X3833488Y600562D01*
X3833675Y599562D01*
X3833488Y598562D01*
X3833021Y597812D01*
X3832181Y597437D01*
X3829941D01*
G01X3839308Y601812D02*
Y594312D01*
G01X3837161Y601812D02*
X3841455D01*
G01X3844848Y594312D02*
Y601812D01*
G01X3848768D02*
Y594312D01*
G01Y598062D02*
X3844848D01*
G01X3860688Y601812D02*
X3862928D01*
G01X3861808D02*
Y594312D01*
G01X3860688D02*
X3862928D01*
G01X3867348Y595312D02*
X3868095Y594687D01*
X3868935Y594312D01*
X3869681D01*
X3870428Y594687D01*
X3870988Y595312D01*
X3871268Y596187D01*
X3871081Y597062D01*
X3870615Y597812D01*
X3869775Y598312D01*
X3868655Y598562D01*
X3868001Y599062D01*
X3867721Y599937D01*
X3867908Y600812D01*
X3868375Y601437D01*
X3869028Y601812D01*
X3869681D01*
X3870335Y601562D01*
X3870895Y600937D01*
G01X3884308Y601812D02*
X3883561Y601562D01*
X3883001Y600937D01*
X3882628Y600187D01*
X3882348Y599187D01*
X3882255Y598062D01*
X3882348Y596937D01*
X3882628Y595937D01*
X3883001Y595187D01*
X3883561Y594562D01*
X3884308Y594312D01*
X3885055Y594562D01*
X3885615Y595187D01*
X3885988Y595937D01*
X3886268Y596937D01*
X3886361Y598062D01*
X3886268Y599187D01*
X3885988Y600187D01*
X3885615Y600937D01*
X3885055Y601562D01*
X3884308Y601812D01*
G01X3891808Y594062D02*
X3891621Y594187D01*
Y594437D01*
X3891808Y594562D01*
X3891995Y594437D01*
Y594187D01*
X3891808Y594062D01*
G01X3899308Y594312D02*
X3899961Y594437D01*
X3900708Y594812D01*
X3901175Y595437D01*
X3901361Y596312D01*
X3901175Y597187D01*
X3900615Y597937D01*
X3899775Y598312D01*
X3898841D01*
X3898281Y598562D01*
X3897815Y599187D01*
X3897628Y600062D01*
X3897908Y600937D01*
X3898561Y601562D01*
X3899308Y601812D01*
X3900055Y601562D01*
X3900708Y600937D01*
X3900988Y600062D01*
X3900801Y599187D01*
X3900335Y598562D01*
X3899775Y598312D01*
X3898841D01*
X3898001Y597937D01*
X3897441Y597187D01*
X3897255Y596312D01*
X3897441Y595437D01*
X3897908Y594812D01*
X3898655Y594437D01*
X3899308Y594312D01*
G01X3906808D02*
Y601812D01*
X3905688Y600312D01*
G01Y594312D02*
X3907928D01*
G01X3913095Y596812D02*
X3915521D01*
G01X3921808Y601812D02*
X3921061Y601562D01*
X3920501Y600937D01*
X3920128Y600187D01*
X3919848Y599187D01*
X3919755Y598062D01*
X3919848Y596937D01*
X3920128Y595937D01*
X3920501Y595187D01*
X3921061Y594562D01*
X3921808Y594312D01*
X3922555Y594562D01*
X3923115Y595187D01*
X3923488Y595937D01*
X3923768Y596937D01*
X3923861Y598062D01*
X3923768Y599187D01*
X3923488Y600187D01*
X3923115Y600937D01*
X3922555Y601562D01*
X3921808Y601812D01*
G01X3929308Y594062D02*
X3929121Y594187D01*
Y594437D01*
X3929308Y594562D01*
X3929495Y594437D01*
Y594187D01*
X3929308Y594062D01*
G01X3936808Y594312D02*
X3937461Y594437D01*
X3938208Y594812D01*
X3938675Y595437D01*
X3938861Y596312D01*
X3938675Y597187D01*
X3938115Y597937D01*
X3937275Y598312D01*
X3936341D01*
X3935781Y598562D01*
X3935315Y599187D01*
X3935128Y600062D01*
X3935408Y600937D01*
X3936061Y601562D01*
X3936808Y601812D01*
X3937555Y601562D01*
X3938208Y600937D01*
X3938488Y600062D01*
X3938301Y599187D01*
X3937835Y598562D01*
X3937275Y598312D01*
X3936341D01*
X3935501Y597937D01*
X3934941Y597187D01*
X3934755Y596312D01*
X3934941Y595437D01*
X3935408Y594812D01*
X3936155Y594437D01*
X3936808Y594312D01*
G01X3942535Y597437D02*
X3943188Y598312D01*
X3943748Y598812D01*
X3944495Y599062D01*
X3945148Y598812D01*
X3945615Y598312D01*
X3945988Y597562D01*
X3946081Y596687D01*
X3945988Y595937D01*
X3945615Y595187D01*
X3945055Y594562D01*
X3944401Y594312D01*
X3943655Y594562D01*
X3943001Y595312D01*
X3942628Y596437D01*
X3942535Y597687D01*
X3942721Y599312D01*
X3943001Y600187D01*
X3943468Y601062D01*
X3944121Y601687D01*
X3944775Y601812D01*
X3945428Y601562D01*
X3945895Y600937D01*
G01X3949381Y594312D02*
Y601812D01*
X3951808Y595562D01*
X3954235Y601812D01*
Y594312D01*
G01X3956881D02*
Y601812D01*
X3959308Y595562D01*
X3961735Y601812D01*
Y594312D01*
G01X3966341Y591812D02*
X3965408Y593062D01*
X3964941Y594312D01*
Y599312D01*
X3965408Y600562D01*
X3966341Y601812D01*
G01X3974308D02*
X3973561Y601562D01*
X3973001Y600937D01*
X3972628Y600187D01*
X3972348Y599187D01*
X3972255Y598062D01*
X3972348Y596937D01*
X3972628Y595937D01*
X3973001Y595187D01*
X3973561Y594562D01*
X3974308Y594312D01*
X3975055Y594562D01*
X3975615Y595187D01*
X3975988Y595937D01*
X3976268Y596937D01*
X3976361Y598062D01*
X3976268Y599187D01*
X3975988Y600187D01*
X3975615Y600937D01*
X3975055Y601562D01*
X3974308Y601812D01*
G01X3981808Y594062D02*
X3981621Y594187D01*
Y594437D01*
X3981808Y594562D01*
X3981995Y594437D01*
Y594187D01*
X3981808Y594062D01*
G01X3989308Y594312D02*
X3989961Y594437D01*
X3990708Y594812D01*
X3991175Y595437D01*
X3991361Y596312D01*
X3991175Y597187D01*
X3990615Y597937D01*
X3989775Y598312D01*
X3988841D01*
X3988281Y598562D01*
X3987815Y599187D01*
X3987628Y600062D01*
X3987908Y600937D01*
X3988561Y601562D01*
X3989308Y601812D01*
X3990055Y601562D01*
X3990708Y600937D01*
X3990988Y600062D01*
X3990801Y599187D01*
X3990335Y598562D01*
X3989775Y598312D01*
X3988841D01*
X3988001Y597937D01*
X3987441Y597187D01*
X3987255Y596312D01*
X3987441Y595437D01*
X3987908Y594812D01*
X3988655Y594437D01*
X3989308Y594312D01*
G01X3994755Y595437D02*
X3995315Y594812D01*
X3995968Y594437D01*
X3996808Y594312D01*
X3997648Y594562D01*
X3998301Y595062D01*
X3998768Y595937D01*
X3998861Y596937D01*
X3998675Y597937D01*
X3998208Y598562D01*
X3997555Y599062D01*
X3996901Y599187D01*
X3996248Y599062D01*
X3995408Y598562D01*
X3995688Y601812D01*
X3998208D01*
G01X4001881Y594312D02*
Y601812D01*
X4004308Y595562D01*
X4006735Y601812D01*
Y594312D01*
G01X4009381D02*
Y601812D01*
X4011808Y595562D01*
X4014235Y601812D01*
Y594312D01*
G01X4024755D02*
Y601812D01*
X4026621D01*
X4027368Y601437D01*
X4027928Y600937D01*
X4028395Y600187D01*
X4028768Y599312D01*
X4028861Y598062D01*
X4028768Y596812D01*
X4028395Y595937D01*
X4027928Y595187D01*
X4027368Y594687D01*
X4026621Y594312D01*
X4024755D01*
G01X4032441D02*
Y601812D01*
X4034775D01*
X4035521Y601437D01*
X4035988Y600937D01*
X4036175Y599937D01*
X4035988Y598937D01*
X4035428Y598312D01*
X4034775Y597937D01*
X4032441D01*
G01X4034775D02*
X4036175Y594312D01*
G01X4040688Y601812D02*
X4042928D01*
G01X4041808D02*
Y594312D01*
G01X4040688D02*
X4042928D01*
G01X4047441Y601812D02*
Y594312D01*
X4051175D01*
G01X4054941Y601812D02*
Y594312D01*
X4058675D01*
G01X4064775Y591812D02*
X4065708Y593062D01*
X4066175Y594312D01*
Y599312D01*
X4065708Y600562D01*
X4064775Y601812D01*
G01X3351108Y614212D02*
Y606712D01*
G01X3348961Y614212D02*
X3353255D01*
G01X3357488D02*
X3359728D01*
G01X3358608D02*
Y606712D01*
G01X3357488D02*
X3359728D01*
G01X3363961D02*
Y614212D01*
X3368255Y606712D01*
Y614212D01*
G01X3372395Y609212D02*
X3374821D01*
G01X3379241Y614212D02*
Y606712D01*
X3382975D01*
G01X3390475D02*
X3386741D01*
Y614212D01*
X3390475D01*
G01X3388981Y610587D02*
X3386741D01*
G01X3393775Y606712D02*
X3396108Y614212D01*
X3398441Y606712D01*
G01X3397601Y609337D02*
X3394615D01*
G01X3401555Y606712D02*
Y614212D01*
X3403421D01*
X3404168Y613837D01*
X3404728Y613337D01*
X3405195Y612587D01*
X3405568Y611712D01*
X3405661Y610462D01*
X3405568Y609212D01*
X3405195Y608337D01*
X3404728Y607587D01*
X3404168Y607087D01*
X3403421Y606712D01*
X3401555D01*
G01X3411108Y606462D02*
X3410921Y606587D01*
Y606837D01*
X3411108Y606962D01*
X3411295Y606837D01*
Y606587D01*
X3411108Y606462D01*
G01Y609837D02*
X3410921Y609962D01*
Y610212D01*
X3411108Y610337D01*
X3411295Y610212D01*
Y609962D01*
X3411108Y609837D01*
G01X3416741Y606712D02*
Y614212D01*
X3419075D01*
X3419821Y613837D01*
X3420288Y613337D01*
X3420475Y612337D01*
X3420288Y611337D01*
X3419728Y610712D01*
X3419075Y610337D01*
X3416741D01*
G01X3419075D02*
X3420475Y606712D01*
G01X3427975D02*
X3424241D01*
Y614212D01*
X3427975D01*
G01X3426481Y610587D02*
X3424241D01*
G01X3435661Y613587D02*
X3435101Y613962D01*
X3434448Y614212D01*
X3433701D01*
X3432861Y613837D01*
X3432208Y613212D01*
X3431741Y612462D01*
X3431368Y611212D01*
X3431275Y610087D01*
X3431461Y608962D01*
X3431741Y608212D01*
X3432301Y607462D01*
X3432955Y606962D01*
X3433608Y606712D01*
X3434261D01*
X3434915Y606962D01*
X3435475Y607337D01*
X3435941Y607837D01*
G01X3441108Y606712D02*
X3440361Y606837D01*
X3439708Y607337D01*
X3439148Y608087D01*
X3438775Y608962D01*
X3438588Y609962D01*
Y610962D01*
X3438775Y611962D01*
X3439148Y612837D01*
X3439708Y613587D01*
X3440361Y614087D01*
X3441108Y614212D01*
X3441855Y614087D01*
X3442508Y613587D01*
X3443068Y612837D01*
X3443441Y611962D01*
X3443628Y610962D01*
Y609962D01*
X3443441Y608962D01*
X3443068Y608087D01*
X3442508Y607337D01*
X3441855Y606837D01*
X3441108Y606712D01*
G01X3446181D02*
Y614212D01*
X3448608Y607962D01*
X3451035Y614212D01*
Y606712D01*
G01X3453681D02*
Y614212D01*
X3456108Y607962D01*
X3458535Y614212D01*
Y606712D01*
G01X3465475D02*
X3461741D01*
Y614212D01*
X3465475D01*
G01X3463981Y610587D02*
X3461741D01*
G01X3468961Y606712D02*
Y614212D01*
X3473255Y606712D01*
Y614212D01*
G01X3476555Y606712D02*
Y614212D01*
X3478421D01*
X3479168Y613837D01*
X3479728Y613337D01*
X3480195Y612587D01*
X3480568Y611712D01*
X3480661Y610462D01*
X3480568Y609212D01*
X3480195Y608337D01*
X3479728Y607587D01*
X3479168Y607087D01*
X3478421Y606712D01*
X3476555D01*
G01X3487975D02*
X3484241D01*
Y614212D01*
X3487975D01*
G01X3486481Y610587D02*
X3484241D01*
G01X3491555Y606712D02*
Y614212D01*
X3493421D01*
X3494168Y613837D01*
X3494728Y613337D01*
X3495195Y612587D01*
X3495568Y611712D01*
X3495661Y610462D01*
X3495568Y609212D01*
X3495195Y608337D01*
X3494728Y607587D01*
X3494168Y607087D01*
X3493421Y606712D01*
X3491555D01*
G01X3506555D02*
Y614212D01*
X3508421D01*
X3509168Y613837D01*
X3509728Y613337D01*
X3510195Y612587D01*
X3510568Y611712D01*
X3510661Y610462D01*
X3510568Y609212D01*
X3510195Y608337D01*
X3509728Y607587D01*
X3509168Y607087D01*
X3508421Y606712D01*
X3506555D01*
G01X3514241D02*
Y614212D01*
X3516575D01*
X3517321Y613837D01*
X3517788Y613337D01*
X3517975Y612337D01*
X3517788Y611337D01*
X3517228Y610712D01*
X3516575Y610337D01*
X3514241D01*
G01X3516575D02*
X3517975Y606712D01*
G01X3522488Y614212D02*
X3524728D01*
G01X3523608D02*
Y606712D01*
G01X3522488D02*
X3524728D01*
G01X3529241Y614212D02*
Y606712D01*
X3532975D01*
G01X3536741Y614212D02*
Y606712D01*
X3540475D01*
G01X3551648Y607712D02*
X3552395Y607087D01*
X3553235Y606712D01*
X3553981D01*
X3554728Y607087D01*
X3555288Y607712D01*
X3555568Y608587D01*
X3555381Y609462D01*
X3554915Y610212D01*
X3554075Y610712D01*
X3552955Y610962D01*
X3552301Y611462D01*
X3552021Y612337D01*
X3552208Y613212D01*
X3552675Y613837D01*
X3553328Y614212D01*
X3553981D01*
X3554635Y613962D01*
X3555195Y613337D01*
G01X3559988Y614212D02*
X3562228D01*
G01X3561108D02*
Y606712D01*
G01X3559988D02*
X3562228D01*
G01X3566835Y614212D02*
X3570381D01*
X3566835Y606712D01*
X3570381D01*
G01X3577975D02*
X3574241D01*
Y614212D01*
X3577975D01*
G01X3576481Y610587D02*
X3574241D01*
G01X3589335Y606712D02*
Y614212D01*
X3592881D01*
G01X3591575Y610587D02*
X3589335D01*
G01X3598608Y606712D02*
X3597861Y606837D01*
X3597208Y607337D01*
X3596648Y608087D01*
X3596275Y608962D01*
X3596088Y609962D01*
Y610962D01*
X3596275Y611962D01*
X3596648Y612837D01*
X3597208Y613587D01*
X3597861Y614087D01*
X3598608Y614212D01*
X3599355Y614087D01*
X3600008Y613587D01*
X3600568Y612837D01*
X3600941Y611962D01*
X3601128Y610962D01*
Y609962D01*
X3600941Y608962D01*
X3600568Y608087D01*
X3600008Y607337D01*
X3599355Y606837D01*
X3598608Y606712D01*
G01X3604241D02*
Y614212D01*
X3606575D01*
X3607321Y613837D01*
X3607788Y613337D01*
X3607975Y612337D01*
X3607788Y611337D01*
X3607228Y610712D01*
X3606575Y610337D01*
X3604241D01*
G01X3606575D02*
X3607975Y606712D01*
G01X3621108Y614212D02*
X3620361Y613962D01*
X3619801Y613337D01*
X3619428Y612587D01*
X3619148Y611587D01*
X3619055Y610462D01*
X3619148Y609337D01*
X3619428Y608337D01*
X3619801Y607587D01*
X3620361Y606962D01*
X3621108Y606712D01*
X3621855Y606962D01*
X3622415Y607587D01*
X3622788Y608337D01*
X3623068Y609337D01*
X3623161Y610462D01*
X3623068Y611587D01*
X3622788Y612587D01*
X3622415Y613337D01*
X3621855Y613962D01*
X3621108Y614212D01*
G01X3628608Y606462D02*
X3628421Y606587D01*
Y606837D01*
X3628608Y606962D01*
X3628795Y606837D01*
Y606587D01*
X3628608Y606462D01*
G01X3635921Y606712D02*
X3636108Y608337D01*
X3636388Y609712D01*
X3636761Y610962D01*
X3637228Y612337D01*
X3637975Y614212D01*
X3634241D01*
G01X3641835Y612962D02*
X3642395Y613712D01*
X3643048Y614087D01*
X3643795Y614212D01*
X3644728Y613962D01*
X3645381Y613337D01*
X3645568Y612587D01*
X3645475Y611837D01*
X3645101Y611212D01*
X3643235Y609962D01*
X3642395Y609087D01*
X3641835Y607837D01*
X3641648Y606712D01*
X3645568D01*
G01X3649055Y607837D02*
X3649615Y607212D01*
X3650268Y606837D01*
X3651108Y606712D01*
X3651948Y606962D01*
X3652601Y607462D01*
X3653068Y608337D01*
X3653161Y609337D01*
X3652975Y610337D01*
X3652508Y610962D01*
X3651855Y611462D01*
X3651201Y611587D01*
X3650548Y611462D01*
X3649708Y610962D01*
X3649988Y614212D01*
X3652508D01*
G01X3656181Y606712D02*
Y614212D01*
X3658608Y607962D01*
X3661035Y614212D01*
Y606712D01*
G01X3663681D02*
Y614212D01*
X3666108Y607962D01*
X3668535Y614212D01*
Y606712D01*
G01X3679335D02*
Y614212D01*
X3682881D01*
G01X3681575Y610587D02*
X3679335D01*
G01X3687488Y614212D02*
X3689728D01*
G01X3688608D02*
Y606712D01*
G01X3687488D02*
X3689728D01*
G01X3693961D02*
Y614212D01*
X3698255Y606712D01*
Y614212D01*
G01X3702488D02*
X3704728D01*
G01X3703608D02*
Y606712D01*
G01X3702488D02*
X3704728D01*
G01X3709148Y607712D02*
X3709895Y607087D01*
X3710735Y606712D01*
X3711481D01*
X3712228Y607087D01*
X3712788Y607712D01*
X3713068Y608587D01*
X3712881Y609462D01*
X3712415Y610212D01*
X3711575Y610712D01*
X3710455Y610962D01*
X3709801Y611462D01*
X3709521Y612337D01*
X3709708Y613212D01*
X3710175Y613837D01*
X3710828Y614212D01*
X3711481D01*
X3712135Y613962D01*
X3712695Y613337D01*
G01X3716648Y606712D02*
Y614212D01*
G01X3720568D02*
Y606712D01*
G01Y610462D02*
X3716648D01*
G01X3727975Y606712D02*
X3724241D01*
Y614212D01*
X3727975D01*
G01X3726481Y610587D02*
X3724241D01*
G01X3731555Y606712D02*
Y614212D01*
X3733421D01*
X3734168Y613837D01*
X3734728Y613337D01*
X3735195Y612587D01*
X3735568Y611712D01*
X3735661Y610462D01*
X3735568Y609212D01*
X3735195Y608337D01*
X3734728Y607587D01*
X3734168Y607087D01*
X3733421Y606712D01*
X3731555D01*
G01X3746741D02*
Y614212D01*
X3748981D01*
X3749728Y613837D01*
X3750288Y612962D01*
X3750475Y611962D01*
X3750288Y610962D01*
X3749821Y610212D01*
X3748981Y609837D01*
X3746741D01*
G01X3756108Y614212D02*
Y606712D01*
G01X3753961Y614212D02*
X3758255D01*
G01X3761648Y606712D02*
Y614212D01*
G01X3765568D02*
Y606712D01*
G01Y610462D02*
X3761648D01*
G01X3777488Y614212D02*
X3779728D01*
G01X3778608D02*
Y606712D01*
G01X3777488D02*
X3779728D01*
G01X3784148Y607712D02*
X3784895Y607087D01*
X3785735Y606712D01*
X3786481D01*
X3787228Y607087D01*
X3787788Y607712D01*
X3788068Y608587D01*
X3787881Y609462D01*
X3787415Y610212D01*
X3786575Y610712D01*
X3785455Y610962D01*
X3784801Y611462D01*
X3784521Y612337D01*
X3784708Y613212D01*
X3785175Y613837D01*
X3785828Y614212D01*
X3786481D01*
X3787135Y613962D01*
X3787695Y613337D01*
G01X3801108Y614212D02*
X3800361Y613962D01*
X3799801Y613337D01*
X3799428Y612587D01*
X3799148Y611587D01*
X3799055Y610462D01*
X3799148Y609337D01*
X3799428Y608337D01*
X3799801Y607587D01*
X3800361Y606962D01*
X3801108Y606712D01*
X3801855Y606962D01*
X3802415Y607587D01*
X3802788Y608337D01*
X3803068Y609337D01*
X3803161Y610462D01*
X3803068Y611587D01*
X3802788Y612587D01*
X3802415Y613337D01*
X3801855Y613962D01*
X3801108Y614212D01*
G01X3808608Y606462D02*
X3808421Y606587D01*
Y606837D01*
X3808608Y606962D01*
X3808795Y606837D01*
Y606587D01*
X3808608Y606462D01*
G01X3816108Y606712D02*
X3816761Y606837D01*
X3817508Y607212D01*
X3817975Y607837D01*
X3818161Y608712D01*
X3817975Y609587D01*
X3817415Y610337D01*
X3816575Y610712D01*
X3815641D01*
X3815081Y610962D01*
X3814615Y611587D01*
X3814428Y612462D01*
X3814708Y613337D01*
X3815361Y613962D01*
X3816108Y614212D01*
X3816855Y613962D01*
X3817508Y613337D01*
X3817788Y612462D01*
X3817601Y611587D01*
X3817135Y610962D01*
X3816575Y610712D01*
X3815641D01*
X3814801Y610337D01*
X3814241Y609587D01*
X3814055Y608712D01*
X3814241Y607837D01*
X3814708Y607212D01*
X3815455Y606837D01*
X3816108Y606712D01*
G01X3823608D02*
Y614212D01*
X3822488Y612712D01*
G01Y606712D02*
X3824728D01*
G01X3829895Y609212D02*
X3832321D01*
G01X3838608Y614212D02*
X3837861Y613962D01*
X3837301Y613337D01*
X3836928Y612587D01*
X3836648Y611587D01*
X3836555Y610462D01*
X3836648Y609337D01*
X3836928Y608337D01*
X3837301Y607587D01*
X3837861Y606962D01*
X3838608Y606712D01*
X3839355Y606962D01*
X3839915Y607587D01*
X3840288Y608337D01*
X3840568Y609337D01*
X3840661Y610462D01*
X3840568Y611587D01*
X3840288Y612587D01*
X3839915Y613337D01*
X3839355Y613962D01*
X3838608Y614212D01*
G01X3846108Y606462D02*
X3845921Y606587D01*
Y606837D01*
X3846108Y606962D01*
X3846295Y606837D01*
Y606587D01*
X3846108Y606462D01*
G01X3853608Y606712D02*
X3854261Y606837D01*
X3855008Y607212D01*
X3855475Y607837D01*
X3855661Y608712D01*
X3855475Y609587D01*
X3854915Y610337D01*
X3854075Y610712D01*
X3853141D01*
X3852581Y610962D01*
X3852115Y611587D01*
X3851928Y612462D01*
X3852208Y613337D01*
X3852861Y613962D01*
X3853608Y614212D01*
X3854355Y613962D01*
X3855008Y613337D01*
X3855288Y612462D01*
X3855101Y611587D01*
X3854635Y610962D01*
X3854075Y610712D01*
X3853141D01*
X3852301Y610337D01*
X3851741Y609587D01*
X3851555Y608712D01*
X3851741Y607837D01*
X3852208Y607212D01*
X3852955Y606837D01*
X3853608Y606712D01*
G01X3859335Y609837D02*
X3859988Y610712D01*
X3860548Y611212D01*
X3861295Y611462D01*
X3861948Y611212D01*
X3862415Y610712D01*
X3862788Y609962D01*
X3862881Y609087D01*
X3862788Y608337D01*
X3862415Y607587D01*
X3861855Y606962D01*
X3861201Y606712D01*
X3860455Y606962D01*
X3859801Y607712D01*
X3859428Y608837D01*
X3859335Y610087D01*
X3859521Y611712D01*
X3859801Y612587D01*
X3860268Y613462D01*
X3860921Y614087D01*
X3861575Y614212D01*
X3862228Y613962D01*
X3862695Y613337D01*
G01X3866181Y606712D02*
Y614212D01*
X3868608Y607962D01*
X3871035Y614212D01*
Y606712D01*
G01X3873681D02*
Y614212D01*
X3876108Y607962D01*
X3878535Y614212D01*
Y606712D01*
G01X3883141Y604212D02*
X3882208Y605462D01*
X3881741Y606712D01*
Y611712D01*
X3882208Y612962D01*
X3883141Y614212D01*
G01X3891108D02*
X3890361Y613962D01*
X3889801Y613337D01*
X3889428Y612587D01*
X3889148Y611587D01*
X3889055Y610462D01*
X3889148Y609337D01*
X3889428Y608337D01*
X3889801Y607587D01*
X3890361Y606962D01*
X3891108Y606712D01*
X3891855Y606962D01*
X3892415Y607587D01*
X3892788Y608337D01*
X3893068Y609337D01*
X3893161Y610462D01*
X3893068Y611587D01*
X3892788Y612587D01*
X3892415Y613337D01*
X3891855Y613962D01*
X3891108Y614212D01*
G01X3898608Y606462D02*
X3898421Y606587D01*
Y606837D01*
X3898608Y606962D01*
X3898795Y606837D01*
Y606587D01*
X3898608Y606462D01*
G01X3906108Y606712D02*
X3906761Y606837D01*
X3907508Y607212D01*
X3907975Y607837D01*
X3908161Y608712D01*
X3907975Y609587D01*
X3907415Y610337D01*
X3906575Y610712D01*
X3905641D01*
X3905081Y610962D01*
X3904615Y611587D01*
X3904428Y612462D01*
X3904708Y613337D01*
X3905361Y613962D01*
X3906108Y614212D01*
X3906855Y613962D01*
X3907508Y613337D01*
X3907788Y612462D01*
X3907601Y611587D01*
X3907135Y610962D01*
X3906575Y610712D01*
X3905641D01*
X3904801Y610337D01*
X3904241Y609587D01*
X3904055Y608712D01*
X3904241Y607837D01*
X3904708Y607212D01*
X3905455Y606837D01*
X3906108Y606712D01*
G01X3911555Y607837D02*
X3912115Y607212D01*
X3912768Y606837D01*
X3913608Y606712D01*
X3914448Y606962D01*
X3915101Y607462D01*
X3915568Y608337D01*
X3915661Y609337D01*
X3915475Y610337D01*
X3915008Y610962D01*
X3914355Y611462D01*
X3913701Y611587D01*
X3913048Y611462D01*
X3912208Y610962D01*
X3912488Y614212D01*
X3915008D01*
G01X3918681Y606712D02*
Y614212D01*
X3921108Y607962D01*
X3923535Y614212D01*
Y606712D01*
G01X3926181D02*
Y614212D01*
X3928608Y607962D01*
X3931035Y614212D01*
Y606712D01*
G01X3941555D02*
Y614212D01*
X3943421D01*
X3944168Y613837D01*
X3944728Y613337D01*
X3945195Y612587D01*
X3945568Y611712D01*
X3945661Y610462D01*
X3945568Y609212D01*
X3945195Y608337D01*
X3944728Y607587D01*
X3944168Y607087D01*
X3943421Y606712D01*
X3941555D01*
G01X3949241D02*
Y614212D01*
X3951575D01*
X3952321Y613837D01*
X3952788Y613337D01*
X3952975Y612337D01*
X3952788Y611337D01*
X3952228Y610712D01*
X3951575Y610337D01*
X3949241D01*
G01X3951575D02*
X3952975Y606712D01*
G01X3957488Y614212D02*
X3959728D01*
G01X3958608D02*
Y606712D01*
G01X3957488D02*
X3959728D01*
G01X3964241Y614212D02*
Y606712D01*
X3967975D01*
G01X3971741Y614212D02*
Y606712D01*
X3975475D01*
G01X3981575Y604212D02*
X3982508Y605462D01*
X3982975Y606712D01*
Y611712D01*
X3982508Y612962D01*
X3981575Y614212D01*
G54D14*
X47244Y17716D03*
Y330708D03*
X279528Y53148D03*
X314961Y561023D03*
X393702Y344488D03*
X748032Y64961D03*
Y344488D03*
X984252Y64961D03*
Y344488D03*
X1338584D03*
X1417324Y561023D03*
X1452756Y53149D03*
X1685040Y17716D03*
Y330708D03*
X1799212Y96457D03*
Y478346D03*
X2463384Y375862D03*
G54D23*
X287402Y628465D03*
X263780Y659961D03*
X1468504Y628465D03*
X1444882Y659961D03*
X2463384Y186862D03*
G54D24*
X668314Y570042D03*
X681498Y575042D03*
Y565042D03*
X668420Y598187D03*
X681604Y593187D03*
Y603187D03*
X1011017Y570042D03*
X997833Y575042D03*
Y565042D03*
X1011017Y598187D03*
X997833Y593187D03*
Y603187D03*
X2463384Y413662D03*
G54D15*
X45275Y236614D03*
Y411594D03*
X72835Y236614D03*
X68898Y226771D03*
X59055Y222834D03*
X49212Y226771D03*
X68898Y246457D03*
X49212D03*
X59055Y250394D03*
X68898Y421437D03*
X72835Y411594D03*
X68898Y401751D03*
X59055Y397814D03*
X49212Y401751D03*
Y421437D03*
X59055Y425374D03*
X1673228Y222834D03*
X1663385Y226771D03*
X1659448Y236614D03*
X1663385Y246457D03*
X1673228Y250394D03*
Y397834D03*
X1663385Y401771D03*
X1659448Y411614D03*
X1663385Y421457D03*
X1673228Y425394D03*
X1687008Y236614D03*
X1683071Y226771D03*
Y246457D03*
Y421457D03*
X1687008Y411614D03*
X1683071Y401771D03*
X2463384Y640462D03*
G54D25*
X822087Y88484D03*
Y313484D03*
X940197Y88484D03*
Y313484D03*
X2463384Y35662D03*
G54D16*
X59055Y236614D03*
Y411594D03*
X1673228Y236614D03*
Y411614D03*
X2463384Y-2138D03*
G54D26*
X822087Y88484D03*
Y313484D03*
X940197Y88484D03*
Y313484D03*
X2463384Y338062D03*
G54D17*
X137355Y120500D03*
X134600Y150000D03*
Y134000D03*
X156785Y101285D03*
X205061Y67500D03*
X211425Y106075D03*
X205061Y93000D03*
X200600Y109059D03*
X210925Y115575D03*
X317000Y58000D03*
X321500Y66500D03*
X325100Y64000D03*
X332500Y63300D03*
X396216Y46875D03*
X441938Y132100D03*
Y309700D03*
X458946Y341216D03*
X455946Y357216D03*
X465946Y357016D03*
X471946Y341216D03*
X484446D03*
X517409Y322000D03*
X506309Y329000D03*
Y322000D03*
X517410Y329000D03*
X551430Y132400D03*
X561155Y160784D03*
X580184Y117800D03*
X586184Y111800D03*
X580184Y105800D03*
X562830Y140300D03*
X574230Y132400D03*
X564305Y160784D03*
X563007Y251677D03*
X562830Y266500D03*
X590298Y282890D03*
X571325Y292757D03*
X590298Y276984D03*
X571542Y289065D03*
X612684Y297000D03*
X606084Y293100D03*
X616684Y307975D03*
X622184Y308000D03*
X608259Y305000D03*
X639010Y236377D03*
X645900Y242200D03*
X649200Y254500D03*
X637684Y280575D03*
X625684Y273499D03*
X630308Y284500D03*
X657784Y40500D03*
Y96000D03*
X676638Y230894D03*
X681684Y230820D03*
X674800Y269600D03*
X679184Y273190D03*
X675100Y304500D03*
X702223Y197419D03*
X689684Y230762D03*
X685884Y297000D03*
X736554Y131056D03*
X742554Y128056D03*
X726100Y185000D03*
X720100D03*
X717384Y273400D03*
X725000Y292500D03*
X770700Y206900D03*
X758600Y185000D03*
X776000Y206600D03*
X885100Y361500D03*
X954200Y200200D03*
X954600Y207200D03*
X980500Y185000D03*
X974500D03*
X978600Y310955D03*
X996954Y128056D03*
X1013000Y185000D03*
X1027675Y215000D03*
X1034360Y254000D03*
X1044900Y278600D03*
X1021414Y355979D03*
X1017300Y385600D03*
X1074500Y43500D03*
Y99000D03*
X1074430Y256461D03*
X1083100Y278810D03*
X1131976Y267500D03*
X1112000Y296000D03*
X1123100Y322500D03*
X1123400Y356300D03*
X1145600Y257500D03*
X1156200Y258900D03*
X1145600Y244025D03*
X1140100Y244000D03*
X1163266Y255311D03*
X1166000Y352500D03*
X1182100Y105800D03*
X1187700Y132400D03*
X1197425Y160284D03*
X1171600Y238000D03*
X1171986Y269110D03*
X1196500Y293284D03*
X1171986Y275016D03*
X1176000Y350000D03*
X1179500Y355000D03*
X1210500Y132400D03*
X1199100Y133300D03*
X1200575Y160284D03*
X1210500Y265600D03*
X1201500Y293284D03*
X1199100Y273500D03*
X1225930Y359148D03*
X1244874Y330000D03*
X1255975D03*
X1242930Y359148D03*
X1255975Y337000D03*
X1260340Y359284D03*
X1286113Y378312D03*
X1320346Y112300D03*
Y289900D03*
X1406230Y21076D03*
Y15076D03*
X1400230Y21076D03*
Y15076D03*
X1412230Y21076D03*
X1498180Y63500D03*
X1490000Y80500D03*
X1499228Y74500D03*
X1490228Y66500D03*
X1505100Y64500D03*
X1551000Y96500D03*
X1567500Y67000D03*
X1618800Y76700D03*
X1597100Y145000D03*
Y126000D03*
X1625370Y103940D03*
X1632336Y109117D03*
X1631323Y115140D03*
X1641932Y122969D03*
X1635000Y152925D03*
X1650117Y180000D03*
X1636600Y173500D03*
X1622100Y155931D03*
X1657050Y116760D03*
X1669800Y120400D03*
X1675800D03*
X1656657Y127365D03*
X1651325Y125076D03*
X1676350Y160251D03*
X1672050Y181550D03*
X1668075Y189500D03*
X1679176Y194760D03*
X1657500Y191500D03*
X1664000Y202500D03*
X1667600Y198500D03*
X1654000Y192500D03*
X1660000Y193500D03*
X1706100Y92000D03*
X1701350Y114250D03*
X1696600Y119000D03*
X1685100Y127500D03*
X1702525Y129500D03*
X1692600Y135975D03*
X1688100Y145560D03*
X1685000Y133000D03*
X1685976Y153500D03*
X1688100Y173060D03*
Y162060D03*
X1709600Y158000D03*
X1701100Y182000D03*
X1688100Y184220D03*
X1702075Y205500D03*
X1719075Y107016D03*
X1721685Y95940D03*
X1727200Y104500D03*
X1721000Y142525D03*
X1714100Y144925D03*
X1729411Y143661D03*
X1727100Y164280D03*
X1715525Y168500D03*
X1722063Y156962D03*
X1726099Y153000D03*
X1720100Y179500D03*
X1729411Y159161D03*
X1733500Y173760D03*
X1738740Y191500D03*
X1759600Y114500D03*
X1767425Y107000D03*
X1761600Y124524D03*
X1764000Y142525D03*
X1770575Y137000D03*
X1763075Y178900D03*
X1767075Y155484D03*
X1769476Y168500D03*
X1747925Y204000D03*
X1762454Y320347D03*
X1769300Y329400D03*
X1747235Y355989D03*
X1769300Y340600D03*
X1769692Y334649D03*
X1767700Y346200D03*
X1747235Y363689D03*
Y371389D03*
X1773000Y142525D03*
X1773500Y129500D03*
X1773000Y158000D03*
X1772600Y177300D03*
X1795600Y308000D03*
X1817500Y188000D03*
X1809600Y195000D03*
X1811500Y186000D03*
X1847164Y419238D03*
X1842164Y432338D03*
X1847164Y430568D03*
X1852164Y435538D03*
X1837164Y428238D03*
X2463384Y716062D03*
G54D27*
X825900Y362200D03*
Y382200D03*
Y372200D03*
X866400Y362200D03*
Y372200D03*
Y382200D03*
X906900Y362200D03*
Y382200D03*
Y372200D03*
X2463384Y489262D03*
G54D18*
X137303Y601693D03*
Y609567D03*
Y617441D03*
Y625315D03*
Y633189D03*
Y641063D03*
Y648937D03*
Y656811D03*
Y664685D03*
X163878Y601693D03*
X156004D03*
X145177D03*
X163878Y609567D03*
Y617441D03*
Y625315D03*
Y633189D03*
X156004Y609567D03*
Y617441D03*
Y625315D03*
Y633189D03*
X145177Y609567D03*
Y617441D03*
Y625315D03*
Y633189D03*
X163878Y641063D03*
Y648937D03*
Y656811D03*
X156004Y641063D03*
Y648937D03*
Y656811D03*
X145177Y641063D03*
Y648937D03*
Y656811D03*
X163878Y664685D03*
X156004D03*
X145177D03*
X192126Y633189D03*
Y625315D03*
Y617441D03*
Y656811D03*
Y648937D03*
Y664685D03*
X200000Y633189D03*
Y625315D03*
Y617441D03*
X215748Y633189D03*
Y625315D03*
Y617441D03*
X223622Y633189D03*
Y625315D03*
Y617441D03*
X215748Y656811D03*
Y648937D03*
X223622Y656811D03*
Y648937D03*
X200000Y656811D03*
Y648937D03*
X215748Y664685D03*
X223622D03*
X200000D03*
X250866Y20827D03*
Y10197D03*
X255906Y617441D03*
X248032D03*
X255906Y625315D03*
Y633189D03*
X248032D03*
Y625315D03*
X255906Y648937D03*
X248032D03*
X255906Y656811D03*
X248032D03*
X255906Y664685D03*
X248032D03*
X279646Y23012D03*
Y13012D03*
X284646Y18012D03*
X274646D03*
X284646Y8012D03*
X274646D03*
X260866Y20827D03*
Y10197D03*
X279528Y617441D03*
X271654D03*
X279528Y625315D03*
Y633189D03*
X271654D03*
Y625315D03*
X279528Y648937D03*
X271654D03*
X279528Y656811D03*
X271654D03*
X279528Y664685D03*
X271654D03*
X289646Y23012D03*
Y13012D03*
X295276Y617441D03*
Y625315D03*
Y633189D03*
X303150D03*
Y625315D03*
Y617441D03*
Y648937D03*
X295276D03*
X303150Y656811D03*
X295276D03*
X303150Y664685D03*
X295276D03*
X802087Y145984D03*
X792087D03*
X802087Y135984D03*
X792087D03*
X802087Y180984D03*
X792087D03*
X802087Y170984D03*
X792087D03*
X802087Y200984D03*
X792087D03*
X802087Y230984D03*
X792087D03*
X802087Y220984D03*
X792087D03*
X802087Y265984D03*
X792087D03*
X802087Y255984D03*
X792087D03*
X822087Y145984D03*
X812087D03*
X822087Y135984D03*
X812087D03*
X822087Y180984D03*
X812087D03*
X822087Y170984D03*
X812087D03*
X822087Y200984D03*
X812087D03*
X822087Y230984D03*
X812087D03*
X822087Y220984D03*
X812087D03*
X822087Y265984D03*
X812087D03*
X822087Y255984D03*
X812087D03*
X920197Y145984D03*
X910197D03*
X920197Y135984D03*
X910197D03*
X920197Y180984D03*
X910197D03*
X920197Y170984D03*
X910197D03*
X920197Y200984D03*
X910197D03*
X920197Y230984D03*
X910197D03*
X920197Y220984D03*
X910197D03*
X920197Y265984D03*
X910197D03*
X920197Y255984D03*
X910197D03*
X940197Y145984D03*
X930197D03*
X940197Y135984D03*
X930197D03*
X940197Y180984D03*
X930197D03*
X940197Y170984D03*
X930197D03*
X940197Y200984D03*
X930197D03*
X940197Y230984D03*
X930197D03*
X940197Y220984D03*
X930197D03*
X940197Y265984D03*
X930197D03*
X940197Y255984D03*
X930197D03*
X1437008Y617441D03*
X1429134D03*
X1437008Y625315D03*
Y633189D03*
X1429134D03*
Y625315D03*
X1437008Y648937D03*
X1429134D03*
X1437008Y656811D03*
X1429134D03*
X1437008Y664685D03*
X1429134D03*
X1465197Y18012D03*
Y8012D03*
X1451417Y20827D03*
X1441417D03*
X1451417Y10197D03*
X1441417D03*
X1460630Y617441D03*
X1452756D03*
X1460630Y625315D03*
Y633189D03*
X1452756D03*
Y625315D03*
X1460630Y648937D03*
X1452756D03*
X1460630Y656811D03*
X1452756D03*
X1460630Y664685D03*
X1452756D03*
X1480197Y23012D03*
X1470197D03*
X1480197Y13012D03*
X1470197D03*
X1475197Y18012D03*
Y8012D03*
X1476378Y617441D03*
Y625315D03*
Y633189D03*
X1484252D03*
Y625315D03*
Y617441D03*
Y648937D03*
X1476378D03*
X1484252Y656811D03*
X1476378D03*
X1484252Y664685D03*
X1476378D03*
X1508661Y633189D03*
Y625315D03*
Y617441D03*
X1516535Y633189D03*
Y625315D03*
Y617441D03*
X1508661Y656811D03*
Y648937D03*
X1516535Y656811D03*
Y648937D03*
X1508661Y664685D03*
X1516535D03*
X1532283Y633189D03*
Y625315D03*
Y617441D03*
X1540157Y633189D03*
Y625315D03*
Y617441D03*
X1532283Y656811D03*
Y648937D03*
X1540157Y656811D03*
Y648937D03*
X1532283Y664685D03*
X1540157D03*
X1587107Y601693D03*
X1576280D03*
X1568406D03*
X1587107Y609567D03*
Y617441D03*
Y625315D03*
Y633189D03*
X1576280Y609567D03*
Y617441D03*
Y625315D03*
Y633189D03*
X1568406Y609567D03*
Y617441D03*
Y625315D03*
Y633189D03*
X1587107Y641063D03*
Y648937D03*
Y656811D03*
X1576280Y641063D03*
Y648937D03*
Y656811D03*
X1568406Y641063D03*
Y648937D03*
Y656811D03*
X1587107Y664685D03*
X1576280D03*
X1568406D03*
X1594981Y601693D03*
Y609567D03*
Y617441D03*
Y625315D03*
Y633189D03*
Y641063D03*
Y648937D03*
Y656811D03*
Y664685D03*
X2463384Y564862D03*
Y602662D03*
G54D19*
X166785Y200472D03*
Y230000D03*
Y280472D03*
Y310000D03*
Y360472D03*
Y390000D03*
Y440472D03*
Y470000D03*
Y520472D03*
Y550000D03*
X243785Y200472D03*
Y230000D03*
Y280472D03*
Y310000D03*
Y360472D03*
Y390000D03*
Y440472D03*
Y470000D03*
Y520472D03*
Y550000D03*
X1488500Y200472D03*
Y230000D03*
Y280472D03*
Y310000D03*
Y360472D03*
Y390000D03*
Y440472D03*
Y470000D03*
Y520472D03*
Y550000D03*
X1565500Y200472D03*
Y230000D03*
Y280472D03*
Y310000D03*
Y360472D03*
Y390000D03*
Y440472D03*
Y470000D03*
Y520472D03*
Y550000D03*
X2463384Y451462D03*
G54D28*
X1848583Y99212D03*
X1848582Y481693D03*
X2463384Y300262D03*
G54D29*
X1835739Y99212D03*
X1835738Y481693D03*
X2463384Y-39938D03*
M02*
